GRAND TETONMBThu Aug 24 16:11:55 2023N/AN/AN/AN/AV051 OF 312COVER PAGE
SHEETDATE
DEPARTMENT
SIZE
PROJECT DOCUMENT NUMBER REV
REVIEWER
DESIGNER
123
7 3 2 1 6 5 4
E
A
B
C
E
D
C
B
A
7 6 5 4
D
C



SPR CPU0 & 1 - PVNN_TERM & MISCSPR CPU0 - PCIE PE4 (19 OF 30)SPR CPU0 - PCIE PE0/PE1 (17 OF 30)SPR CPU0 - DDR CH E (12 OF 30)
2 OF 312V05N/A N/AThu Aug 24 16:11:55 2023
COVER PAGETABLE OF CONTENT 1/3TABLE OF CONTENT 2/3TABLE OF CONTENT 3/3BLOCK DIAGRAM - MBBLOCK DIAGRAM - SPIBLOCK DIAGRAM - VRBLCOK DIAGRAM - CLOCKBLOCK DIAGRAM - SMBUSBLOCK DIAGRAM - I3CBLOCK DIAGRAM - JTAGBLOCK DIAGRAM - POWER SEQUENCESPR CPU0 MISC:CLK/JTAG/STRAPS(1/30)SPR CPU0 MISC:SMBUS/SVID/ERRORS(2/30)SPR CPU0 MISC:(3 OF 30)SPR CPU0 MISC:DDRVIEW & VSENSE(4/30)SPR CPU0 MISC:VIEW MDFI/HBM(5 OF 30)SPR CPU0 MISC:SPARE(6 OF 30)SPR CPU0 MISC:7 OF 30)SPR CPU0 - DDR CH A (8 OF 30)SPR CPU0 - DDR CH B (9 OF 30)SPR CPU0 - DDR CH C (10 OF 30)SPR CPU0 - DDR CH D (11 OF 30)SPR CPU0 - DDR CH F (13 OF 30)SPR CPU0 - DDR CH G (14 OF 30)SPR CPU0 - DDR CH H (15 OF 30)SPR CPU0 - DMI (16 OF 30)SPR CPU0 - PCIE PE2/PE3 (18 OF 30)SPR CPU0 - UPI0 (20 OF 30)SPR CPU0 - UPI1 (21 OF 30)SPR CPU0 - UPI2 (22 OF 30)SPR CPU0 - UPI3 (23 OF 30)SPR CPU0 POWER - VCCIN (24 OF 30)SPR CPU0 POWER - VCCIN/VCCINFAON (25)SPR CPU0 POWER - VCCFA EHV FIVRA (26)SPR CPU0 POWER - GND (27 OF 30)SPR CPU0 POWER - GND (28 OF 30)
SPR CPU0 POWER - GND (29 OF 30)SPR CPU0 POWER - GND (30 OF 30)SPR CPU0 IBL/S3M SERIAL RESISTORSSPR CPU1 MISC:CLK/JTAG/STRAPS(1/30)SPR CPU1 MISC:SMBUS/SVID/ERRORS(2/30)SPR CPU1 MISC:(3 OF 30)SPR CPU1 MISC:DDRVIEW & VSENSE(4/30)SPR CPU1 MISC:VIEW MDFI/HBM(5 OF 30)SPR CPU1 MISC:SPARE(6 OF 30)SPR CPU1 MISC:7 OF 30)SPR CPU1 - DDR CH A (8 OF 30)SPR CPU1 - DDR CH B (9 OF 30)SPR CPU1 - DDR CH C (10 OF 30)SPR CPU1 - DDR CH D (11 OF 30)SPR CPU1 - DDR CH E (12 OF 30)SPR CPU1 - DDR CH F (13 OF 30)SPR CPU1 - DDR CH G (14 OF 30)SPR CPU1 - DDR CH H (15 OF 30)SPR CPU1 - DMI (16 OF 30)SPR CPU1 - PCIE PE0/PE1 (17 OF 30)SPR CPU1 - PCIE PE2/PE3 (18 OF 30)SPR CPU1 - PCIE PE4 (19 OF 30)SPR CPU1 - UPI0 (20 OF 30)SPR CPU1 - UPI1 (21 OF 30)SPR CPU1 - UPI2 (22 OF 30)SPR CPU1 - UPI3 (23 OF 30)SPR CPU1 POWER - VCCIN (24 OF 30)SPR CPU1 POWER - VCCIN/VCCINFAON (25)SPR CPU1 POWER - VCCFA EHV FIVRA (26)SPR CPU1 POWER - GND (27 OF 30)SPR CPU1 POWER - GND (28 OF 30)SPR CPU1 POWER - GND (29 OF 30)SPR CPU1 POWER - GND (30 OF 30)SPR CPU0 TOP DECOUPLING CAPSSPR CPU0 BOTTOM DECOUPLING CAPSSPR CPU0 BOTTOM DECOUPLING CAPS CONTI.SPR CPU1 TOP DECOUPLING CAPSSPR CPU1 BOTTOM DECOUPLING CAPSSPR CPU1 BOTTOM DECOUPLING CAPS CONTI.
BLANKDDR5 - CPU0 CHA DIMM1(YELLOW)DDR5 - CPU0 CHA DIMM2(BLACK)DDR5 - CPU0 CHB DIMM1(YELLOW)DDR5 - CPU0 CHB DIMM2(BLACK)DDR5 - CPU0 CHC DIMM1(YELLOW)DDR5 - CPU0 CHC DIMM2(BLACK)DDR5 - CPU0 CHD DIMM1(YELLOW)DDR5 - CPU0 CHD DIMM2(BLACK)DDR5 - CPU0 CHE DIMM1(YELLOW)DDR5 - CPU0 CHE DIMM2(BLACK)DDR5 - CPU0 CHF DIMM1(YELLOW)DDR5 - CPU0 CHF DIMM2(BLACK)DDR5 - CPU0 CHG DIMM1(YELLOW)DDR5 - CPU0 CHG DIMM2(BLACK)DDR5 - CPU0 CHH DIMM1(YELLOW)DDR5 - CPU0 CHH DIMM2(BLACK)DDR5 - CPU1 CHA DIMM1(YELLOW)DDR5 - CPU1 CHA DIMM2(BLACK)DDR5 - CPU1 CHB DIMM1(YELLOW)DDR5 - CPU1 CHB DIMM2(BLACK)DDR5 - CPU1 CHC DIMM1(YELLOW)DDR5 - CPU1 CHC DIMM2(BLACK)DDR5 - CPU1 CHD DIMM1(YELLOW)DDR5 - CPU1 CHD DIMM2(BLACK)DDR5 - CPU1 CHE DIMM1(YELLOW)DDR5 - CPU1 CHE DIMM2(BLACK)DDR5 - CPU1 CHF DIMM1(YELLOW)DDR5 - CPU1 CHF DIMM2(BLACK)DDR5 - CPU1 CHG DIMM1(YELLOW)DDR5 - CPU1 CHG DIMM2(BLACK)DDR5 - CPU1 CHH DIMM1(YELLOW)DDR5 - CPU1 CHH DIMM2(BLACK)DDR5 - PWRGDDDR5 - PWRGDBLANKSPR CPU0 & 1 - SVID/MISC/UARTSPR CPU0 & 1 - CATERR/RMCASPR CPU0 & 1- HW STRAPSSPR CPU0 & 1 SIDE BAND-GPIO
12345678910111213141516171819202122232425262728293031323334353637383940
41424344454647484950515253545556575859606162636465666768697071727374757677787980
81828384858687888990919293949596979899100101102103104105106107108109110111112113114115116117118119120SEANTABLE OF CONTENT 1/3
1
DEPARTMENT REV
7 3 2 6 5 4
C
A
B
7
E
D
6 4 5 3 2 1
E
D
C
B
A
DATE
PROJECT
SHEET
DOCUMENT NUMBERDESIGNER
SIZE
REVIEWER
C
CONTENTSPAGE(S) PAGE(S) CONTENTS PAGE(S) CONTENTS



EMMITSBURG - GPIO/SPI (7/10)EMMITSBURG - POWER (8/10)EMMITSBURG - RSVD (9/10)EMMITSBURG - GND (10/10)EMMITSBURG - DECOUPLING CAPSSMBUS - I3C CPU1 SPDPCH - E1S - 0 CONNNM DEBUG HEADER -(ME CONNECTOR)191EXAMAX_ISO (6/7)EXAMAX_ISO (5/7)EXAMAX_ISO (4/7)EXAMAX_ISO (3/7)146SPR CPU0 & 1- PROCHOT/THERMTRIPSPR CPU0 & 1- MEMHOTSPR CPU0 & 1- MEMTRIP/NMISPR CPU0 & 1 - CPU0 PWRGDS/RESETSPR CPU0 & 1 - CPU1 PWRGDS/RESETSPR CPU0 & 1- MONF/FISTSPR CPU0 & 1 - PIROMSPR CPU0 & 1 - DDR RESET CPU TO PLDSPR CPU0 - DDR RESET PLD TO DIMMSPR CPU1 - DDR RESET PLD TO DIMMSPR & PCH - DEBUG PORT (1/3)SPR & PCH - DEBUG PORT (2/3)SPR & PCH - DEBUG PORT (3/3)SPR & PCH - JTAGBLANKPCIE - CPU0_EXAMAX_P2/P3_X16PCIE - CPU0_EXAMAX_P2/P3_X16PCIE - CPU0_EXAMAX_P0/P4_X16PCIE - CPU0_EXAMAX_P0/P4_X16PCIE - CPU1_EXAMAX_P2/P3_X16PCIE - CPU1_EXAMAX_P2/P3_X16PCIE - CPU1_EXAMAX_P0/P4_X16PCIE - CPU1_EXAMAX_P0/P4_X16EXAMAX_PRESENTEXAMAX_ISO (1/7)EXAMAX_ISO (2/7)EXAMAX_ISO (7/7)USB HUBPCIE - SFF OCP3.0_X16 (1/3)PCIE - SFF OCP3.0 (2/3)PCIE - SFF OCP3.0 (3/3)SFF_OCP3.0 HSC(1/3)SFF_OCP3.0 HSC CO-LAYOUT(2/3)SFF_OCP3.0 HSC(3/3)PCIE - V3_2 OCP3.0_X16(1/3)PCIE - V3_2 OCP3.0 (2/3)
PCIE - V3_2 OCP3.0 (3/3)V3_2_OCP3.0 HSC(1/3)V3_2_OCP3.0 HSC-CO-LAYOUT(2/3)V3_2_OCP3.0 HSC(3/3)OCP3.0 NCSIFPGA- PCIE - RE-DRIVER121122123124125126127128129130131132133134135136137138139140141142143144145147148149150151152153154155156157158159160
161162163164165166
Thu Aug 24 16:11:56 2023
FPGA- PCIE - RE-DRIVER(CO-LAYOUT)BLANKUSB3.0 REDRIVERTEMP SENSOR - LM75POWER MONITOR (1/2)POWER MONITOR (2/2)PCIE AC-COUPLE CAPS 1/5PCIE AC-COUPLE CAPS 2/5PCIE AC-COUPLE CAPS 3/5PCIE AC-COUPLE CAPS 4/5PCIE AC-COUPLE CAPS 5/5DMI AC-COUPLE CAPSEMMITSBURG - CLK (1/10)EMMITSBURG - USB (2/10)EMMITSBURG - DMI/SATA/PCIE (3/10)EMMITSBURG - GPIO/JTAG (4/10)EMMITSBURG - GPIO/SMB (5/10)EMMITSBURG - GPIO/JTAG (6/10)PCH - M.2 - 0 CONNE1S_HSCE1S_HSC_CO_LAYOUTPCH - SATA / RAID KEYBOARD IDSPCH - USB EXT HUBPCH - PECIPCH SIDEBAND: HW STRAPS (1/4)PCH SIDEBAND: HW STRAPS (2/4)PCH SIDEBAND: HW STRAPS (3/4)
PCH SIDEBAND: HW STRAPS (4/4)PCH SIDEBAND - ESPI/LPCPCH SIDEBAND - THERMTRIP & FIVRBREAKPCH TERMINATION(1/2)PCH TERMINATION(2/2)CLK- DB2000QL CLK BUFFER (1/2)CLK- DB2000QL CLK BUFFER (2/2)CLK- CK440Q CLK GENCLK- CK440Q CLK GEN (2/2)CLK- CK440 POWER FILTERCLK - 9ZXL045 CLK BUFFERCLK-GEN(NON SSC)MAIN FPGA / PFR (1/5)MAIN FPGA / PFR (2/5)MAIN FPGA / PFR (3/5)MAIN FPGA / PFR (4/5)MAIN FPGA / PFR (5/5)MAIN FPGA / PFR - LEDSMAIN FPGA / PFR - PU/PDMAIN FPGA / PFR - MISC/PU/PDMAIN FPGA / PFR - JTAGMAIN FPGA / PFR - SI (1/2)MAIN FPGA / PFR - SI (2/2)MAIN FPGA / PFR - ISOLATORGTL2014(1/2)GTL2014(2/2)BMC - PCA9539SMBUS - I3C CPU0 SPDSMBUS - PCIE0 SMBUSSMBUS - PCIE1 SMBUSSMBUS - PCIE2 SMBUSSMBUS - PCIE3 SMBUSSMBUS - CPU0 &1 PEHP SMBUSSMBUS - CPU0 &1 S3M SMBUSSMBUS - ISOLATEDSMBUS - ISOLATEDSCM REMOTE JTAG LOGICSCM CONN
167168169170171172173174175176177178179180181182183184185186187188189190192193194195196197198199200
201202203204205206207208209210211212213214215216217218219220221222223224225226227228229230231232233234235236237238239240N/AN/A V053 OF 312SEANTABLE OF CONTENT 2/3
1
DEPARTMENT REV
7 3 2 6 5 4
C
A
B
7
E
D
6 4 5 3 2 1
E
D
C
B
A
DATE
PROJECT
SHEET
DOCUMENT NUMBERDESIGNER
SIZE
REVIEWER
C
CONTENTSPAGE(S) PAGE(S) CONTENTS PAGE(S) CONTENTS



BLANKVCCD_HV_CPU0 VR PHASE (2/2)VCCD_HV CPU0 VR CONTROLLER (1/2)277276VCCFA_EHV CPU0 VR PHASE (3/3)VCCINFAON CPU0 VR PHASE 1&2 (2/3)VCCINFAON/VCCFA_EHV CPU0 VR(1/3)VCCFA_EHV_FIVRA CPU0 VR PHASE 3&4(7/7)VCCFA_EHV_FIVRA CPU0 VR PHASE 1&2(6/7)VCCIN CPU0 VR PHASE 7&8 (5/7)269268261BLANKNCP3284/P3V3_AUXMPQ8633A/P5V_AUX258HSC MODULE(2/4)HSC MODULE(3/4)HSC MODULE(4/4)DELTA LTDRMOUNTING HOLE311VCCIN CPU0 VR PHASE 5&6 (4/7)VCCIN CPU0 VR PHASE 3&4 (3/7)VCCIN CPU0 VR PHASE 1&2 (2/7)266SCM SMBUS BUSP12V_SCMMB FRUPWRGD_DSW_PWROKPOWER CONNECTOR/ISOLATEDPOWER CONNECTOR/ISOLATEDPSU POWER CONNECTORSSCM REMOTE JTAG LOGICBLANKVOLTAGE SENSOR (1/2)VOLTAGE SENSOR (2/2)POWER GOOD LED'S 1/5POWER GOOD LED'S 2/5POWER GOOD LED'S 3/5POWER GOOD LED'S 4/5POWER GOOD LED'S 5/5PGPPA_AUXP5V & P3V3 SWITCHMPQ8633B/P1V05_PCH_AUX VRNB695/P1V8_PCH_AUXBLANKBLANKVCCIN/VCCFA_EHV_FIVRA CPU0 VR(1/7)BLANKBLANK
PVPP_HBM_CPU0PVNN_MAIN_CPU0BLANKVCCIN/VCCFA_EHV_FIVRA CPU1 VR(1/7)VCCIN CPU1 VR PHASE 1&2 (2/7)VCCIN CPU1 VR PHASE 3&4 (3/7)241242243244245246247248249250251252253254255256257259260262263264265267270271272273274275278279280
281282283284285286
Thu Aug 24 16:11:57 2023
VCCIN CPU1 VR PHASE 5&6 (4/7)VCCIN CPU1 VR PHASE 7&8 (5/7)VCCFA_EHV_FIVRA CPU1 VR PHASE 1&2(6/7)VCCFA_EHV_FIVRA CPU1 VR PHASE 3&4(7/7)BLANKVCCINFAON/VCCFA_EHV CPU1 VR CONTROLLER (1/3)VCCINFAON CPU1 VR PHASE 1&2 (2/3)VCCFA_EHV_CPU1 VR PHASE (3/3)BLANKVCCD_HV CPU1 VR CONTROLLER (1/2)VCCD_HV_CPU1 VR PHASE (2/2)BLANKPVPP_HBM_CPU1PVNN_MAIN_CPU1HSC MP5990 (1/4)HSC MP5990 (2/4)HSC MP5990 (3/4)HSC MODULE(1/4)TDRDUMMY SYMBOL287288289290291292293294295296297298299300301302303304305306307308309310312N/AN/A V054 OF 312SEANTABLE OF CONTENT 3/3
1
DEPARTMENT REV
7 3 2 6 5 4
C
A
B
7
E
D
6 4 5 3 2 1
E
D
C
B
A
DATE
PROJECT
SHEET
DOCUMENT NUMBERDESIGNER
SIZE
REVIEWER
C
CONTENTSPAGE(S) PAGE(S) CONTENTS PAGE(S) CONTENTS



Thu Aug 24 16:11:57 2023N/AN/AN/AN/AV055 OF 312BLOCK DIAGRAM - MB
SHEETDATE
DEPARTMENT
SIZE
PROJECT DOCUMENT NUMBER REV
REVIEWER
DESIGNER
123
7 3 2 1 6 5 4
E
A
B
C
E
D
C
B
A
7 6 5 4
D
C



Thu Aug 24 16:11:58 2023N/AN/AN/AN/AV056 OF 312BLOCK DIAGRAM - SPI
SHEETDATE
DEPARTMENT
SIZE
PROJECT DOCUMENT NUMBER REV
REVIEWER
DESIGNER
123
7 3 2 1 6 5 4
E
A
B
C
E
D
C
B
A
7 6 5 4
D
C



Thu Aug 24 16:11:59 2023N/AN/AN/AN/AV057 OF 312BLOCK DIAGRAM - VR
SHEETDATE
DEPARTMENT
SIZE
PROJECT DOCUMENT NUMBER REV
REVIEWER
DESIGNER
123
7 3 2 1 6 5 4
E
A
B
C
E
D
C
B
A
7 6 5 4
D
C



Thu Aug 24 16:11:59 2023N/AN/AN/AN/AV058 OF 312BLCOK DIAGRAM - CLOCK
SHEETDATE
DEPARTMENT
SIZE
PROJECT DOCUMENT NUMBER REV
REVIEWER
DESIGNER
123
7 3 2 1 6 5 4
E
A
B
C
E
D
C
B
A
7 6 5 4
D
C



Thu Aug 24 16:12:00 2023N/AN/AN/AN/AV059 OF 312BLOCK DIAGRAM - SMBUS
SHEETDATE
DEPARTMENT
SIZE
PROJECT DOCUMENT NUMBER REV
REVIEWER
DESIGNER
123
7 3 2 1 6 5 4
E
A
B
C
E
D
C
B
A
7 6 5 4
D
C



Thu Aug 24 16:12:01 2023N/AN/AN/AN/AV0510 OF 312BLOCK DIAGRAM - I3C
SHEETDATE
DEPARTMENT
SIZE
PROJECT DOCUMENT NUMBER REV
REVIEWER
DESIGNER
123
7 3 2 1 6 5 4
E
A
B
C
E
D
C
B
A
7 6 5 4
D
C



Thu Aug 24 16:12:01 2023N/AN/AN/AN/AV0511 OF 312BLOCK DIAGRAM - JTAG
SHEETDATE
DEPARTMENT
SIZE
PROJECT DOCUMENT NUMBER REV
REVIEWER
DESIGNER
123
7 3 2 1 6 5 4
E
A
B
C
E
D
C
B
A
7 6 5 4
D
C



Thu Aug 24 16:12:02 2023N/AN/AN/AN/AV0512 OF 312BLOCK DIAGRAM - POWER SEQUENCE
SHEETDATE
DEPARTMENT
SIZE
PROJECT DOCUMENT NUMBER REV
REVIEWER
DESIGNER
123
7 3 2 1 6 5 4
E
A
B
C
E
D
C
B
A
7 6 5 4
D
C



13 OF 312V05N/AN/AN/AN/AFri Aug 25 13:59:59 2023SPR CPU0 MISC:CLK/JTAG/STRAPS(1/30)
2291192091192062062062062062062062061191192291281282292291281281191191192141192141192141192141192141191191191191191191331191192094419713344132132441324413113418244NC_CLK_PFT_OUT_CPU0_DNI3C_SPD_DDRABCD_CPU0_SCLTP_CPU0_BR23SOCKET4677_AZIF0045-P001C01CSPU_CPU0_FRMAGENTCLK_25M_NSSC_CPU0_DNNC_XTAL_CPU0_25M_OUTPUD_XTAL_CPU0_MODE0CLK_100M_DB2000_CPU0_BCLK0_DNCLK_100M_DB2000_CPU0_BCLK1_DPCLK_100M_DB2000_CPU0_BCLK1_DNCLK_100M_DB2000_CPU0_BCLK0_DPCLK_100M_DB2000_CPU0_BCLK2_DNCLK_100M_DB2000_CPU0_BCLK2_DPCLK_100M_DB2000_CPU0_BCLK3_DNCLK_100M_DB2000_CPU0_BCLK3_DPPD_CPU0_BIST_ENABLEH_CPU0_BMCINIT_LVC1I3C_SPD_DDRABCD_CPU0_SDARST_CPU0_DRAM_AB_NRST_CPU0_DRAM_CD_NI3C_SPD_DDREFGH_CPU0_SCLI3C_SPD_DDREFGH_CPU0_SDARST_CPU0_DRAM_EF_NRST_CPU0_DRAM_GH_NPD_CPU0_DMIMODE_OVERRIDEPU_CPU0_LEGACY_SKTPECI_CPU0_GTL_RFM_CPU0_PKGID2FM_CPU0_PKGID1FM_CPU0_PKGID0H_CPU0_PRDY_QS_GTL_R_NH_CPU0_PREQ_QS_GTL_R_NTP_CPU0_PROCDIS_COD_GTL_NFM_CPU0_PROC_ID1FM_CPU0_PROC_ID0PUD_XTAL_CPU0_MODE1NC_XTAL_CPU0_25M_INPD_EXT_CLK_SEL_CPU0NC_CLK_PFT_OUT_CPU0_DPPU_CPU0_SAFE_MODE_BOOTPU_CPU0_SOCKET_ID2PU_CPU0_SOCKET_ID1PU_CPU0_SOCKET_ID0JTAG_DBP_CPU0_GTL_R_TCKJTAG_DBP_CPU0_GTL_R_TDIJTAG_CPU0_MUX_GTL_TDOJTAG_DBP_CPU0_QS_GTL_R_TMSPU_CPU0_TXT_AGENTPD_CPU0_TXT_PLTENCLK_25M_NSSC_CPU0_DPIOSMLFPECI_CPU_GTL33.2CHIP1%1/16W0402LFJTAG_MUX_CPU0_GTL_TDICHIP1/16W2001%0402LFH_CPU_PRDY_QS_GTL_N0402LFCHIP10 1%1/16WH_CPU_PREQ_QS_GTL_N1000402LF1%1/16WCHIPJTAG_DBP_CPU_QS_GTL_TMS0402LF1%1001/16WCHIPJTAG_DBP_CPU_GTL_TCK1001%0402LF
R4
R6
R5
R3
R1
R2
G5
D4
CL72
CJ72
CE70
CD71
BY24
BR23
CT18
CU17
BY22
BT22
CY32
CW31
CT20
BT26
BR25 BW25
BV24
BT24
CT61
CY61
CW60
AU23
DA52
BH71
BG72
AV22
BP26
BN64
AY63
BL64
BH24
CY59
AU17
AW17
CY55
CY42
AV51
AU50
BN23
AT18
DA27
CW27
AV28
AU29
CW29
CY28
AV30
AT30
U2
1/42
XTAL_CLK_DN
RSVD157
RSVD120
BCLK0_DN
BCLK1_DP
BCLK1_DN
BCLK0_DP
BCLK2_DN
BCLK2_DP
BCLK3_DN
BCLK3_DP
BIST_ENABLE
BMCINIT
DDR0123_SPDSCL
DDR0123_SPDSDA
DDR01_RESET_N
DDR23_RESET_N
DDR4567_SPDSCL
DDR4567_SPDSDA
DDR45_RESET_N
DDR67_RESET_N
DMIMODE_OVERRIDE
FRMAGENT
LEGACY_SKT
RSVD72
PECI
PKG_ID2
PKG_ID1
PKG_ID0
PRDY_N
PREQ_N
PROCDIS_N
PROC_ID1
PROC_ID0
RSVD108
RSVD161
RSVD76
RSVD88
RSVD91
SAFE_MODE_BOOT
SOCKET_ID2
SOCKET_ID1
SOCKET_ID0
TCK
TDI
TDOTMS
TXT_AGENT
TXT_PLTEN
XTAL_CLK_DP
21
21 21
21
21 21
SHEETDATE
DEPARTMENT
SIZE
PROJECT DOCUMENT NUMBER REV
REVIEWER
DESIGNER
123
7 3 2 1 6 5 4
E
A
B
C
E
D
C
B
A
7 6 5 4
D
ININ
IN
IN
IN
ININ
OUTOUTOUTOUT
OUT
IN
ININ
IN
OUTOUT
OUT
IN
OUTOUTINININ
IN
IN
INININ
IN
IN
ININ
BI
IN
OUTIN
OUTBI
OUTBI
ININ
C



20210818 MODIFY FOR GT
20211129 ADD R4089Fri Aug 25 14:00:00 2023N/AN/AV0514 OF 312N/AN/APVNN_TERM_CPU0SPR CPU0 MISC:SMBUS/SVID/ERRORS(2/30)2662741414278
1191332221241241414141412712712712711912412412412423523523512112111712312312212213145225225225118
1414141445141418414266274
14266 274266 2741427827814266 27414278
27814141414 1445
236236
141418449.90402LF1/16W1%1/16W0402LFSVID_ALERT0_CPU0_R_NSVID_DIO1_CPU0_R
PU_TAP_ODT_CPU0_ENFM_CPU0_SKTOCC_LVT3_NTP_IBL_PLT_RST_SYNC_NRST_CPU0_LVC1_NPWRGD_CPU0_LVC1H_CPU0_PMSYNC_PCHH_CPU0_PMSYNC_CPU1_RTP_H_SBLINK2_CPU0_PMSYNCTP_H_SBLINK3_CPU0_PMSYNCTP_H_SBLINK4_CPU0_PMSYNCTP_H_SBLINK5_CPU0_PMSYNCTP_H_SBLINK6_CPU0_PMSYNCTP_H_SBLINK7_CPU0_PMSYNCH_CPU0_PMDOWN_PCH_R2H_CPU0_PMDOWN_CPU1_RTP_H_SBLINK2_CPU0_PMDOWNTP_H_SBLINK3_CPU0_PMDOWNTP_H_SBLINK4_CPU0_PMDOWNTP_H_SBLINK5_CPU0_PMDOWNTP_H_SBLINK6_CPU0_PMDOWNTP_H_SBLINK7_CPU0_PMDOWNPU_PIROM_CPU0_SM_WPSMB_S3M_CPU0_PIROM_3V3AUX_SDA_R1SMB_S3M_CPU0_PIROM_3V3AUX_SCL_R1PD_PIROM_CPU0_ADDR0PD_PIROM_CPU0_ADDR1PD_PIROM_CPU0_ADDR2PD_CPU0_ENH_MCECC_DISPWRGD_DRAMPWRGD_CPU0_GH_LVC1_RPWRGD_DRAMPWRGD_CPU0_EF_LVC1_RPWRGD_DRAMPWRGD_CPU0_CD_LVC1_RPWRGD_DRAMPWRGD_CPU0_AB_LVC1_RFM_PEHPCPU0_ALERT_NSMB_PEHPCPU0_GTL_SDASMB_PEHPCPU0_GTL_SCLH_CPU0_THERMTRIP_LVC1_R_NTP_EV_CPU0_EXT_BGREFSVID_DIO1_CPU0SVID_DIO0_CPU0SVID_CLK1_CPU0SVID_CLK0_CPU0SVID_ALERT1_CPU0_NSVID_ALERT0_CPU0_NNC_CPU0_VIEWPIN_DIE11<0>NC_CPU0_VIEWPIN_DIE01<0>NC_CPU0_VIEWPIN_DIE01<1>NC_CPU0_VIEWPIN_DIE00<2>NC_CPU0_VIEWPIN_DIE01<3>NC_CPU0_VIEWPIN_DIE00<1>NC_CPU0_VIEWPIN_DIE01<2>NC_CPU0_VIEWPIN_DIE00<0>NC_CPU0_VIEWPIN_DIE00<3>NC_CPU0_RSVD<144>NC_CPU0_VIEWPIN_DIE10<1>NC_CPU0_VIEWPIN_DIE10<3>NC_CPU0_VIEWPIN_DIE10<2>NC_CPU0_VIEWPIN_DIE10<0>NC_CPU0_VIEWPIN_DIE11<1>NC_CPU0_VIEWPIN_DIE11<2>NC_CPU0_VIEWPIN_DIE11<3>H_CPU0_PROCHOT_LVC1_NH_CPU0_PM_FAST_WAKE_NH_CPU0_NMI_LVC1_NH_CPU0_MEMTRIP_LVC1_R_NH_CPU0_MEMHOT_OUT_LVC1_R_NH_CPU0_MEMHOT_IN_LVC1_NFM_CPU_FBRK_DEBUG_R_NH_CPU0_ERR0_LVC1_R_NH_CPU0_ERR1_LVC1_R_NH_CPU0_ERR2_LVC1_R_NH_CPU0_CATERR_LVC1_R_NSMLFIOSOCKET4677_AZIF0045-P001C01CS
PLACE R4089 CLOSE TO CPU1PLACE R322 CLOSE TO CPU0PLACE R11 CLOSE TO CPU1PLACE R2362 CLOSE TO CPU00402LF0402LFH_CPU0_PMSYNC_CPU1_R1H_CPU0_PMSYNC_CPU1_RH_CPU0_PMDOWN_CPU1_R10402LF33.21/16WH_CPU0_PMDOWN_CPU1_R1CHIPCHIPH_CPU0_PMSYNC_CPU1H_CPU0_PMSYNC_CPU1_R11%33.21%CHIPPLACE R10 CLOSE TO CPU0PLACE R1960 CLOSE TO PCHPLACE R1959 CLOSE TO CPU0PLACE R7 CLOSE TO PCH5%CHIP00402LF1/16WH_CPU0_PMDOWN_PCH_R201/16W0402LFH_CPU0_PMSYNC_PCH_R2CHIP1/16W1%1000402LFSVID_DIO0_CPU0_R100CHIP
0402LF5%0CHIP 1/16WSVID_DIO0_CPU0_R0402LF5%0SVID_CLK0_CPU0_R0402LF05%SVID_DIO1_CPU0_R00402LF5%SVID_CLK1_CPU0_R0402LF1/16W2001%CHIPSVID_ALERT0_CPU0_R_N2001%0402LF1/16WCHIPSVID_ALERT1_CPU0_R_N
1/16W0402LFCHIP1%CHIPSVID_ALERT1_CPU0_R_N49.91%
1%33.233.21%CHIP
1/16W1%H_CPU0_PMDOWN_CPU1_R0402LFCHIP1%1/16W33.2H_CPU0_PMDOWN_PCH_R33.21/16W0402LFH_CPU0_PMSYNC_PCH_R H_CPU0_PMSYNC_PCH0402LFCHIP1%33.2H_CPU0_PMDOWN_CPU1
CHIP1/16W0402LFSMB_S3M_CPU0_PIROM_3V3AUX_SDASMB_S3M_CPU0_PIROM_3V3AUX_SCL
CHIPH_CPU0_PMSYNC_PCH_RH_CPU0_PMDOWN_PCH_RH_CPU0_PMDOWN_PCHCHIP5%1%33.21/16W1/16W
R17
R14
R16
R15
R13
R12
R4089
R2362
R1960
R1959
R1933
R1932
R322
R11
R10
CW68
CW25
CW23
CV24
CR23
CN62
CM63
CL64
CL21
CJ62
CH22
BP69
BP67
BJ70
AY65
AY26
AV59
AV26
AU25
AT24
AV20
CR72
CM71
CU70
CP71
CT71
CR70
BD22
AY22
BF22
BL62
AY20
BL25
BD26
BF26
BH26
BJ25
BK26
CG66
BH61
AU19
DA39
CF24
CH24
CR19
CE25
CH26
CL25
CN25
CP20
CY40
CC25
CE23
CV18
CD24
CM26
CP26
CW39
AV18
AV24
CF26
AU21
AV57
CW45
CY44
F47
A43
BY26
CA25
BV26
BP24
U2
2/42
THERMTRIP_N
RSVD19
TAP_ODT_EN
SVIDDATA1
SVIDDATA0
SVIDCLK1
SVIDCLK0
SVIDALERT1_N
SVIDALERT0_N
SKTOCC_N
RSVD104
RSVD70
RSVD69
RSVD6
RSVD59
RSVD4
RSVD29
RSVD27
RSVD15
RSVD150
RSVD146
RSVD145
RSVD141
RSVD132
RSVD126
RSVD121
RSVD116
RSVD113
RESET_N
PWRGOOD
PROCHOT_N
PMSYNC_PCH
PMSYNC0
PMSYNC1
PMSYNC2
PMSYNC3
PMSYNC4
PMSYNC5
PMSYNC6
PMFAST_WAKE_N
PMDOWN_PCH
PMDOWN0
PMDOWN1
PMDOWN2
PMDOWN3
PMDOWN4
PMDOWN5
PMDOWN6
PIROM_SM_WP
PIROM_SDA
PIROM_SCL
PIROM_AD0
PIROM_AD1
PIROM_AD2
NMI
MEMTRIP_N
MEMHOT_OUT_N
MEMHOT_IN_N
FBRK_N
ERROR_N0
ERROR_N1
ERROR_N2
RSVD96
DDR67_DRAM_PWR_OK
DDR45_DRAM_PWR_OK
DDR23_DRAM_PWR_OK
DDR01_DRAM_PWR_OK
CXPSMBUS_ALERT_N
CXPSMBUSSDA
CXPSMBUSSCL
CATERR_N
21
21
21
21 21
21
21
21
21
21
21
21
21
21 21
21 21
R7
CAD NOTE:
CAD NOTE:
CAD NOTE:
R556
R555
R548
R328
SHEETDATE
DEPARTMENT
SIZE
PROJECT DOCUMENT NUMBER REV
REVIEWER
DESIGNER
123
7 3 2 1 6 5 4
E
A
B
C
E
D
C
B
A
7 6 5 4
D
OUT
OUT
OUT
OUT IN
BI
IN
IN
OUT
IN
OUTIN
IN INOUTBI
OUTIN
IN
BI
BI
ININ
IN
BI
IN
OUTOUTOUT
OUTOUTOUT
IN
INININININ
INOUT
OUTIN
INOUT
IN
OUT IN
OUTIN
OUTIN
OUT
IN OUT
IN OUT
BI
IN
IN
OUT
C



DEBUG PLDCPU0 SPI FLASH
Fri Aug 25 14:00:02 202315 OF 312V05N/AN/AN/AN/ASPR CPU0 MISC:(3 OF 30)
80808023623612012012012012012043 8021343PU_S3M_CPU0_CPLD_STATUSFM_S3M_CPU0_CPLD_CONFIG_NPU_S3M_CPU0_CPLD_CONFDSMB_S3M_CPU0_SDASMB_S3M_CPU0_SCLFM_S3M_CPU0_LVC1_GPIO_0FM_S3M_CPU0_LVC1_GPIO_1FM_S3M_CPU0_LVC1_GPIO_2FM_S3M_CPU0_LVC1_GPIO_3FM_S3M_CPU0_LVC1_GPIO_4TP_SGPIO_S3M_CPU0_GSXDLOAD_RTP_I2C_S3M_RTC_CPU0_ALERT_NTP_I2C_S3M_RTC_CPU0_SDATP_IBL_GRST_WARN_PLD_R_NTP_PWRGD_S0_PWROK_CPU0_LVC1TP_SGPIO_S3M_CPU0_GSXDINTP_SGPIO_S3M_CPU0_GSXDOUT_RTP_SGPIO_S3M_CPU0_GSXCLK_RPUD_PCH_BOOT_MODE_CPU0TP_SGPIO_S3M_CPU0_RST_R_NTP_ESPI_IBL_CPU0_IO3_LVC1TP_ESPI_IBL_CPU0_IO0_LVC1TP_ESPI_IBL_CPU0_IO1_LVC1TP_ESPI_IBL_CPU0_CS1_NTP_ESPI_IBL_CPU0_OE_LVC1_NTP_RST_ESPI_IBL_CPU0_LVC1_NTP_CLK_66M_ESPI_IBL_CPU0_LVC1TP_ESPI_IBL_CPU0_CS0_LVC1_NTP_ESPI_IBL_CPU0_ALERT0_LVC1_NTP_I3C_MNG2_BMC_SW_SCLTP_SPI_S3M_CPU0_IO2_LVC1_RTP_ESPI_IBL_CPU0_ALERT1_NTP_SPI_S3M_CPU0_IO3_LVC1_RTP_SPI_S3M_CPU0_CLK_LVC1_RTP_I3C_MNG2_BMC_SW_SDATP_SPI_IBL_CPU0_TPM_OE_NTP_SPI_S3M_CPU0_CS0_LVC1_R_NTP_SPI_S3M_CPU0_OE_LVC1_R_NTP_SPI_IBL_CPU0_TPM_IO0TP_SPI_S3M_CPU0_IO0_LVC1_RTP_SPI_IBL_CPU0_TPM_CS0_NTP_SPI_IBL_CPU0_TPM_IO1TP_SPI_S3M_CPU0_IO1_LVC1_RTP_FM_IBL_WAKE_CPU0_NTP_SPI_S3M_CPU0_CS1_LVC1_R_NNC_UART_IBL_CPU0_RTSNC_UART_IBL_CPU0_RXDPD_JTAG_CPU0_PLD_TCKFM_S3M_CPU0_CPLD_CRC_ERRORTP_IBL_SLPS5_CPU0_R_NNC_UART_IBL_CPU0_CTSNC_UART_IBL_CPU0_TXDTP_JTAG_CPU0_PLD_TMSTP_FM_IBL_ADR_TRIGGER_CPU0_RTP_JTAG_CPU0_PLD_TDITP_IBL_SLPS3_CPU0_R_NTP_FM_IBL_ADR_COMPLETE_CPU0_RTP_JTAG_CPU0_PLD_TDOTP_ESPI_IBL_CPU0_IO2_LVC1TP_FM_IBL_ADR_ACK_CPU0TP_IBL_SLPS4_CPU0_R_NTP_CPU0_SSC_SYNCTP_SPI_IBL_CPU0_TPM_CLKTP_I2C_S3M_RTC_CPU0_SCLTP_CPU0_PWRBTN_NTP_FM_IBL_SYS_RST_CPU0_NPWRGD_PLT_AUX_CPU0_LVT3SOCKET4677_AZIF0045-P001C01CSIOSMLF
AY69
AV69
CF61
CY22
CH65
CK65
CJ64
CY71
CY69
CW21
CV71
CV69
CV22
CT24
CT22
CR21
CP24
CP22
CN23
CN21
CL66
CL23
CK24
CK22
CJ66
CJ25
CJ23
CJ21
CH71
CH63
CF65
CF63
CD65
BM63
BK63
BJ64
BH65
BH63
BG64
BG62
BF65
BE62
BE25
BD65
BD63
BD61
BC64
BC25
BB67
BB61
BA68
BA66
BA62
AY67
AY61
AW70
AW64
AW19
AV63
AU64
AU62
AV71
BA70
CY20
CD63
CE64
CV20
U2
3/42
TEST_3
TEST_2
TEST_1
SMB_DATA
SMB_CLK
PARTITION_ID0
PARTITION_ID1
TEST_7
TEST_8
RSVD25
RSVD105
RSVD103
RSVD102
RSVD101
RSVD100
RSVD98
RSVD94
RSVD93
TEST_6
RSVD86
RSVD64
RSVD61
RSVD58
RSVD56
RSVD55
RSVD53
RSVD52
RSVD50
RSVD48
RSVD47
RSVD42
RSVD41
RSVD40
RSVD39
RSVD38
RSVD36
RSVD35
RSVD34
RSVD33
RSVD32
RSVD30
RSVD28
RSVD24
RSVD23
RSVD20
RSVD156
RSVD155
TEST_5
CD_INIT_ERROR
RSVD144
RSVD143
RSVD142
RSVD140
RSVD137
RSVD136
RSVD131
RSVD128
RSVD127
RSVD12
RSVD124
RSVD123
RSVD117
RSVD11
RSVD114
RSVD110
RSVD109
PLT_AUX_PWRGOOD
SHEETDATE
DEPARTMENT
SIZE
PROJECT DOCUMENT NUMBER REV
REVIEWER
DESIGNER
123
7 3 2 1 6 5 4
E
A
B
C
E
D
C
B
A
7 6 5 4
D
OUT
OUTOUT
OUT
BIOUT
ININ
IN
OUTINININ
OUT
C



Fri Aug 25 14:00:03 2023N/A16 OF 312V05N/AN/AN/A
PVNN_TERM_CPU0
SPR CPU0 MISC:DDRVIEW & VSENSE(4/30)
VSENSE_PVCCFA_EHV_FIVRA_CPU0_DPVSENSE_PVCCFA_EHV_FIVRA_CPU0_DNNC_CPU0_DDR23_VIEWDIG1NC_CPU0_DDR01_VIEWDIG0NC_CPU0_DDR01_VIEWDIG1DBP_CPU_MBP1_GTL_NDBP_CPU_MBP0_GTL_N26627427426627826627427426627811711847132471647161821647182164747132SOCKET4677_AZIF0045-P001C01CSVSENSE_PVCCIN_CPU0_DNVSENSE_PVCCINFAON_CPU0_DNVSENSE_PVCCFA_EHV_CPU0_DNVSENSE_PVCCD_HV_CPU0_DNVSENSE_PVCCIN_CPU0_DPVSENSE_PVCCINFAON_CPU0_DPVSENSE_PVCCFA_EHV_CPU0_DPVSENSE_PVCCD_HV_CPU0_DPNC_CPU0_DDR23_VIEWDIG0NC_CPU0_DDR67_VIEWDIG0NC_CPU0_DDR67_VIEWDIG1NC_CPU0_DDR45_VIEWDIG1NC_CPU0_DDR45_VIEWDIG0H_PMAX_TRIGGER_IO_CPU0NC_CPU0_LGSSPARE4NC_CPU0_THERMADANC_CPU0_THERMADCTP_CPU0_A0_DEBUG_ENNC_CPU0_LGSSPARE0NC_CPU0_LGSSPARE5NC_CPU0_LGSSPARE1NC_CPU0_LGSSPARE2NC_CPU0_LGSSPARE3H_CPU0_RMCA_LVC1_R_NDBP_CPU0_HOOK9_MBP3_GTL_QS_R_NDBP_CPU0_HOOK8_MBP2_GTL_QS_R_NDBP_CPU0_MBP1_GTL_R_NDBP_CPU0_MBP0_GTL_R_NTP_CPU0_IFST_TRIG_LVC1_RTP_CPU0_IFST_KOT_LVC1_RTP_CPU0_IFST_DONE_LVC1_RIOSMLF1/16WCHIP4990402LF1%CHIP1%0402LF4991/16WDBP_CPU_HOOK8_MBP2_GTL_QS_N1/16W0402LF10CHIP1%DBP_CPU_MBP1_GTL_N1/16W0402LF1001%CHIPDBP_CPU_MBP0_GTL_N1/16W0402LF1001%CHIPFM_PCH_TRIGGER1_N1/16W0402LF05%CHIPFM_PCH_TRIGGER0_NCHIP 1/16W5%00402LFDBP_CPU_HOOK9_MBP3_GTL_QS_N1/16W0402LF1%CHIP10
R25
R24
R23
R22
BN11
AT85
CY24
H12
DA45
CY49
CY38
CU62
CR60
CP61
CN60
CE62
CC64
BF24
BE23
BC23
AV40
AV38
AV32
AU58
AU56
AU33
CE11
BC90
BA11
CA11
BD87
AU11
AY85
BU11
BH22
BD24
BK24
BJ23
BN25
BL23
U2
4/42
VSS_VCCIN_SENSE
VSS_VCCINFAON_SENSE
VSS_VCCFA_EHV_SENSE
VSS_VCCFA_EHV_FIVRA_SENSE
VSS_VCCD_HV_SENSE
VCCIN_SENSE
VCCINFAON_SENSE
VCCFA_EHV_SENSE
VCCFA_EHV_FIVRA_SENSE
VCCD_HV_SENSE
RSVD81
RSVD9
RSVD7
RSVD18
RSVD17
RSVD16 RSVD162
RSVD158
RSVD153
RSVD152
RSVD151
RSVD134
RSVD129
RSVD125
RSVD139
RSVD90
RSVD10
RMCA_N
PMAX_TRIGGER_IO
MBP3_N
MBP2_N
MBP1_N
MBP0_N
RSVD49
RSVD46
RSVD37
2
1
2
1
21 21
21 21 21 21
R21R20
SHEETDATE
DEPARTMENT
SIZE
PROJECT DOCUMENT NUMBER REV
REVIEWER
DESIGNER
123
7 3 2 1 6 5 4
E
A
B
C
E
D
C
B
A
7 6 5 4
D
OUTOUT
OUTOUT
OUTOUT
BIBIIN
OUT
IN
BIBIBI
OUT
BI
BI
IN
OUTOUT
R18 R19
C



Fri Aug 25 14:00:03 2023N/AN/A V0517 OF 312N/AN/ASPR CPU0 MISC:VIEW MDFI/HBM(5 OF 30)
NC_CPU0_MDFI_DIE11_EW1NC_CPU0_MDFI_DIE10_NS0NC_CPU0_MDFI_DIE10_EW1NC_CPU0_MDFI_DIE10_EW0NC_CPU0_MDFI_DIE10_NS1NC_CPU0_MDFI_DIE01_EW1NC_CPU0_MDFI_DIE00_EW1NC_CPU0_SOC_SPARE5NC_CPU0_MDFI_DIE00_EW0NC_CPU0_SOC_SPARE1NC_CPU0_HBM3_VIEWDIG1NC_CPU0_MDFI_DIE00_NS0NC_CPU0_MDFI_DIE00_NS1NC_CPU0_HBM3_VIEWDIG0NC_CPU0_MDFI_DIE01_NS0TP_CPU0_DIE_HVM_EN_LVC1NC_CPU0_MDFI_DIE01_NS1NC_CPU0_SOC_SPARE4NC_CPU0_SOC_SPARE0NC_CPU0_MDFI_DIE01_EW0NC_CPU0_HBM1_VIEWDIG0NC_CPU0_HBM0_VIEWDIG0NC_CPU0_HBM0_VIEWDIG1NC_CPU0_VIEWPIN_GNR3NC_CPU0_VIEWPIN_GNR1NC_CPU0_HBM1_VIEWDIG1NC_CPU0_VIEWPIN_GNR0NC_CPU0_VIEWPIN_GNR2NC_CPU0_MDFI_DIE11_NS1NC_CPU0_MDFI_DIE11_EW0NC_CPU0_MDFI_DIE11_NS0NC_CPU0_HBM2_VIEWDIG1NC_CPU0_HBM2_VIEWDIG0SOCKET4677_AZIF0045-P001C01CSIOSMLF
W17
U17
EG17
CY57
CW58
CW41
CT26
CR25
CK67
CJ70
CJ68
CH69
CF22
CD30
CD26
CD22
CC66
BR21
BP65
BP22
BM65
BL60
BK22
BJ21
BG78
BF71
BE21
BD71
BA25
AY24
AV65
AD77
AC78
U2
5/42
RSVD99
RSVD92
RSVD85
RSVD84
RSVD83
RSVD82
RSVD71
RSVD68
RSVD67
RSVD65
RSVD63
RSVD60
RSVD57
RSVD54
RSVD51
RSVD45
RSVD43
RSVD31
RSVD26
RSVD21
RSVD165
RSVD164
RSVD160
RSVD154
RSVD149
RSVD147
RSVD138
RSVD133
RSVD112
RSVD107
RSVD106RSVD1
RSVD0
SHEETDATE
DEPARTMENT
SIZE
PROJECT DOCUMENT NUMBER REV
REVIEWER
DESIGNER
123
7 3 2 1 6 5 4
E
A
B
C
E
D
C
B
A
7 6 5 4
D
C



18 OF 312N/AFri Aug 25 14:00:04 2023V05N/AN/AN/ASPR CPU0 MISC:SPARE(6 OF 30)
TP_CPU0_PPDTP_CPU0_SPARE10TP_CPU0_SPARE8TP_CPU0_SPARE11TP_CPU0_SPARE5TP_CPU0_SPARE9TP_CPU0_SPARE13TP_CPU0_SPARE4TP_CPU0_SPARE6TP_CPU0_SPARE7TP_CPU0_SPARE12SOCKET4677_AZIF0045-P001C01CSIOSMLF
J13
DA70
CW43
CL70
CL60
CK61
CH61
CG60
CD69
BD77
AU52
U2
6/42
RSVD163
RSVD95
RSVD111
RSVD87
RSVD8
RSVD97
RSVD44
RSVD159
RSVD148
RSVD115
RSVD119
SHEETDATE
DEPARTMENT
SIZE
PROJECT DOCUMENT NUMBER REV
REVIEWER
DESIGNER
123
7 3 2 1 6 5 4
E
A
B
C
E
D
C
B
A
7 6 5 4
D
C



Fri Aug 25 14:00:05 2023N/AN/AN/AN/AV0519 OF 312SPR CPU0 MISC:7 OF 30)
126126126126PU_CPU0_UPI2_AC_COUPLINGPU_CPU0_UPI1_AC_COUPLINGPU_CPU0_UPI0_AC_COUPLINGPU_CPU0_UPI3_AC_COUPLINGNC_CPU0_PE1_APROBE<0>NC_CPU0_PE2_APROBE<0>NC_CPU0_PE1_APROBE<1>NC_CPU0_UPI1_APROBE<1>NC_CPU0_DMI_APROBE<0>NC_CPU0_PE2_APROBE<1>NC_CPU0_DMI_APROBE<1>NC_CPU0_UPI1_APROBE<0>NC_CPU0_PE0_APROBE<0>NC_CPU0_PE0_APROBE<1>NC_CPU0_UPI2_APROBE<1>NC_CPU0_UPI0_APROBE<1>NC_CPU0_PE4_APROBE<0>NC_CPU0_UPI0_APROBE<0>NC_CPU0_UPI2_APROBE<0>NC_CPU0_PE4_APROBE<1>NC_CPU0_UPI3_APROBE<1>NC_CPU0_UPI3_APROBE<0>NC_CPU0_PE3_APROBE<1>NC_CPU0_PE3_APROBE<0>TP_TRC_CPU0_PTI3_CLKTP_TRC_CPU0_PTI2_CLKTP_TRC_CPU0_PTI<16>TP_TRC_CPU0_PTI<17>TP_TRC_CPU0_PTI<18>TP_TRC_CPU0_PTI<19>TP_TRC_CPU0_PTI<20>TP_TRC_CPU0_PTI<21>TP_TRC_CPU0_PTI<22>TP_TRC_CPU0_PTI<23>TP_TRC_CPU0_PTI<24>TP_TRC_CPU0_PTI<25>TP_TRC_CPU0_PTI<26>TP_TRC_CPU0_PTI<27>TP_TRC_CPU0_PTI<28>TP_TRC_CPU0_PTI<29>TP_TRC_CPU0_PTI<30>TP_TRC_CPU0_PTI<31>TP_TRC_CPU0_PTI1_CLKTP_TRC_CPU0_PTI0_CLKTP_TP_TRC_CPU0_PTI_MON<0>TP_TRC_CPU0_PTI_MON<1>TP_TRC_CPU0_PTI<2>TP_TRC_CPU0_PTI<3>TP_TRC_CPU0_PTI<4>TP_TRC_CPU0_PTI<5>TP_TRC_CPU0_PTI<6>TP_TRC_CPU0_PTI<7>TP_TRC_CPU0_PTI<8>TP_TRC_CPU0_PTI<9>TP_TRC_CPU0_PTI<10>TP_TRC_CPU0_PTI<11>TP_TRC_CPU0_PTI<12>TP_TRC_CPU0_PTI<13>TP_TRC_CPU0_PTI<14>TP_TRC_CPU0_PTI<15>SOCKET4677_AZIF0045-P001C01CSIOSMLF
CR68
CP69
CM69
CL68
CE21
CC23
CC21CA23
CA21
BW23
BW21
BV22
BN21
BL21
AV67
AU68
AU66
AT67
AR17
AN17
CK71
BB65
CW19
BA23
BN66
BM67
BL66
BJ66
BG66
BN68
BM69
BK69
BD67
BG68
BC68
BP30
BH69
BN29
BF69
BP28
BD69
BN27
BE70
BT30
BC70
BU29
BT28
BU27
BV28
CA27
BV30
CA29
BY30
CC27
BK67
BF67
CD28
BY28
CB30
CC29
U2
7/42
UPI3_AC_COUPLING
UPI2_AC_COUPLING
UPI1_AC_COUPLING
UPI0_AC_COUPLING
RSVD89
RSVD80
RSVD79RSVD78
RSVD77
RSVD75
RSVD74
RSVD73
RSVD66
RSVD62
RSVD5
RSVD3
RSVD22
RSVD2
RSVD14
RSVD13
RSVD135
RSVD130
RSVD122
RSVD118
PTI_DIE01_STB_1
PTI_DIE01_STB_0
PTI_DIE010
PTI_DIE011
PTI_DIE012
PTI_DIE013
PTI_DIE014
PTI_DIE015
PTI_DIE016
PTI_DIE017
PTI_DIE018
PTI_DIE019
PTI_DIE0110
PTI_DIE0111
PTI_DIE0112
PTI_DIE0113
PTI_DIE0114
PTI_DIE0115
PTI_DIE00_STB_1
PTI_DIE00_STB_0
PTI_DIE000
PTI_DIE001
PTI_DIE002
PTI_DIE003
PTI_DIE004
PTI_DIE005
PTI_DIE006
PTI_DIE007
PTI_DIE008
PTI_DIE009
PTI_DIE0010
PTI_DIE0011
PTI_DIE0012
PTI_DIE0013
PTI_DIE0014
PTI_DIE0015
SHEETDATE
DEPARTMENT
SIZE
PROJECT DOCUMENT NUMBER REV
REVIEWER
DESIGNER
123
7 3 2 1 6 5 4
E
A
B
C
E
D
C
B
A
7 6 5 4
D
ININININ
C



N/AFri Aug 25 14:00:06 202320 OF 312N/A V05N/AN/ASPR CPU0 - DDR CH A (8 OF 30)82 8382 838283828382 8382838283 82 8382 83
8283 82 8382 838283 82 8382 838283 82 8382 838283
SOCKET4677_AZIF0045-P001C01CS
M_A_CPU0_SB_PARM_A_CPU0_SA_PARM_A_CPU0_SB_RSP<0>M_A_CPU0_SB_RSP<1>M_A_CPU0_SA_RSP<0>M_A_CPU0_SA_RSP<1>M_A_CPU0_ALERT_N
IOSMLF
M_A_CPU0_CLK_DN<1:0>M_A_CPU0_CLK_DP<1:0>M_A_CPU0_SA_CA<6:0>M_A_CPU0_SA_CS_N<3:0>
M_A_CPU0_SA_DQ<31:0>M_A_CPU0_SA_DQS_DN<9:0>M_A_CPU0_SA_DQS_DP<9:0>M_A_CPU0_SA_CB<7:0>M_A_CPU0_SB_CA<6:0>M_A_CPU0_SB_CS_N<3:0>M_A_CPU0_SB_DQ<31:0>M_A_CPU0_SB_DQS_DN<9:0>M_A_CPU0_SB_DQS_DP<9:0>M_A_CPU0_SB_CB<7:0>
E37
F38
C37
B38
F53
E54
B53
C54
G39
F34
E35
B34
C35
E31
F32
C31
B32
C33
E9
E21
E27
P30
E33
C9
C21
C27
K30
A33
G9
G21
G27
M30
G33
A9
A21
A27
H30
E7
F8
C7
B8
F10
E11
B10
C11
E19
F20
C19
B20
F22
E23
B22
C23
E25
F26
C25
B26
F28
E29
B28
C29
M28
N29
K28
J29
N31
M32
J31
K32
A39
F40
B40
E41
C41
F44
E43
E48
E56
F57
C56
B57
F59
E60
B59
C60
E58
E64
E70
M67
F77
C58
C64
C70
K67
D77
G58
G64
G70
P67
H77
A58
A64
B71
H67
B77
E62
F63
C62
B63
F65
E66
B65
C66
E68
F69
C68
B69
F71
D73
E72
B73
M65
N66
K65
J66
N68
M69
J68
K69
F75
G76
D75
C76
G78
M77
B79
B81
C48
E50
C50
F51
B51
G52
A52
E45
C43
G45
B44
AV42
AV44
AT49
AU43
AT42
25
19
5
7
8
9
0
9
8
7
16
5
6
4
3
1
2
0
15
1
3
5
6
7
4
14
0
2
2
1
0
3
4
5
7
6
13
8
10
9
13
11
12
14
15
18
17
12
16
19
20
23
22
21
24
27
28
11
26
29
30
31
0
1
10
9
8
2
7
6
5
4
3
31
30
29
27
28
26
25
0
1
0
1
23
0
1
2
3
4
7
6
5
24
0
2
1
3
0
22
3
2
1
0
1
2
3
4
21
6
5
4
6
5
2
20
3
0
1
0
2
1
4
5
3
6
7
9
8
1
0
4
2
3
6
5
18
7
8
9
1
4
2
3
617
U2
8/42
DDR0_SB_PAR
DDR0_SB_ECC0
DDR0_SB_ECC1
DDR0_SB_ECC2
DDR0_SB_ECC3
DDR0_SB_ECC4
DDR0_SB_ECC5
DDR0_SB_ECC6
DDR0_SB_ECC7
DDR0_SB_DQS_DP0
DDR0_SB_DQS_DP1
DDR0_SB_DQS_DP2
DDR0_SB_DQS_DP3
DDR0_SB_DQS_DP4
DDR0_SB_DQS_DP5
DDR0_SB_DQS_DP6
DDR0_SB_DQS_DP7
DDR0_SB_DQS_DP8
DDR0_SB_DQS_DP9
DDR0_SB_DQS_DN0
DDR0_SB_DQS_DN1
DDR0_SB_DQS_DN2
DDR0_SB_DQS_DN3
DDR0_SB_DQS_DN4
DDR0_SB_DQS_DN5
DDR0_SB_DQS_DN6
DDR0_SB_DQS_DN7
DDR0_SB_DQS_DN8
DDR0_SB_DQS_DN9
DDR0_SB_DQ0
DDR0_SB_DQ1
DDR0_SB_DQ2
DDR0_SB_DQ3
DDR0_SB_DQ4
DDR0_SB_DQ5
DDR0_SB_DQ6
DDR0_SB_DQ7
DDR0_SB_DQ8
DDR0_SB_DQ9
DDR0_SB_DQ10
DDR0_SB_DQ11
DDR0_SB_DQ12
DDR0_SB_DQ13
DDR0_SB_DQ14
DDR0_SB_DQ15
DDR0_SB_DQ16
DDR0_SB_DQ17
DDR0_SB_DQ18
DDR0_SB_DQ19
DDR0_SB_DQ20
DDR0_SB_DQ21
DDR0_SB_DQ22
DDR0_SB_DQ23
DDR0_SB_DQ24
DDR0_SB_DQ25
DDR0_SB_DQ26
DDR0_SB_DQ27
DDR0_SB_DQ28
DDR0_SB_DQ29
DDR0_SB_DQ30
DDR0_SB_DQ31
DDR0_SB_CS_N0
DDR0_SB_CS_N1
DDR0_SB_CS_N2
DDR0_SB_CS_N3
DDR0_SB_CA0
DDR0_SB_CA1
DDR0_SB_CA2
DDR0_SB_CA3
DDR0_SB_CA4
DDR0_SB_CA5
DDR0_SB_CA6
DDR0_SA_PAR
DDR0_SA_ECC0
DDR0_SA_ECC1
DDR0_SA_ECC2
DDR0_SA_ECC3
DDR0_SA_ECC4
DDR0_SA_ECC5
DDR0_SA_ECC6
DDR0_SA_ECC7
DDR0_SA_DQS_DP0
DDR0_SA_DQS_DP1
DDR0_SA_DQS_DP2
DDR0_SA_DQS_DP3
DDR0_SA_DQS_DP4
DDR0_SA_DQS_DP5
DDR0_SA_DQS_DP6
DDR0_SA_DQS_DP7
DDR0_SA_DQS_DP8
DDR0_SA_DQS_DP9
DDR0_SA_DQS_DN0
DDR0_SA_DQS_DN1
DDR0_SA_DQS_DN2
DDR0_SA_DQS_DN3
DDR0_SA_DQS_DN4
DDR0_SA_DQS_DN5
DDR0_SA_DQS_DN6
DDR0_SA_DQS_DN7
DDR0_SA_DQS_DN8
DDR0_SA_DQS_DN9
DDR0_SA_DQ0
DDR0_SA_DQ1
DDR0_SA_DQ2
DDR0_SA_DQ3
DDR0_SA_DQ4
DDR0_SA_DQ5
DDR0_SA_DQ6
DDR0_SA_DQ7
DDR0_SA_DQ8
DDR0_SA_DQ9
DDR0_SA_DQ10
DDR0_SA_DQ11
DDR0_SA_DQ12
DDR0_SA_DQ13
DDR0_SA_DQ14
DDR0_SA_DQ15
DDR0_SA_DQ16
DDR0_SA_DQ17
DDR0_SA_DQ18
DDR0_SA_DQ19
DDR0_SA_DQ20
DDR0_SA_DQ21
DDR0_SA_DQ22
DDR0_SA_DQ23
DDR0_SA_DQ24
DDR0_SA_DQ25
DDR0_SA_DQ26
DDR0_SA_DQ27
DDR0_SA_DQ28
DDR0_SA_DQ29
DDR0_SA_DQ30
DDR0_SA_DQ31
DDR0_SA_CS_N0
DDR0_SA_CS_N1
DDR0_SA_CS_N2
DDR0_SA_CS_N3
DDR0_SA_CA0
DDR0_SA_CA1
DDR0_SA_CA2
DDR0_SA_CA3
DDR0_SA_CA4
DDR0_SA_CA5
DDR0_SA_CA6
DDR0_CLK_DP0
DDR0_CLK_DP1
DDR0_CLK_DN0
DDR0_CLK_DN1
DDR0_B_RSP0
DDR0_B_RSP1
DDR0_A_RSP0
DDR0_A_RSP1
DDR0_ALERT_N
SHEETDATE
DEPARTMENT
SIZE
PROJECT DOCUMENT NUMBER REV
REVIEWER
DESIGNER
123
7 3 2 1 6 5 4
E
A
B
C
E
D
C
B
A
7 6 5 4
D
BI
BI
BI
BI
BI
OUT
OUT
BI
IN
ININ
ININ
OUT
OUT
OUT
BI
OUT
BI
BI
BI
C



Fri Aug 25 14:00:07 202321 OF 312N/AN/A V05N/AN/ASPR CPU0 - DDR CH B (9 OF 30)84 8584 858485848584 8584 8584858485 84 8584 85
8485 84 8584 858485 84 858485 84 8584 858485
IO
M_B_CPU0_SB_PARM_B_CPU0_SA_PARM_B_CPU0_SB_RSP<0>M_B_CPU0_SB_RSP<1>M_B_CPU0_SA_RSP<0>M_B_CPU0_SA_RSP<1>M_B_CPU0_ALERT_N
SOCKET4677_AZIF0045-P001C01CSSMLF
M_B_CPU0_SB_CS_N<3:0>M_B_CPU0_CLK_DN<1:0>M_B_CPU0_CLK_DP<1:0>M_B_CPU0_SA_CA<6:0>M_B_CPU0_SA_CS_N<3:0>
M_B_CPU0_SA_DQ<31:0>M_B_CPU0_SA_DQS_DN<9:0>M_B_CPU0_SA_DQS_DP<9:0>M_B_CPU0_SA_CB<7:0>M_B_CPU0_SB_CA<6:0>M_B_CPU0_SB_DQ<31:0>M_B_CPU0_SB_DQS_DN<9:0>M_B_CPU0_SB_DQS_DP<9:0>M_B_CPU0_SB_CB<7:0>
M40
N41
K40
J41
N50
M51
J50
K51
P42
N37
M38
J37
K38
M34
N35
K34
J35
H36
G15
P18
P24
AA27
M36
C15
K18
K24
U27
K36
E15
M18
M24
W27
P36
A15
H18
H24
R27
F14
B14
E13
C13
F16
E17
B16
C17
M16
N17
K16
J17
N19
M20
J19
K20
M22
N23
K22
J23
N25
M26
J25
K26
W25
Y26
U25
T26
Y28
W29
T28
U29
H42
N43
J43
M44
K44
U43
T44
W43
M53
N54
K53
J54
N56
M57
J56
K57
P55
W58
P61
W70
P73
K55
U58
K61
U70
K73
M55
AA58
M61
AA70
M73
H55
R58
H61
R70
H73
W56
Y57
U56
T57
Y59
W60
T59
U60
M59
N60
K59
J60
N62
M63
J62
K63
W68
Y69
U68
T69
Y71
W72
T71
U72
M71
N72
K71
J72
N74
M75
J74
K75
Y44
M47
K47
N48
J48
P49
H49
AA45
U45
W45
R45
AP47
AN48
AV49
AK47
AL48
26
1
2
0
2
3
0
1
31
30
0
29
28
27
25
24
21
22
23
1
20
19
16
17
18
15
14
12
11
13
1
9
10
8
6
7
5
4
3
7
0
0
1
2
6
4
5
3
2
1
31
0
28
30
29
27
26
25
24
23
22
21
20
19
18
17
16
15
14
13
11
12
10
9
8
7
5
6
4
3
0
2
7
6
9
8
7
5
6
0
3
2
4
0
1
8
9
7
6
3
1
5
4
1
2
0
7
9
8
5
6
5
3
2
4
1
0
8
9
7
6
3
3
5
4
1
2
0
4
5
6
4
3
2
2
1
0
4
5
6
3
2
0
1
3
1
U2
9/42
DDR1_SB_PAR
DDR1_SB_ECC0
DDR1_SB_ECC1
DDR1_SB_ECC2
DDR1_SB_ECC3
DDR1_SB_ECC4
DDR1_SB_ECC5
DDR1_SB_ECC6
DDR1_SB_ECC7
DDR1_SB_DQS_DP0
DDR1_SB_DQS_DP1
DDR1_SB_DQS_DP2
DDR1_SB_DQS_DP3
DDR1_SB_DQS_DP4
DDR1_SB_DQS_DP5
DDR1_SB_DQS_DP6
DDR1_SB_DQS_DP7
DDR1_SB_DQS_DP8
DDR1_SB_DQS_DP9
DDR1_SB_DQS_DN0
DDR1_SB_DQS_DN1
DDR1_SB_DQS_DN2
DDR1_SB_DQS_DN3
DDR1_SB_DQS_DN4
DDR1_SB_DQS_DN5
DDR1_SB_DQS_DN6
DDR1_SB_DQS_DN7
DDR1_SB_DQS_DN8
DDR1_SB_DQS_DN9
DDR1_SB_DQ0
DDR1_SB_DQ1
DDR1_SB_DQ2
DDR1_SB_DQ3
DDR1_SB_DQ4
DDR1_SB_DQ5
DDR1_SB_DQ6
DDR1_SB_DQ7
DDR1_SB_DQ8
DDR1_SB_DQ9
DDR1_SB_DQ10
DDR1_SB_DQ11
DDR1_SB_DQ12
DDR1_SB_DQ13
DDR1_SB_DQ14
DDR1_SB_DQ15
DDR1_SB_DQ16
DDR1_SB_DQ17
DDR1_SB_DQ18
DDR1_SB_DQ19
DDR1_SB_DQ20
DDR1_SB_DQ21
DDR1_SB_DQ22
DDR1_SB_DQ23
DDR1_SB_DQ24
DDR1_SB_DQ25
DDR1_SB_DQ26
DDR1_SB_DQ27
DDR1_SB_DQ28
DDR1_SB_DQ29
DDR1_SB_DQ30
DDR1_SB_DQ31
DDR1_SB_CS_N0
DDR1_SB_CS_N1
DDR1_SB_CS_N2
DDR1_SB_CS_N3
DDR1_SB_CA0
DDR1_SB_CA1
DDR1_SB_CA2
DDR1_SB_CA3
DDR1_SB_CA4
DDR1_SB_CA5
DDR1_SB_CA6
DDR1_SA_PAR
DDR1_SA_ECC0
DDR1_SA_ECC1
DDR1_SA_ECC2
DDR1_SA_ECC3
DDR1_SA_ECC4
DDR1_SA_ECC5
DDR1_SA_ECC6
DDR1_SA_ECC7
DDR1_SA_DQS_DP0
DDR1_SA_DQS_DP1
DDR1_SA_DQS_DP2
DDR1_SA_DQS_DP3
DDR1_SA_DQS_DP4
DDR1_SA_DQS_DP5
DDR1_SA_DQS_DP6
DDR1_SA_DQS_DP7
DDR1_SA_DQS_DP8
DDR1_SA_DQS_DP9
DDR1_SA_DQS_DN0
DDR1_SA_DQS_DN1
DDR1_SA_DQS_DN2
DDR1_SA_DQS_DN3
DDR1_SA_DQS_DN4
DDR1_SA_DQS_DN5
DDR1_SA_DQS_DN6
DDR1_SA_DQS_DN7
DDR1_SA_DQS_DN8
DDR1_SA_DQS_DN9
DDR1_SA_DQ0
DDR1_SA_DQ1
DDR1_SA_DQ2
DDR1_SA_DQ3
DDR1_SA_DQ4
DDR1_SA_DQ5
DDR1_SA_DQ6
DDR1_SA_DQ7
DDR1_SA_DQ8
DDR1_SA_DQ9
DDR1_SA_DQ10
DDR1_SA_DQ11
DDR1_SA_DQ12
DDR1_SA_DQ13
DDR1_SA_DQ14
DDR1_SA_DQ15
DDR1_SA_DQ16
DDR1_SA_DQ17
DDR1_SA_DQ18
DDR1_SA_DQ19
DDR1_SA_DQ20
DDR1_SA_DQ21
DDR1_SA_DQ22
DDR1_SA_DQ23
DDR1_SA_DQ24
DDR1_SA_DQ25
DDR1_SA_DQ26
DDR1_SA_DQ27
DDR1_SA_DQ28
DDR1_SA_DQ29
DDR1_SA_DQ30
DDR1_SA_DQ31
DDR1_SA_CS_N0
DDR1_SA_CS_N1
DDR1_SA_CS_N2
DDR1_SA_CS_N3
DDR1_SA_CA0
DDR1_SA_CA1
DDR1_SA_CA2
DDR1_SA_CA3
DDR1_SA_CA4
DDR1_SA_CA5
DDR1_SA_CA6
DDR1_CLK_DP0
DDR1_CLK_DP1
DDR1_CLK_DN0
DDR1_CLK_DN1
DDR1_B_RSP0
DDR1_B_RSP1
DDR1_A_RSP0
DDR1_A_RSP1
DDR1_ALERT_N
SHEETDATE
DEPARTMENT
SIZE
PROJECT DOCUMENT NUMBER REV
REVIEWER
DESIGNER
123
7 3 2 1 6 5 4
E
A
B
C
E
D
C
B
A
7 6 5 4
D
IN
BI
BI
BI
BI
OUT
OUT
BI
BI
BI
BI
BI
OUT
BI
OUT
OUT
OUT
ININ
ININ
C



Fri Aug 25 14:00:08 2023N/A22 OF 312N/AV05N/AN/ASPR CPU0 - DDR CH C (10 OF 30)86 8786 878687868786 878687 86 87
86878687 86 8786 87
8687 86 878687 86 8786 8786 8786 878687 M_C_CPU0_SB_PARM_C_CPU0_SA_PARM_C_CPU0_SB_RSP<0>M_C_CPU0_SB_RSP<1>M_C_CPU0_SA_RSP<0>M_C_CPU0_SA_RSP<1>M_C_CPU0_ALERT_N
SOCKET4677_AZIF0045-P001C01CSIOSMLFM_C_CPU0_SB_DQ<31:0>M_C_CPU0_SA_DQS_DP<9:0>
M_C_CPU0_CLK_DN<1:0>M_C_CPU0_CLK_DP<1:0>M_C_CPU0_SA_CA<6:0>M_C_CPU0_SA_CS_N<3:0>
M_C_CPU0_SA_DQ<31:0>M_C_CPU0_SA_DQS_DN<9:0>M_C_CPU0_SA_CB<7:0>M_C_CPU0_SB_CA<6:0>M_C_CPU0_SB_CS_N<3:0>M_C_CPU0_SB_DQS_DN<9:0>M_C_CPU0_SB_DQS_DP<9:0>M_C_CPU0_SB_CB<7:0>
W37
Y38
U37
T38
Y53
W54
T53
U54
AA39
Y34
W35
T34
U35
W31
Y32
U31
T32
U33
AH18
AA21
AH30
AH36
AA33
AD18
U21
AD30
AD36
R33
AF18
W21
AF30
AF36
W33
AB18
R21
AB30
AB36
AJ17
AC17
AG17
AA17
AG19
AF20
AC19
AD20
W19
Y20
U19
T20
Y22
W23
T22
U23
AF28
AG29
AD28
AC29
AG31
AF32
AC31
AD32
AF34
AG35
AD34
AC35
AG37
AF38
AC37
AD38
R39
Y40
T40
W41
U41
Y47
W48
T47
AF53
AG54
AD53
AC54
AG56
AF57
AC56
AD57
AF55
AH61
W64
AF67
AA76
AB55
AD61
U64
AD67
U76
AH55
AF61
AA64
AH67
W76
AD55
AB61
R64
AB67
R76
AF59
AG60
AD59
AC60
AG62
AF63
AC62
AD63
W62
Y63
U62
T63
Y65
W66
T65
U66
AF65
AG66
AD65
AC66
AG68
AF69
AC68
AD69
W74
Y75
U74
T75
Y77
W78
T77
U78
U48
W50
U50
Y51
T51
AA52
R52
AH49
AD49
AF49
AB49
AF47
AG48
AT47
AD47
AC48
2
3
1
0
31
1
30
29
28
26
27
24
25
23
21
22
19
20
18
16
17
15
14
13
12
11
10
9
8
6
7
5
4
3
2
1
0
0
7
6
4
5
3
2
1
1
0
30
31
29
28
27
26
25
23
24
1
22
21
20
18
19
17
16
15
13
14
0
12
11
10
9
8
7
5
6
4
3
2
1
0
7
9
8
7
4
2
5
6
3
6
9
0
1
8
2
4
5
7
6
3
5
1
0
9
4
6
7
8
5
0
3
4
2
1
5
6
7
8
9
0
2
3
3
4
1
5
6
4
0
3
2
1
3
2
4
5
6
2
0
1
3
1
2
0
0
U2
10/42
DDR2_SB_PAR
DDR2_SB_ECC0
DDR2_SB_ECC1
DDR2_SB_ECC2
DDR2_SB_ECC3
DDR2_SB_ECC4
DDR2_SB_ECC5
DDR2_SB_ECC6
DDR2_SB_ECC7
DDR2_SB_DQS_DP0
DDR2_SB_DQS_DP1
DDR2_SB_DQS_DP2
DDR2_SB_DQS_DP3
DDR2_SB_DQS_DP4
DDR2_SB_DQS_DP5
DDR2_SB_DQS_DP6
DDR2_SB_DQS_DP7
DDR2_SB_DQS_DP8
DDR2_SB_DQS_DP9
DDR2_SB_DQS_DN0
DDR2_SB_DQS_DN1
DDR2_SB_DQS_DN2
DDR2_SB_DQS_DN3
DDR2_SB_DQS_DN4
DDR2_SB_DQS_DN5
DDR2_SB_DQS_DN6
DDR2_SB_DQS_DN7
DDR2_SB_DQS_DN8
DDR2_SB_DQS_DN9
DDR2_SB_DQ0
DDR2_SB_DQ1
DDR2_SB_DQ2
DDR2_SB_DQ3
DDR2_SB_DQ4
DDR2_SB_DQ5
DDR2_SB_DQ6
DDR2_SB_DQ7
DDR2_SB_DQ8
DDR2_SB_DQ9
DDR2_SB_DQ10
DDR2_SB_DQ11
DDR2_SB_DQ12
DDR2_SB_DQ13
DDR2_SB_DQ14
DDR2_SB_DQ15
DDR2_SB_DQ16
DDR2_SB_DQ17
DDR2_SB_DQ18
DDR2_SB_DQ19
DDR2_SB_DQ20
DDR2_SB_DQ21
DDR2_SB_DQ22
DDR2_SB_DQ23
DDR2_SB_DQ24
DDR2_SB_DQ25
DDR2_SB_DQ26
DDR2_SB_DQ27
DDR2_SB_DQ28
DDR2_SB_DQ29
DDR2_SB_DQ30
DDR2_SB_DQ31
DDR2_SB_CS_N0
DDR2_SB_CS_N1
DDR2_SB_CS_N2
DDR2_SB_CS_N3
DDR2_SB_CA0
DDR2_SB_CA1
DDR2_SB_CA2
DDR2_SB_CA3
DDR2_SB_CA4
DDR2_SB_CA5
DDR2_SB_CA6
DDR2_SA_PAR
DDR2_SA_ECC0
DDR2_SA_ECC1
DDR2_SA_ECC2
DDR2_SA_ECC3
DDR2_SA_ECC4
DDR2_SA_ECC5
DDR2_SA_ECC6
DDR2_SA_ECC7
DDR2_SA_DQS_DP0
DDR2_SA_DQS_DP1
DDR2_SA_DQS_DP2
DDR2_SA_DQS_DP3
DDR2_SA_DQS_DP4
DDR2_SA_DQS_DP5
DDR2_SA_DQS_DP6
DDR2_SA_DQS_DP7
DDR2_SA_DQS_DP8
DDR2_SA_DQS_DP9
DDR2_SA_DQS_DN0
DDR2_SA_DQS_DN1
DDR2_SA_DQS_DN2
DDR2_SA_DQS_DN3
DDR2_SA_DQS_DN4
DDR2_SA_DQS_DN5
DDR2_SA_DQS_DN6
DDR2_SA_DQS_DN7
DDR2_SA_DQS_DN8
DDR2_SA_DQS_DN9
DDR2_SA_DQ0
DDR2_SA_DQ1
DDR2_SA_DQ2
DDR2_SA_DQ3
DDR2_SA_DQ4
DDR2_SA_DQ5
DDR2_SA_DQ6
DDR2_SA_DQ7
DDR2_SA_DQ8
DDR2_SA_DQ9
DDR2_SA_DQ10
DDR2_SA_DQ11
DDR2_SA_DQ12
DDR2_SA_DQ13
DDR2_SA_DQ14
DDR2_SA_DQ15
DDR2_SA_DQ16
DDR2_SA_DQ17
DDR2_SA_DQ18
DDR2_SA_DQ19
DDR2_SA_DQ20
DDR2_SA_DQ21
DDR2_SA_DQ22
DDR2_SA_DQ23
DDR2_SA_DQ24
DDR2_SA_DQ25
DDR2_SA_DQ26
DDR2_SA_DQ27
DDR2_SA_DQ28
DDR2_SA_DQ29
DDR2_SA_DQ30
DDR2_SA_DQ31
DDR2_SA_CS_N0
DDR2_SA_CS_N1
DDR2_SA_CS_N2
DDR2_SA_CS_N3
DDR2_SA_CA0
DDR2_SA_CA1
DDR2_SA_CA2
DDR2_SA_CA3
DDR2_SA_CA4
DDR2_SA_CA5
DDR2_SA_CA6
DDR2_CLK_DP0
DDR2_CLK_DP1
DDR2_CLK_DN0
DDR2_CLK_DN1
DDR2_B_RSP0
DDR2_B_RSP1
DDR2_A_RSP0
DDR2_A_RSP1
DDR2_ALERT_N
SHEETDATE
DEPARTMENT
SIZE
PROJECT DOCUMENT NUMBER REV
REVIEWER
DESIGNER
123
7 3 2 1 6 5 4
E
A
B
C
E
D
C
B
A
7 6 5 4
D
IN
ININ
IN
BI
BI
BI
BI
OUT
BI
BI
BI
BI
BI
BI
OUT
OUT
OUT
OUT
IN
OUT
C



Fri Aug 25 14:00:08 2023N/A01N/AN/AN/AV0523 OF 312SPR CPU0 - DDR CH D (11 OF 30)88 8988 898889888988 89888988898889 88 8988 89
8889 88 8988 898889 88 8988 8988 8988 898889 M_D_CPU0_SB_PARM_D_CPU0_SA_PARM_D_CPU0_SB_RSP<0>M_D_CPU0_SB_RSP<1>M_D_CPU0_SA_RSP<0>M_D_CPU0_SA_RSP<1>M_D_CPU0_ALERT_N
SOCKET4677_AZIF0045-P001C01CSIOSMLFM_D_CPU0_SB_DQ<31:0>M_D_CPU0_CLK_DN<1:0>M_D_CPU0_CLK_DP<1:0>M_D_CPU0_SA_CA<6:0>M_D_CPU0_SA_CS_N<3:0>
M_D_CPU0_SA_DQ<31:0>M_D_CPU0_SA_DQS_DN<9:0>M_D_CPU0_SA_DQS_DP<9:0>M_D_CPU0_SA_CB<7:0>M_D_CPU0_SB_CA<6:0>M_D_CPU0_SB_CS_N<3:0>M_D_CPU0_SB_DQS_DN<9:0>M_D_CPU0_SB_DQS_DP<9:0>M_D_CPU0_SB_CB<7:0>
AD40
AF40
AG41
AC41
AP53
AN54
AK53
AL54
AH42
AP40
AN41
AK40
AL41
AN37
AP38
AL37
AK38
AL39
AR21
AH24
AR27
AR33
AN39
AL21
AD24
AL27
AL33
AJ39
AN21
AF24
AN27
AN33
AR39
AJ21
AB24
AJ27
AJ33
AN19
AP20
AL19
AK20
AP22
AN23
AK22
AL23
AF22
AG23
AD22
AC23
AG25
AF26
AC25
AD26
AN25
AP26
AL25
AK26
AP28
AN29
AK28
AL29
AN31
AP32
AL31
AK32
AP34
AN35
AK34
AL35
AB42
AG43
AC43
AF44
AD44
AL43
AK44
AP44
AN56
AP57
AL56
AK57
AP59
AN60
AK59
AL60
AR58
AR64
AR70
AR76
AF73
AL58
AL64
AL70
AL76
AD73
AN58
AN64
AN70
AN76
AH73
AJ58
AJ64
AJ70
AJ76
AB73
AN62
AP63
AL62
AK63
AP65
AN66
AK65
AL66
AN68
AP69
AL68
AK69
AP71
AN72
AK71
AL72
AN74
AP75
AL74
AK75
AP77
AN78
AK77
AL78
AF71
AG72
AD71
AC72
AG74
AF75
AC74
AD75
AN43
AN50
AL50
AP51
AK51
AR52
AJ52
AR45
AL45
AN45
AJ45
AG50
AF51
AV47
AC50
AD51
2
1
0
31
2
30
29
28
26
27
25
23
24
22
21
3
20
19
18
17
16
15
14
13
12
11
1
10
9
8
7
6
5
4
3
2
1
1
0
7
6
5
4
3
2
1
0
0
30
31
29
28
27
26
25
24
23
22
0
21
20
19
18
17
16
15
14
13
12
0
11
10
9
8
7
6
5
4
3
2
1
0
7
9
8
7
6
4
5
2
3
1
0
9
8
7
4
5
6
2
3
0
1
9
6
8
7
4
5
3
1
2
6
0
9
7
8
5
6
4
2
3
1
4
0
6
4
3
5
0
1
2
6
5
5
3
4
2
1
0
2
3
0
1
3
1
U2
11/42
DDR3_SB_PAR
DDR3_SB_ECC0
DDR3_SB_ECC1
DDR3_SB_ECC2
DDR3_SB_ECC3
DDR3_SB_ECC4
DDR3_SB_ECC5
DDR3_SB_ECC6
DDR3_SB_ECC7
DDR3_SB_DQS_DP0
DDR3_SB_DQS_DP1
DDR3_SB_DQS_DP2
DDR3_SB_DQS_DP3
DDR3_SB_DQS_DP4
DDR3_SB_DQS_DP5
DDR3_SB_DQS_DP6
DDR3_SB_DQS_DP7
DDR3_SB_DQS_DP8
DDR3_SB_DQS_DP9
DDR3_SB_DQS_DN0
DDR3_SB_DQS_DN1
DDR3_SB_DQS_DN2
DDR3_SB_DQS_DN3
DDR3_SB_DQS_DN4
DDR3_SB_DQS_DN5
DDR3_SB_DQS_DN6
DDR3_SB_DQS_DN7
DDR3_SB_DQS_DN8
DDR3_SB_DQS_DN9
DDR3_SB_DQ0
DDR3_SB_DQ1
DDR3_SB_DQ2
DDR3_SB_DQ3
DDR3_SB_DQ4
DDR3_SB_DQ5
DDR3_SB_DQ6
DDR3_SB_DQ7
DDR3_SB_DQ8
DDR3_SB_DQ9
DDR3_SB_DQ10
DDR3_SB_DQ11
DDR3_SB_DQ12
DDR3_SB_DQ13
DDR3_SB_DQ14
DDR3_SB_DQ15
DDR3_SB_DQ16
DDR3_SB_DQ17
DDR3_SB_DQ18
DDR3_SB_DQ19
DDR3_SB_DQ20
DDR3_SB_DQ21
DDR3_SB_DQ22
DDR3_SB_DQ23
DDR3_SB_DQ24
DDR3_SB_DQ25
DDR3_SB_DQ26
DDR3_SB_DQ27
DDR3_SB_DQ28
DDR3_SB_DQ29
DDR3_SB_DQ30
DDR3_SB_DQ31
DDR3_SB_CS_N0
DDR3_SB_CS_N1
DDR3_SB_CS_N2
DDR3_SB_CS_N3
DDR3_SB_CA0
DDR3_SB_CA1
DDR3_SB_CA2
DDR3_SB_CA3
DDR3_SB_CA4
DDR3_SB_CA5
DDR3_SB_CA6
DDR3_SA_PAR
DDR3_SA_ECC0
DDR3_SA_ECC1
DDR3_SA_ECC2
DDR3_SA_ECC3
DDR3_SA_ECC4
DDR3_SA_ECC5
DDR3_SA_ECC6
DDR3_SA_ECC7
DDR3_SA_DQS_DP0
DDR3_SA_DQS_DP1
DDR3_SA_DQS_DP2
DDR3_SA_DQS_DP3
DDR3_SA_DQS_DP4
DDR3_SA_DQS_DP5
DDR3_SA_DQS_DP6
DDR3_SA_DQS_DP7
DDR3_SA_DQS_DP8
DDR3_SA_DQS_DP9
DDR3_SA_DQS_DN0
DDR3_SA_DQS_DN1
DDR3_SA_DQS_DN2
DDR3_SA_DQS_DN3
DDR3_SA_DQS_DN4
DDR3_SA_DQS_DN5
DDR3_SA_DQS_DN6
DDR3_SA_DQS_DN7
DDR3_SA_DQS_DN8
DDR3_SA_DQS_DN9
DDR3_SA_DQ0
DDR3_SA_DQ1
DDR3_SA_DQ2
DDR3_SA_DQ3
DDR3_SA_DQ4
DDR3_SA_DQ5
DDR3_SA_DQ6
DDR3_SA_DQ7
DDR3_SA_DQ8
DDR3_SA_DQ9
DDR3_SA_DQ10
DDR3_SA_DQ11
DDR3_SA_DQ12
DDR3_SA_DQ13
DDR3_SA_DQ14
DDR3_SA_DQ15
DDR3_SA_DQ16
DDR3_SA_DQ17
DDR3_SA_DQ18
DDR3_SA_DQ19
DDR3_SA_DQ20
DDR3_SA_DQ21
DDR3_SA_DQ22
DDR3_SA_DQ23
DDR3_SA_DQ24
DDR3_SA_DQ25
DDR3_SA_DQ26
DDR3_SA_DQ27
DDR3_SA_DQ28
DDR3_SA_DQ29
DDR3_SA_DQ30
DDR3_SA_DQ31
DDR3_SA_CS_N0
DDR3_SA_CS_N1
DDR3_SA_CS_N2
DDR3_SA_CS_N3
DDR3_SA_CA0
DDR3_SA_CA1
DDR3_SA_CA2
DDR3_SA_CA3
DDR3_SA_CA4
DDR3_SA_CA5
DDR3_SA_CA6
DDR3_CLK_DP0
DDR3_CLK_DP1
DDR3_CLK_DN0
DDR3_CLK_DN1
DDR3_B_RSP0
DDR3_B_RSP1
DDR3_A_RSP0
DDR3_A_RSP1
DDR3_ALERT_N
SHEETDATE
DEPARTMENT
SIZE
PROJECT DOCUMENT NUMBER REV
REVIEWER
DESIGNER
123
7 3 2 1 6 5 4
E
A
B
C
E
D
C
B
A
7 6 5 4
D
ININ
ININ
IN
BI
OUT
BI
BI
BI
BI
BI
BI
OUT
OUT
OUT
BI
OUT
BI
BI
OUT
C



Fri Aug 25 14:00:09 2023N/A01N/AN/AN/AV0524 OF 312SPR CPU0 - DDR CH E (12 OF 30)90919091909190919091909190919091 90919091
9091 909190919091 90919091909190919091 M_E_CPU0_SB_PARM_E_CPU0_SA_PARM_E_CPU0_SB_RSP<0>M_E_CPU0_SB_RSP<1>M_E_CPU0_SA_RSP<0>M_E_CPU0_SA_RSP<1>M_E_CPU0_ALERT_N
SOCKET4677_AZIF0045-P001C01CSIOSMLFM_E_CPU0_SB_DQ<31:0>M_E_CPU0_CLK_DN<1:0>M_E_CPU0_CLK_DP<1:0>M_E_CPU0_SA_CA<6:0>M_E_CPU0_SA_CS_N<3:0>
M_E_CPU0_SA_DQ<31:0>M_E_CPU0_SA_DQS_DN<9:0>M_E_CPU0_SA_DQS_DP<9:0>M_E_CPU0_SA_CB<7:0>M_E_CPU0_SB_CA<6:0>M_E_CPU0_SB_CS_N<3:0>M_E_CPU0_SB_DQS_DN<9:0>M_E_CPU0_SB_DQS_DP<9:0>M_E_CPU0_SB_CB<7:0>
EL41
EM40
ET40
EP40
EL50
EM51
ET51
EP51
EP42
ER37
EP38
EL37
EM38
EP34
ER35
EM34
EL35
EM36
EP18
EP24
EP30
EG27
EP36
EM18
EM24
EM30
EC27
EK36
ET18
ET24
ET30
EJ27
ET36
EK18
EK24
EK30
EE27
EP16
ER17
EM16
EL17
ER19
EP20
EL19
EM20
EP22
ER23
EM22
EL23
ER25
EP26
EL25
EM26
EP28
ER29
EM28
EL29
ER31
EP32
EL31
EM32
EG25
EH26
EE25
ED26
EH28
EG29
ED28
EE29
EK42
ET42
EL43
EP44
EM44
EH44
EG43
EE43
EP53
ER54
EM53
EL54
ER56
EP57
EL56
EM57
EP55
EP61
EM67
EG70
EN74
EK55
EM61
EL68
EE70
EN76
ET55
ET61
EN68
EJ70
EM75
EM55
EK61
EK67
EC70
EP75
EP59
ER60
EM59
EL60
ER62
EP63
EL62
EM63
EP65
EL66
EM65
ER66
ER68
EN70
EM69
EM71
EG68
EH69
EE68
ED69
EH71
EG72
ED71
EE72
ER72
EP73
EK73
EL74
ER76
EP79
EM77
EL78
ED44
EP47
EM47
EL48
EK49
ET49
EP49
EC45
EG45
EE45
EJ45
DG43
DF44
CY47
DC43
DD44
21
20
21
22
0
1
2
31
30
28
29
27
25
26
24
23
22
1
18
19
17
15
16
14
12
13
10
0
11
9
7
8
5
6
4
2
3
1
0
0
7
5
6
2
3
4
0
1
1
31
29
30
27
28
26
24
25
1
23
19
20
17
18
16
14
15
13
0
11
12
9
10
8
6
7
4
5
3
1
2
0
7
8
9
6
7
3
5
4
1
2
6
9
0
7
8
6
5
4
1
3
2
5
0
8
9
7
6
3
5
4
2
1
4
9
0
6
8
7
4
5
1
3
2
3
0
5
6
3
4
2
1
0
5
6
2
2
4
3
0
1
3
2
0
1
3
U2
12/42
DDR4_SB_PAR
DDR4_SB_ECC0
DDR4_SB_ECC1
DDR4_SB_ECC2
DDR4_SB_ECC3
DDR4_SB_ECC4
DDR4_SB_ECC5
DDR4_SB_ECC6
DDR4_SB_ECC7
DDR4_SB_DQS_DP0
DDR4_SB_DQS_DP1
DDR4_SB_DQS_DP2
DDR4_SB_DQS_DP3
DDR4_SB_DQS_DP4
DDR4_SB_DQS_DP5
DDR4_SB_DQS_DP6
DDR4_SB_DQS_DP7
DDR4_SB_DQS_DP8
DDR4_SB_DQS_DP9
DDR4_SB_DQS_DN0
DDR4_SB_DQS_DN1
DDR4_SB_DQS_DN2
DDR4_SB_DQS_DN3
DDR4_SB_DQS_DN4
DDR4_SB_DQS_DN5
DDR4_SB_DQS_DN6
DDR4_SB_DQS_DN7
DDR4_SB_DQS_DN8
DDR4_SB_DQS_DN9
DDR4_SB_DQ0
DDR4_SB_DQ1
DDR4_SB_DQ2
DDR4_SB_DQ3
DDR4_SB_DQ4
DDR4_SB_DQ5
DDR4_SB_DQ6
DDR4_SB_DQ7
DDR4_SB_DQ8
DDR4_SB_DQ9
DDR4_SB_DQ10
DDR4_SB_DQ11
DDR4_SB_DQ12
DDR4_SB_DQ13
DDR4_SB_DQ14
DDR4_SB_DQ15
DDR4_SB_DQ16
DDR4_SB_DQ17
DDR4_SB_DQ18
DDR4_SB_DQ19
DDR4_SB_DQ20
DDR4_SB_DQ21
DDR4_SB_DQ22
DDR4_SB_DQ23
DDR4_SB_DQ24
DDR4_SB_DQ25
DDR4_SB_DQ26
DDR4_SB_DQ27
DDR4_SB_DQ28
DDR4_SB_DQ29
DDR4_SB_DQ30
DDR4_SB_DQ31
DDR4_SB_CS_N0
DDR4_SB_CS_N1
DDR4_SB_CS_N2
DDR4_SB_CS_N3
DDR4_SB_CA0
DDR4_SB_CA1
DDR4_SB_CA2
DDR4_SB_CA3
DDR4_SB_CA4
DDR4_SB_CA5
DDR4_SB_CA6
DDR4_SA_PAR
DDR4_SA_ECC0
DDR4_SA_ECC1
DDR4_SA_ECC2
DDR4_SA_ECC3
DDR4_SA_ECC4
DDR4_SA_ECC5
DDR4_SA_ECC6
DDR4_SA_ECC7
DDR4_SA_DQS_DP0
DDR4_SA_DQS_DP1
DDR4_SA_DQS_DP2
DDR4_SA_DQS_DP3
DDR4_SA_DQS_DP4
DDR4_SA_DQS_DP5
DDR4_SA_DQS_DP6
DDR4_SA_DQS_DP7
DDR4_SA_DQS_DP8
DDR4_SA_DQS_DP9
DDR4_SA_DQS_DN0
DDR4_SA_DQS_DN1
DDR4_SA_DQS_DN2
DDR4_SA_DQS_DN3
DDR4_SA_DQS_DN4
DDR4_SA_DQS_DN5
DDR4_SA_DQS_DN6
DDR4_SA_DQS_DN7
DDR4_SA_DQS_DN8
DDR4_SA_DQS_DN9
DDR4_SA_DQ0
DDR4_SA_DQ1
DDR4_SA_DQ2
DDR4_SA_DQ3
DDR4_SA_DQ4
DDR4_SA_DQ5
DDR4_SA_DQ6
DDR4_SA_DQ7
DDR4_SA_DQ8
DDR4_SA_DQ9
DDR4_SA_DQ10
DDR4_SA_DQ11
DDR4_SA_DQ12
DDR4_SA_DQ13
DDR4_SA_DQ14
DDR4_SA_DQ15
DDR4_SA_DQ16
DDR4_SA_DQ17
DDR4_SA_DQ18
DDR4_SA_DQ19
DDR4_SA_DQ20
DDR4_SA_DQ21
DDR4_SA_DQ22
DDR4_SA_DQ23
DDR4_SA_DQ24
DDR4_SA_DQ25
DDR4_SA_DQ26
DDR4_SA_DQ27
DDR4_SA_DQ28
DDR4_SA_DQ29
DDR4_SA_DQ30
DDR4_SA_DQ31
DDR4_SA_CS_N0
DDR4_SA_CS_N1
DDR4_SA_CS_N2
DDR4_SA_CS_N3
DDR4_SA_CA0
DDR4_SA_CA1
DDR4_SA_CA2
DDR4_SA_CA3
DDR4_SA_CA4
DDR4_SA_CA5
DDR4_SA_CA6
DDR4_CLK_DP0
DDR4_CLK_DP1
DDR4_CLK_DN0
DDR4_CLK_DN1
DDR4_B_RSP0
DDR4_B_RSP1
DDR4_A_RSP0
DDR4_A_RSP1
DDR4_ALERT_N
SHEETDATE
DEPARTMENT
SIZE
PROJECT DOCUMENT NUMBER REV
REVIEWER
DESIGNER
123
7 3 2 1 6 5 4
E
A
B
C
E
D
C
B
A
7 6 5 4
D
IN
ININ
IN
IN
BI
BI
BI
OUT
BI
BI
BI
BI
BI
OUT
BI
OUT
OUT
OUT
BI
OUT
C



Fri Aug 25 14:00:10 2023N/A01N/AN/AN/AV0525 OF 312SPR CPU0 - DDR CH F (13 OF 30)92 9392 939293929392 9392 9392 9392939293 92 939293 92 9392 939293 92 939293 92 9392 939293 M_F_CPU0_SB_PARM_F_CPU0_SA_PARM_F_CPU0_SB_RSP<0>M_F_CPU0_SB_RSP<1>M_F_CPU0_SA_RSP<0>M_F_CPU0_SA_RSP<1>M_F_CPU0_ALERT_N
SOCKET4677_AZIF0045-P001C01CSIOSMLF
M_F_CPU0_SB_CS_N<3:0>M_F_CPU0_SA_CS_N<3:0>M_F_CPU0_CLK_DN<1:0>M_F_CPU0_CLK_DP<1:0>M_F_CPU0_SA_CA<6:0>M_F_CPU0_SA_DQ<31:0>M_F_CPU0_SA_DQS_DN<9:0>M_F_CPU0_SA_DQS_DP<9:0>M_F_CPU0_SA_CB<7:0>M_F_CPU0_SB_CA<6:0>M_F_CPU0_SB_DQ<31:0>M_F_CPU0_SB_DQS_DN<9:0>M_F_CPU0_SB_DQS_DP<9:0>M_F_CPU0_SB_CB<7:0>
EE37
ED38
EG37
EH38
ED53
EE54
EH53
EG54
EJ39
EH34
EG35
ED34
EE35
EG31
EH32
EE31
ED32
EC33
EB18
EP12
EG21
DY30
EG33
DV18
EK12
EC21
DT30
EE33
DY18
ET12
EJ21
EB30
EJ33
DT18
EM12
EE21
DV30
DR17
EC17
DU17
EA17
EA19
DY20
DU19
DV20
EP10
ER11
EM10
EL11
ER13
EP14
EL13
EM14
EG19
EH20
EE19
ED20
EH22
EG23
ED22
EE23
DY28
EA29
DV28
DU29
EA31
DY32
DU31
DV32
EC39
EH40
ED40
EG41
EE41
DU50
DV51
EA50
EG56
EH57
EE56
ED57
EH59
EG60
ED59
EE60
EG58
DY55
EG64
DY67
EG76
EC58
DT55
EE64
DV67
EC76
EJ58
EB55
EJ64
EB67
EJ76
EE58
DV55
EC64
DT67
EE76
DY53
EA54
DV53
DU54
EA56
DY57
DU56
DV57
EG62
EH63
EE62
ED63
EH65
EG66
ED65
EE66
DY65
EA66
DV65
DU66
EA68
DY69
DU68
DV69
EG74
EH75
EE74
ED75
EG78
ED77
EH77
EB77
DY51
EG50
EE50
EH51
ED51
EJ52
EC52
DT49
EB49
DV49
DY49
DK47
DL48
CW48
DP47
DN48
6
8
0
3
1
2
0
31
30
29
28
26
27
25
23
24
21
22
20
19
18
16
17
15
13
14
12
11
10
9
7
6
5
3
4
2
0
1
1
6
7
5
4
3
1
0
2
0
30
31
29
28
27
25
26
24
23
22
0
20
21
19
18
17
15
16
14
12
13
1
11
10
9
7
8
6
5
4
2
3
1
7
0
8
9
7
6
3
5
5
4
2
1
9
8
7
0
6
5
6
4
2
3
9
0
1
8
7
6
4
4
5
3
2
0
1
4
5
6
7
8
2
9
1
3
3
0
2
5
6
4
3
0
1
2
0
5
3
4
1
0
2
3
2
1
1
U2
13/42
DDR5_SB_PAR
DDR5_SB_ECC0
DDR5_SB_ECC1
DDR5_SB_ECC2
DDR5_SB_ECC3
DDR5_SB_ECC4
DDR5_SB_ECC5
DDR5_SB_ECC6
DDR5_SB_ECC7
DDR5_SB_DQS_DP0
DDR5_SB_DQS_DP1
DDR5_SB_DQS_DP2
DDR5_SB_DQS_DP3
DDR5_SB_DQS_DP4
DDR5_SB_DQS_DP5
DDR5_SB_DQS_DP6
DDR5_SB_DQS_DP7
DDR5_SB_DQS_DP8
DDR5_SB_DQS_DP9
DDR5_SB_DQS_DN0
DDR5_SB_DQS_DN1
DDR5_SB_DQS_DN2
DDR5_SB_DQS_DN3
DDR5_SB_DQS_DN4
DDR5_SB_DQS_DN5
DDR5_SB_DQS_DN6
DDR5_SB_DQS_DN7
DDR5_SB_DQS_DN8
DDR5_SB_DQS_DN9
DDR5_SB_DQ0
DDR5_SB_DQ1
DDR5_SB_DQ2
DDR5_SB_DQ3
DDR5_SB_DQ4
DDR5_SB_DQ5
DDR5_SB_DQ6
DDR5_SB_DQ7
DDR5_SB_DQ8
DDR5_SB_DQ9
DDR5_SB_DQ10
DDR5_SB_DQ11
DDR5_SB_DQ12
DDR5_SB_DQ13
DDR5_SB_DQ14
DDR5_SB_DQ15
DDR5_SB_DQ16
DDR5_SB_DQ17
DDR5_SB_DQ18
DDR5_SB_DQ19
DDR5_SB_DQ20
DDR5_SB_DQ21
DDR5_SB_DQ22
DDR5_SB_DQ23
DDR5_SB_DQ24
DDR5_SB_DQ25
DDR5_SB_DQ26
DDR5_SB_DQ27
DDR5_SB_DQ28
DDR5_SB_DQ29
DDR5_SB_DQ30
DDR5_SB_DQ31
DDR5_SB_CS_N0
DDR5_SB_CS_N1
DDR5_SB_CS_N2
DDR5_SB_CS_N3
DDR5_SB_CA0
DDR5_SB_CA1
DDR5_SB_CA2
DDR5_SB_CA3
DDR5_SB_CA4
DDR5_SB_CA5
DDR5_SB_CA6
DDR5_SA_PAR
DDR5_SA_ECC0
DDR5_SA_ECC1
DDR5_SA_ECC2
DDR5_SA_ECC3
DDR5_SA_ECC4
DDR5_SA_ECC5
DDR5_SA_ECC6
DDR5_SA_ECC7
DDR5_SA_DQS_DP0
DDR5_SA_DQS_DP1
DDR5_SA_DQS_DP2
DDR5_SA_DQS_DP3
DDR5_SA_DQS_DP4
DDR5_SA_DQS_DP5
DDR5_SA_DQS_DP6
DDR5_SA_DQS_DP7
DDR5_SA_DQS_DP8
DDR5_SA_DQS_DP9
DDR5_SA_DQS_DN0
DDR5_SA_DQS_DN1
DDR5_SA_DQS_DN2
DDR5_SA_DQS_DN3
DDR5_SA_DQS_DN4
DDR5_SA_DQS_DN5
DDR5_SA_DQS_DN6
DDR5_SA_DQS_DN7
DDR5_SA_DQS_DN8
DDR5_SA_DQS_DN9
DDR5_SA_DQ0
DDR5_SA_DQ1
DDR5_SA_DQ2
DDR5_SA_DQ3
DDR5_SA_DQ4
DDR5_SA_DQ5
DDR5_SA_DQ6
DDR5_SA_DQ7
DDR5_SA_DQ8
DDR5_SA_DQ9
DDR5_SA_DQ10
DDR5_SA_DQ11
DDR5_SA_DQ12
DDR5_SA_DQ13
DDR5_SA_DQ14
DDR5_SA_DQ15
DDR5_SA_DQ16
DDR5_SA_DQ17
DDR5_SA_DQ18
DDR5_SA_DQ19
DDR5_SA_DQ20
DDR5_SA_DQ21
DDR5_SA_DQ22
DDR5_SA_DQ23
DDR5_SA_DQ24
DDR5_SA_DQ25
DDR5_SA_DQ26
DDR5_SA_DQ27
DDR5_SA_DQ28
DDR5_SA_DQ29
DDR5_SA_DQ30
DDR5_SA_DQ31
DDR5_SA_CS_N0
DDR5_SA_CS_N1
DDR5_SA_CS_N2
DDR5_SA_CS_N3
DDR5_SA_CA0
DDR5_SA_CA1
DDR5_SA_CA2
DDR5_SA_CA3
DDR5_SA_CA4
DDR5_SA_CA5
DDR5_SA_CA6
DDR5_CLK_DP0
DDR5_CLK_DP1
DDR5_CLK_DN0
DDR5_CLK_DN1
DDR5_B_RSP0
DDR5_B_RSP1
DDR5_A_RSP0
DDR5_A_RSP1
DDR5_ALERT_N
SHEETDATE
DEPARTMENT
SIZE
PROJECT DOCUMENT NUMBER REV
REVIEWER
DESIGNER
123
7 3 2 1 6 5 4
E
A
B
C
E
D
C
B
A
7 6 5 4
D
ININ
IN
BI
BI
BI
BI
OUT
BI
BI
BI
BI
BI
OUT
BI
OUT
OUT
OUT
ININ
OUT
C



Fri Aug 25 14:00:11 2023N/A01N/AN/AN/AV0526 OF 312SPR CPU0 - DDR CH G (14 OF 30)94 9594 959495949594 95949594959495 94 9594 95
9495 94 9594 959495 94 9594 9594 9594 959495 M_G_CPU0_SB_PARM_G_CPU0_SA_PARM_G_CPU0_SB_RSP<0>M_G_CPU0_SB_RSP<1>M_G_CPU0_SA_RSP<0>M_G_CPU0_SA_RSP<1>M_G_CPU0_ALERT_N
SOCKET4677_AZIF0045-P001C01CSIOSMLFM_G_CPU0_SB_DQ<31:0>M_G_CPU0_CLK_DN<1:0>M_G_CPU0_CLK_DP<1:0>M_G_CPU0_SA_CA<6:0>M_G_CPU0_SA_CS_N<3:0>
M_G_CPU0_SA_DQ<31:0>M_G_CPU0_SA_DQS_DN<9:0>M_G_CPU0_SA_DQS_DP<9:0>M_G_CPU0_SA_CB<7:0>M_G_CPU0_SB_CA<6:0>M_G_CPU0_SB_CS_N<3:0>M_G_CPU0_SB_DQS_DN<9:0>M_G_CPU0_SB_DQS_DP<9:0>M_G_CPU0_SB_CB<7:0>
DV40
DU41
DY40
EA41
DK53
DL54
DP53
DN54
EB42
EA37
DY38
DU37
DV38
DY34
EA35
DV34
DU35
DT36
EN5
DY24
DR27
DN33
DY36
EN7
DT24
DL27
DL33
DV36
EM6
EB24
DN27
DR33
EB36
EP6
DV24
DJ27
DJ33
EM4
EP4
EJ5
EK6
ET8
EP8
EH8
EK8
DY22
EA23
DV22
DU23
EA25
DY26
DU25
DV26
DN25
DP26
DL25
DK26
DP28
DL29
DK28
DN29
DN31
DP32
DL31
DK32
DP34
DN35
DK34
DL35
DT42
EA43
DU43
DY44
DV44
DP44
DN43
DL43
DN56
DP57
DL56
DK57
DP59
DN60
DK59
DL60
DN58
DN64
DY61
DN70
DY73
DJ58
DJ64
DV61
DL70
DT73
DR58
DR64
EB61
DR70
EB73
DL58
DL64
DT61
DJ70
DV73
DN62
DP63
DL62
DK63
DP65
DN66
DK65
DL66
DY59
EA60
DV59
DU60
EA62
DY63
DU62
DV63
DN68
DP69
DL68
DK69
DP71
DN72
DK71
DL72
DY71
EA72
DV71
DU72
EA74
DY75
DU74
DV75
DK44
DN50
DL50
DP51
DK51
DR52
DJ52
DJ45
DN45
DL45
DR45
DV47
DU48
CW50
DY47
EA48
31
9
1
3
0
2
30
29
28
26
27
25
23
24
21
22
1
18
20
19
17
16
15
13
14
12
11
0
10
8
6
7
5
3
4
2
0
0
1
6
7
3
5
4
0
1
1
2
30
31
29
28
27
26
25
24
23
0
22
20
21
17
19
18
16
15
14
12
1
13
11
10
9
7
8
5
6
4
2
3
1
7
0
9
7
8
6
5
4
2
3
1
5
0
8
9
7
6
5
3
2
4
0
6
1
7
9
8
5
4
6
3
2
1
3
0
7
8
9
5
6
4
3
2
1
4
0
6
4
5
3
1
2
0
6
4
3
5
1
2
0
3
0
2
1
2
U2
14/42
DDR6_SB_PAR
DDR6_SB_ECC0
DDR6_SB_ECC1
DDR6_SB_ECC2
DDR6_SB_ECC3
DDR6_SB_ECC4
DDR6_SB_ECC5
DDR6_SB_ECC6
DDR6_SB_ECC7
DDR6_SB_DQS_DP0
DDR6_SB_DQS_DP1
DDR6_SB_DQS_DP2
DDR6_SB_DQS_DP3
DDR6_SB_DQS_DP4
DDR6_SB_DQS_DP5
DDR6_SB_DQS_DP6
DDR6_SB_DQS_DP7
DDR6_SB_DQS_DP8
DDR6_SB_DQS_DP9
DDR6_SB_DQS_DN0
DDR6_SB_DQS_DN1
DDR6_SB_DQS_DN2
DDR6_SB_DQS_DN3
DDR6_SB_DQS_DN4
DDR6_SB_DQS_DN5
DDR6_SB_DQS_DN6
DDR6_SB_DQS_DN7
DDR6_SB_DQS_DN8
DDR6_SB_DQS_DN9
DDR6_SB_DQ0
DDR6_SB_DQ1
DDR6_SB_DQ2
DDR6_SB_DQ3
DDR6_SB_DQ4
DDR6_SB_DQ5
DDR6_SB_DQ6
DDR6_SB_DQ7
DDR6_SB_DQ8
DDR6_SB_DQ9
DDR6_SB_DQ10
DDR6_SB_DQ11
DDR6_SB_DQ12
DDR6_SB_DQ13
DDR6_SB_DQ14
DDR6_SB_DQ15
DDR6_SB_DQ16
DDR6_SB_DQ17
DDR6_SB_DQ18
DDR6_SB_DQ19
DDR6_SB_DQ20
DDR6_SB_DQ21
DDR6_SB_DQ22
DDR6_SB_DQ23
DDR6_SB_DQ24
DDR6_SB_DQ25
DDR6_SB_DQ26
DDR6_SB_DQ27
DDR6_SB_DQ28
DDR6_SB_DQ29
DDR6_SB_DQ30
DDR6_SB_DQ31
DDR6_SB_CS_N0
DDR6_SB_CS_N1
DDR6_SB_CS_N2
DDR6_SB_CS_N3
DDR6_SB_CA0
DDR6_SB_CA1
DDR6_SB_CA2
DDR6_SB_CA3
DDR6_SB_CA4
DDR6_SB_CA5
DDR6_SB_CA6
DDR6_SA_PAR
DDR6_SA_ECC0
DDR6_SA_ECC1
DDR6_SA_ECC2
DDR6_SA_ECC3
DDR6_SA_ECC4
DDR6_SA_ECC5
DDR6_SA_ECC6
DDR6_SA_ECC7
DDR6_SA_DQS_DP0
DDR6_SA_DQS_DP1
DDR6_SA_DQS_DP2
DDR6_SA_DQS_DP3
DDR6_SA_DQS_DP4
DDR6_SA_DQS_DP5
DDR6_SA_DQS_DP6
DDR6_SA_DQS_DP7
DDR6_SA_DQS_DP8
DDR6_SA_DQS_DP9
DDR6_SA_DQS_DN0
DDR6_SA_DQS_DN1
DDR6_SA_DQS_DN2
DDR6_SA_DQS_DN3
DDR6_SA_DQS_DN4
DDR6_SA_DQS_DN5
DDR6_SA_DQS_DN6
DDR6_SA_DQS_DN7
DDR6_SA_DQS_DN8
DDR6_SA_DQS_DN9
DDR6_SA_DQ0
DDR6_SA_DQ1
DDR6_SA_DQ2
DDR6_SA_DQ3
DDR6_SA_DQ4
DDR6_SA_DQ5
DDR6_SA_DQ6
DDR6_SA_DQ7
DDR6_SA_DQ8
DDR6_SA_DQ9
DDR6_SA_DQ10
DDR6_SA_DQ11
DDR6_SA_DQ12
DDR6_SA_DQ13
DDR6_SA_DQ14
DDR6_SA_DQ15
DDR6_SA_DQ16
DDR6_SA_DQ17
DDR6_SA_DQ18
DDR6_SA_DQ19
DDR6_SA_DQ20
DDR6_SA_DQ21
DDR6_SA_DQ22
DDR6_SA_DQ23
DDR6_SA_DQ24
DDR6_SA_DQ25
DDR6_SA_DQ26
DDR6_SA_DQ27
DDR6_SA_DQ28
DDR6_SA_DQ29
DDR6_SA_DQ30
DDR6_SA_DQ31
DDR6_SA_CS_N0
DDR6_SA_CS_N1
DDR6_SA_CS_N2
DDR6_SA_CS_N3
DDR6_SA_CA0
DDR6_SA_CA1
DDR6_SA_CA2
DDR6_SA_CA3
DDR6_SA_CA4
DDR6_SA_CA5
DDR6_SA_CA6
DDR6_CLK_DP0
DDR6_CLK_DP1
DDR6_CLK_DN0
DDR6_CLK_DN1
DDR6_B_RSP0
DDR6_B_RSP1
DDR6_A_RSP0
DDR6_A_RSP1
DDR6_ALERT_N
SHEETDATE
DEPARTMENT
SIZE
PROJECT DOCUMENT NUMBER REV
REVIEWER
DESIGNER
123
7 3 2 1 6 5 4
E
A
B
C
E
D
C
B
A
7 6 5 4
D
ININ
ININ
IN
BI
BI
OUT
BI
BI
BI
BI
BI
OUT
BI
OUT
OUT
OUT
BI
BI
OUT
C



Fri Aug 25 14:00:12 2023N/AN/AN/AN/AV0527 OF 312SPR CPU0 - DDR CH H (15 OF 30)96 9796 979697969796 97969796979697 96 9796 97
9697 96 9796 979697 96 9796 9796 9796 979697 M_H_CPU0_SB_PARM_H_CPU0_SA_PARM_H_CPU0_SB_RSP<0>M_H_CPU0_SB_RSP<1>M_H_CPU0_SA_RSP<0>M_H_CPU0_SA_RSP<1>M_H_CPU0_ALERT_N
SOCKET4677_AZIF0045-P001C01CSIOSMLFM_H_CPU0_SB_DQ<31:0>M_H_CPU0_CLK_DN<1:0>M_H_CPU0_CLK_DP<1:0>M_H_CPU0_SA_CA<6:0>M_H_CPU0_SA_CS_N<3:0>
M_H_CPU0_SA_DQ<31:0>M_H_CPU0_SA_DQS_DN<9:0>M_H_CPU0_SA_DQS_DP<9:0>M_H_CPU0_SA_CB<7:0>M_H_CPU0_SB_CA<6:0>M_H_CPU0_SB_CS_N<3:0>M_H_CPU0_SB_DQS_DN<9:0>M_H_CPU0_SB_DQS_DP<9:0>M_H_CPU0_SB_CB<7:0>
DP38
DK38
DN37
DL37
DC50
DD51
DG50
DF51
DR39
DC37
DD38
DG37
DF38
DF34
DG35
DD34
DC35
DB36
DH18
DN21
DF24
DF30
DF36
DD18
DJ21
DB24
DB30
DD36
DF18
DR21
DH24
DH30
DH36
DB18
DL21
DD24
DD30
DC17
DJ17
DA17
DG17
DG19
DF20
DC19
DD20
DN19
DP20
DL19
DK20
DP22
DN23
DK22
DL23
DF22
DG23
DD22
DC23
DG25
DF26
DC25
DD26
DD28
DG29
DF28
DC29
DG31
DF32
DC31
DD32
DJ39
DP40
DK40
DN41
DL41
DG41
DF40
DD40
DF53
DG54
DD53
DC54
DG56
DF57
DC56
DD57
DF55
DF61
DF67
DF73
DN76
DB55
DB61
DB67
DD73
DL76
DH55
DH61
DH67
DH73
DR76
DD55
DD61
DD67
DB73
DJ76
DF59
DG60
DD59
DC60
DG62
DF63
DC62
DD63
DF65
DG66
DD65
DC66
DG68
DF69
DC68
DD69
DF71
DG72
DD71
DC72
DG74
DF75
DC74
DD75
DN74
DP75
DL74
DK75
DP77
DW78
DT77
DY79
DC41
DF47
DD47
DG48
DC48
DH49
DB49
DB42
DF42
DD42
DH42
ED47
EE48
CY51
EH47
EG48
14
1
3
0
31
2
30
29
28
26
27
25
23
24
21
22
1
18
20
19
17
16
15
13
12
11
0
10
8
9
6
7
5
3
4
2
0
0
1
6
7
3
5
4
0
1
1
2
30
31
29
28
27
26
25
24
23
0
22
20
21
17
19
18
16
15
14
12
1
13
11
10
9
7
8
5
6
4
2
3
1
7
0
9
7
8
6
5
4
2
3
1
5
0
8
9
7
6
5
3
2
4
0
6
1
7
9
8
5
4
6
3
2
1
3
0
7
8
9
5
6
4
3
2
1
4
0
6
4
5
3
1
2
0
6
4
3
5
1
2
0
3
0
2
1
2
U2
15/42
DDR7_SB_PAR
DDR7_SB_ECC0
DDR7_SB_ECC1
DDR7_SB_ECC2
DDR7_SB_ECC3
DDR7_SB_ECC4
DDR7_SB_ECC5
DDR7_SB_ECC6
DDR7_SB_ECC7
DDR7_SB_DQS_DP0
DDR7_SB_DQS_DP1
DDR7_SB_DQS_DP2
DDR7_SB_DQS_DP3
DDR7_SB_DQS_DP4
DDR7_SB_DQS_DP5
DDR7_SB_DQS_DP6
DDR7_SB_DQS_DP7
DDR7_SB_DQS_DP8
DDR7_SB_DQS_DP9
DDR7_SB_DQS_DN0
DDR7_SB_DQS_DN1
DDR7_SB_DQS_DN2
DDR7_SB_DQS_DN3
DDR7_SB_DQS_DN4
DDR7_SB_DQS_DN5
DDR7_SB_DQS_DN6
DDR7_SB_DQS_DN7
DDR7_SB_DQS_DN8
DDR7_SB_DQS_DN9
DDR7_SB_DQ0
DDR7_SB_DQ1
DDR7_SB_DQ2
DDR7_SB_DQ3
DDR7_SB_DQ4
DDR7_SB_DQ5
DDR7_SB_DQ6
DDR7_SB_DQ7
DDR7_SB_DQ8
DDR7_SB_DQ9
DDR7_SB_DQ10
DDR7_SB_DQ11
DDR7_SB_DQ12
DDR7_SB_DQ13
DDR7_SB_DQ14
DDR7_SB_DQ15
DDR7_SB_DQ16
DDR7_SB_DQ17
DDR7_SB_DQ18
DDR7_SB_DQ19
DDR7_SB_DQ20
DDR7_SB_DQ21
DDR7_SB_DQ22
DDR7_SB_DQ23
DDR7_SB_DQ24
DDR7_SB_DQ25
DDR7_SB_DQ26
DDR7_SB_DQ27
DDR7_SB_DQ28
DDR7_SB_DQ29
DDR7_SB_DQ30
DDR7_SB_DQ31
DDR7_SB_CS_N0
DDR7_SB_CS_N1
DDR7_SB_CS_N2
DDR7_SB_CS_N3
DDR7_SB_CA0
DDR7_SB_CA1
DDR7_SB_CA2
DDR7_SB_CA3
DDR7_SB_CA4
DDR7_SB_CA5
DDR7_SB_CA6
DDR7_SA_PAR
DDR7_SA_ECC0
DDR7_SA_ECC1
DDR7_SA_ECC2
DDR7_SA_ECC3
DDR7_SA_ECC4
DDR7_SA_ECC5
DDR7_SA_ECC6
DDR7_SA_ECC7
DDR7_SA_DQS_DP0
DDR7_SA_DQS_DP1
DDR7_SA_DQS_DP2
DDR7_SA_DQS_DP3
DDR7_SA_DQS_DP4
DDR7_SA_DQS_DP5
DDR7_SA_DQS_DP6
DDR7_SA_DQS_DP7
DDR7_SA_DQS_DP8
DDR7_SA_DQS_DP9
DDR7_SA_DQS_DN0
DDR7_SA_DQS_DN1
DDR7_SA_DQS_DN2
DDR7_SA_DQS_DN3
DDR7_SA_DQS_DN4
DDR7_SA_DQS_DN5
DDR7_SA_DQS_DN6
DDR7_SA_DQS_DN7
DDR7_SA_DQS_DN8
DDR7_SA_DQS_DN9
DDR7_SA_DQ0
DDR7_SA_DQ1
DDR7_SA_DQ2
DDR7_SA_DQ3
DDR7_SA_DQ4
DDR7_SA_DQ5
DDR7_SA_DQ6
DDR7_SA_DQ7
DDR7_SA_DQ8
DDR7_SA_DQ9
DDR7_SA_DQ10
DDR7_SA_DQ11
DDR7_SA_DQ12
DDR7_SA_DQ13
DDR7_SA_DQ14
DDR7_SA_DQ15
DDR7_SA_DQ16
DDR7_SA_DQ17
DDR7_SA_DQ18
DDR7_SA_DQ19
DDR7_SA_DQ20
DDR7_SA_DQ21
DDR7_SA_DQ22
DDR7_SA_DQ23
DDR7_SA_DQ24
DDR7_SA_DQ25
DDR7_SA_DQ26
DDR7_SA_DQ27
DDR7_SA_DQ28
DDR7_SA_DQ29
DDR7_SA_DQ30
DDR7_SA_DQ31
DDR7_SA_CS_N0
DDR7_SA_CS_N1
DDR7_SA_CS_N2
DDR7_SA_CS_N3
DDR7_SA_CA0
DDR7_SA_CA1
DDR7_SA_CA2
DDR7_SA_CA3
DDR7_SA_CA4
DDR7_SA_CA5
DDR7_SA_CA6
DDR7_CLK_DP0
DDR7_CLK_DP1
DDR7_CLK_DN0
DDR7_CLK_DN1
DDR7_B_RSP0
DDR7_B_RSP1
DDR7_A_RSP0
DDR7_A_RSP1
DDR7_ALERT_N
SHEETDATE
DEPARTMENT
SIZE
PROJECT DOCUMENT NUMBER REV
REVIEWER
DESIGNER
123
7 3 2 1 6 5 4
E
A
B
C
E
D
C
B
A
7 6 5 4
D
ININ
ININ
IN
BI
BI
OUT
BI
BI
BI
BI
BI
OUT
BI
OUT
OUT
OUT
BI
BI
OUT
C



Fri Aug 25 14:00:13 2023N/AN/AN/AN/AV0528 OF 312SPR CPU0 - DMI (16 OF 30)
178178178178SMLFIOSOCKET4677_AZIF0045-P001C01CSDMI_CPU0_PCH_RX_C_DN<7:0>DMI_CPU0_PCH_RX_C_DP<7:0>DMI_CPU0_PCH_TX_DP<7:0>DMI_CPU0_PCH_TX_DN<7:0>
CM18
CL19
CH18
CG19
CD18
CC19
BY18
CA19
CN17
CK18
CJ17
CF18
CE17
CB18
CA17
BW19
BT18
BR19
BM18
BL19
BH18
BG19
BD18
BC19
BU17
BP18
BN17
BK18
BJ17
BF18
BE17
BB18
3
3
6
6
1
3
4
5
6
1
3
4
5
6
0
7
2
1
7
2
1
0
7
0
2
7
0
2
5
4
4
5
U2
16/42
DMI_TX_DP0
DMI_TX_DP1
DMI_TX_DP2
DMI_TX_DP3
DMI_TX_DP4
DMI_TX_DP5
DMI_TX_DP6
DMI_TX_DP7
DMI_TX_DN0
DMI_TX_DN1
DMI_TX_DN2
DMI_TX_DN3
DMI_TX_DN4
DMI_TX_DN5
DMI_TX_DN6
DMI_TX_DN7
DMI_RX_DP0
DMI_RX_DP1
DMI_RX_DP2
DMI_RX_DP3
DMI_RX_DP4
DMI_RX_DP5
DMI_RX_DP6
DMI_RX_DP7
DMI_RX_DN0
DMI_RX_DN1
DMI_RX_DN2
DMI_RX_DN3
DMI_RX_DN4
DMI_RX_DN5
DMI_RX_DN6
DMI_RX_DN7
SHEETDATE
DEPARTMENT
SIZE
PROJECT DOCUMENT NUMBER REV
REVIEWER
DESIGNER
123
7 3 2 1 6 5 4
E
A
B
C
E
D
C
B
A
7 6 5 4
D
OUTOUTININ
C



20210818 MODIFY FOR GT
Fri Aug 25 14:00:14 2023N/A01N/AN/AN/AV0529 OF 312SPR CPU0 - PCIE PE0/PE1 (17 OF 30)174174138139138139153153173173SMLFIOSOCKET4677_AZIF0045-P001C01CSSMLFIOSOCKET4677_AZIF0045-P001C01CS
P5E_CPU0_PE1_TX_DN<15:0>P5E_CPU0_PE1_TX_DP<15:0>P5E_CPU0_PE0_RX_DN<15:0>P5E_CPU0_PE0_RX_DP<15:0>P5E_CPU0_PE1_RX_DP<15:0>P5E_CPU0_PE1_RX_DN<15:0>P5E_CPU0_PE0_TX_DN<15:0>P5E_CPU0_PE0_TX_DP<15:0>
BD14
BG15
BH14
BL15
BM14
BR15
BT14
BW15
BY14
CC15
CD14
CG15
CH14
CL15
CM14
CR15
BE13
BF14
BJ13
BK14
BN13
BP14
BU13
BV14
CA13
CB14
CE13
CF14
CJ13
CK14
CN13
CP14
BD10
BE9
BH10
BJ9
BM10
BN9
BT10
BU9
BY10
CA9
CD10
CE9
CH10
CJ9
CM10
CN9
BC11
BF10
BG11
BK10
BL11
BP10
BR11
BV10
BW11
CB10
CC11
CF10
CG11
CK10
CL11
CP10
BC15
AY14
AW15
AT14
AR15
AM14
AL15
AH14
AG15
AD14
AC15
Y14
W15
T14
R15
M14
BB14
BA13
AV14
AU13
AP14
AN13
AK14
AJ13
AF14
AE13
AB14
AA13
V14
U13
P14
N13
AY10
AW11
AT10
AR11
AN9
AL11
AH10
AG11
AD10
AC11
Y10
W11
U9
R11
N9
L11
BA9
AV10
AU9
AP10
AM10
AK10
AJ9
AF10
AE9
AB10
AA9
V10
T10
P10
M10
K10
15
14
2
0
1
3
2
4
6
5
8
7
9
10
11
12
13
14
15
0
1
2
4
3
5
6
7
9
8
10
12
11
14
13
15
0
1
3
4
5
7
6
8
9
10
11
12
14
13
15
0
1
3
2
4
5
6
8
7
9
10
11
12
13
14
15
14
13
12
11
10
9
8
7
6
5
4
3
2
1
0
14
13
12
10
11
9
8
7
5
6
4
3
2
1
0
15
2
1
0
4
5
3
6
7
8
10
9
11
12
13
14
15
0
1
2
3
6
4
5
7
8
11
9
10
13
12
15
U2
U2
17/42
PE0_TX_DP0
PE0_TX_DP1
PE0_TX_DP2
PE0_TX_DP3
PE0_TX_DP4
PE0_TX_DP5
PE0_TX_DP6
PE0_TX_DP7
PE0_TX_DP8
PE0_TX_DP9
PE0_TX_DP10
PE0_TX_DP11
PE0_TX_DP12
PE0_TX_DP13
PE0_TX_DP14
PE0_TX_DP15
PE0_TX_DN0
PE0_TX_DN1
PE0_TX_DN2
PE0_TX_DN3
PE0_TX_DN4
PE0_TX_DN5
PE0_TX_DN6
PE0_TX_DN7
PE0_TX_DN8
PE0_TX_DN9
PE0_TX_DN10
PE0_TX_DN11
PE0_TX_DN12
PE0_TX_DN13
PE0_TX_DN14
PE0_TX_DN15
PE0_RX_DP0
PE0_RX_DP1
PE0_RX_DP2
PE0_RX_DP3
PE0_RX_DP4
PE0_RX_DP5
PE0_RX_DP6
PE0_RX_DP7
PE0_RX_DP8
PE0_RX_DP9
PE0_RX_DP10
PE0_RX_DP11
PE0_RX_DP12
PE0_RX_DP13
PE0_RX_DP14
PE0_RX_DP15
PE0_RX_DN0
PE0_RX_DN1
PE0_RX_DN2
PE0_RX_DN3
PE0_RX_DN4
PE0_RX_DN5
PE0_RX_DN6
PE0_RX_DN7
PE0_RX_DN8
PE0_RX_DN9
PE0_RX_DN10
PE0_RX_DN11
PE0_RX_DN12
PE0_RX_DN13
PE0_RX_DN14
PE0_RX_DN15
18/42
PE1_TX_DP0
PE1_TX_DP1
PE1_TX_DP2
PE1_TX_DP3
PE1_TX_DP4
PE1_TX_DP5
PE1_TX_DP6
PE1_TX_DP7
PE1_TX_DP8
PE1_TX_DP9
PE1_TX_DP10
PE1_TX_DP11
PE1_TX_DP12
PE1_TX_DP13
PE1_TX_DP14
PE1_TX_DP15
PE1_TX_DN0
PE1_TX_DN1
PE1_TX_DN2
PE1_TX_DN3
PE1_TX_DN4
PE1_TX_DN5
PE1_TX_DN6
PE1_TX_DN7
PE1_TX_DN8
PE1_TX_DN9
PE1_TX_DN10
PE1_TX_DN11
PE1_TX_DN12
PE1_TX_DN13
PE1_TX_DN14
PE1_TX_DN15
PE1_RX_DP0
PE1_RX_DP1
PE1_RX_DP2
PE1_RX_DP3
PE1_RX_DP4
PE1_RX_DP5
PE1_RX_DP6
PE1_RX_DP7
PE1_RX_DP8
PE1_RX_DP9
PE1_RX_DP10
PE1_RX_DP11
PE1_RX_DP12
PE1_RX_DP13
PE1_RX_DP14
PE1_RX_DP15
PE1_RX_DN0
PE1_RX_DN1
PE1_RX_DN2
PE1_RX_DN3
PE1_RX_DN4
PE1_RX_DN5
PE1_RX_DN6
PE1_RX_DN7
PE1_RX_DN8
PE1_RX_DN9
PE1_RX_DN10
PE1_RX_DN11
PE1_RX_DN12
PE1_RX_DN13
PE1_RX_DN14
PE1_RX_DN15
SHEETDATE
DEPARTMENT
SIZE
PROJECT DOCUMENT NUMBER REV
REVIEWER
DESIGNER
123
7 3 2 1 6 5 4
E
A
B
C
E
D
C
B
A
7 6 5 4
D
OUT
OUT
OUT
OUT
IN
IN
IN
IN
C



20211126 SWAP DP/DN20210818 MODIFY FOR GT
Fri Aug 25 14:00:15 2023N/AN/AN/AN/AV0530 OF 312SPR CPU0 - PCIE PE2/PE3 (18 OF 30)174173173136137136137174136137136137
SMLFIOSOCKET4677_AZIF0045-P001C01CSSMLFIOSOCKET4677_AZIF0045-P001C01CSP5E_CPU0_PE3_TX_DP<15:0>P5E_CPU0_PE2_TX_DP<15:0>P5E_CPU0_PE2_TX_DN<15:0>P5E_CPU0_PE2_RX_DP<15:0>P5E_CPU0_PE2_RX_DN<15:0>P5E_CPU0_PE3_TX_DN<15:0>P5E_CPU0_PE3_RX_DN<15:0>P5E_CPU0_PE3_RX_DP<15:0>
CR86
CU86
CW86
DA86
DC86
DE86
DG86
DJ86
DL86
DN86
DR86
DU86
DW86
EA86
EC86
ED87
CP85
CT87
CV85
CY87
DB85
DD87
DF85
DH87
DK85
DM87
DP85
DT87
DV85
DY87
EB85
EE86
CT91
CW90
CY91
DC90
DE90
DF89
DJ90
DK89
DM91
DR90
DT91
DW90
EA90
EB89
EE90
EJ90
CU90
CV89
DA90
DB89
DD91
DG90
DH91
DL90
DN90
DP89
DU90
DV89
DY91
EC90
ED91
EH89
EG15
ED14
EC15
DY14
DW15
DT14
DR15
DM14
DL15
DH14
DG15
DD14
DC15
CY14
CW15
CT14
EF14
EE13
EB14
EA13
DV14
DU13
DP14
DN13
DK14
DJ13
DF14
DE13
DB14
DA13
CV14
CU13
EG11
EF10
EC11
EB10
DW11
DV10
DR11
DP10
DL11
DK10
DG11
DF10
DC11
DB10
CW11
CV10
EH10
EE9
ED10
EA9
DY10
DU9
DT10
DN9
DM10
DJ9
DH10
DE9
DD10
DA9
CY10
CU9
13
0
10
11
0
1
2
3
4
6
5
7
8
9
10
11
13
12
15
14
1
0
2
3
4
6
5
7
8
9
10
12
11
13
14
15
0
1
3
2
4
6
5
8
7
9
10
11
12
13
14
15
2
1
3
4
5
7
6
8
12
15
9
14
10
11
13
14
8
5
15
10
11
12
13
14
12
15
0
1
2
3
4
5
6
7
8
9
0
1
2
3
4
6
7
9
0
1
2
4
12
4
5
9
10
12
13
14
5
11
15
7
8
6
3
2
1
0
13
15
14
11
9
8
10
6
7
3
U2
U2
20/42
PE3_TX_DP0
PE3_TX_DP1
PE3_TX_DP2
PE3_TX_DP3
PE3_TX_DP4
PE3_TX_DP5
PE3_TX_DP6
PE3_TX_DP7
PE3_TX_DP8
PE3_TX_DP9
PE3_TX_DP10
PE3_TX_DP11
PE3_TX_DP12
PE3_TX_DP13
PE3_TX_DP14
PE3_TX_DP15
PE3_TX_DN0
PE3_TX_DN1
PE3_TX_DN2
PE3_TX_DN3
PE3_TX_DN4
PE3_TX_DN5
PE3_TX_DN6
PE3_TX_DN7
PE3_TX_DN8
PE3_TX_DN9
PE3_TX_DN10
PE3_TX_DN11
PE3_TX_DN12
PE3_TX_DN13
PE3_TX_DN14
PE3_TX_DN15
PE3_RX_DP0
PE3_RX_DP1
PE3_RX_DP2
PE3_RX_DP3
PE3_RX_DP4
PE3_RX_DP5
PE3_RX_DP6
PE3_RX_DP7
PE3_RX_DP8
PE3_RX_DP9
PE3_RX_DP10
PE3_RX_DP11
PE3_RX_DP12
PE3_RX_DP13
PE3_RX_DP14
PE3_RX_DP15
PE3_RX_DN0
PE3_RX_DN1
PE3_RX_DN2
PE3_RX_DN3
PE3_RX_DN4
PE3_RX_DN5
PE3_RX_DN6
PE3_RX_DN7
PE3_RX_DN8
PE3_RX_DN9
PE3_RX_DN10
PE3_RX_DN11
PE3_RX_DN12
PE3_RX_DN13
PE3_RX_DN14
PE3_RX_DN15
19/42
PE2_TX_DP0
PE2_TX_DP1
PE2_TX_DP2
PE2_TX_DP3
PE2_TX_DP4
PE2_TX_DP5
PE2_TX_DP6
PE2_TX_DP7
PE2_TX_DP8
PE2_TX_DP9
PE2_TX_DP10
PE2_TX_DP11
PE2_TX_DP12
PE2_TX_DP13
PE2_TX_DP14
PE2_TX_DP15
PE2_TX_DN0
PE2_TX_DN1
PE2_TX_DN2
PE2_TX_DN3
PE2_TX_DN4
PE2_TX_DN5
PE2_TX_DN6
PE2_TX_DN7
PE2_TX_DN8
PE2_TX_DN9
PE2_TX_DN10
PE2_TX_DN11
PE2_TX_DN12
PE2_TX_DN13
PE2_TX_DN14
PE2_TX_DN15
PE2_RX_DP0
PE2_RX_DP1
PE2_RX_DP2
PE2_RX_DP3
PE2_RX_DP4
PE2_RX_DP5
PE2_RX_DP6
PE2_RX_DP7
PE2_RX_DP8
PE2_RX_DP9
PE2_RX_DP10
PE2_RX_DP11
PE2_RX_DP12
PE2_RX_DP13
PE2_RX_DP14
PE2_RX_DP15
PE2_RX_DN0
PE2_RX_DN1
PE2_RX_DN2
PE2_RX_DN3
PE2_RX_DN4
PE2_RX_DN5
PE2_RX_DN6
PE2_RX_DN7
PE2_RX_DN8
PE2_RX_DN9
PE2_RX_DN10
PE2_RX_DN11
PE2_RX_DN12
PE2_RX_DN13
PE2_RX_DN14
PE2_RX_DN15
SHEETDATE
DEPARTMENT
SIZE
PROJECT DOCUMENT NUMBER REV
REVIEWER
DESIGNER
123
7 3 2 1 6 5 4
E
A
B
C
E
D
C
B
A
7 6 5 4
D
OUT
OUT
OUT
OUT
IN
IN
IN
IN
C



20210818 MODIFY FOR GT
Fri Aug 25 14:00:16 2023N/AN/AN/AN/AV0531 OF 312SPR CPU0 - PCIE PE4 (19 OF 30)
138139138139175175SMLFIOSOCKET4677_AZIF0045-P001C01CSP5E_CPU0_PE4_RX_DN<15:0>P5E_CPU0_PE4_RX_DP<15:0>P5E_CPU0_PE4_TX_DN<15:0>P5E_CPU0_PE4_TX_DP<15:0>
BB85
AY87
AV85
AT87
AN86
AM87
AK85
AH87
AF85
AD87
AB85
Y87
V85
T87
N86
M87
BA86
AW86
AU86
AR86
AP85
AL86
AJ86
AG86
AE86
AC86
AA86
W86
U86
R86
P85
L86
BA90
AW90
AU90
AR90
AN90
AL90
AJ90
AG90
AE90
AC90
AA90
W90
U90
R90
N90
K89
BB89
AY91
AV89
AT91
AP89
AM91
AK89
AH91
AF89
AD91
AB89
Y91
V89
T91
P89
J90
15
11
9
6
15
14
13
12
10
11
8
7
5
3
4
2
1
0
15
14
13
12
10
11
8
9
7
6
4
5
3
2
1
00
1
3
2
4
5
6
8
7
9
10
11
12
13
14
15
0
1
2
3
4
5
7
9
8
10
12
13
14
6
U2
21/42
PE4_TX_DP0
PE4_TX_DP1
PE4_TX_DP2
PE4_TX_DP3
PE4_TX_DP4
PE4_TX_DP5
PE4_TX_DP6
PE4_TX_DP7
PE4_TX_DP8
PE4_TX_DP9
PE4_TX_DP10
PE4_TX_DP11
PE4_TX_DP12
PE4_TX_DP13
PE4_TX_DP14
PE4_TX_DP15
PE4_TX_DN0
PE4_TX_DN1
PE4_TX_DN2
PE4_TX_DN3
PE4_TX_DN4
PE4_TX_DN5
PE4_TX_DN6
PE4_TX_DN7
PE4_TX_DN8
PE4_TX_DN9
PE4_TX_DN10
PE4_TX_DN11
PE4_TX_DN12
PE4_TX_DN13
PE4_TX_DN14
PE4_TX_DN15
PE4_RX_DP0
PE4_RX_DP1
PE4_RX_DP2
PE4_RX_DP3
PE4_RX_DP4
PE4_RX_DP5
PE4_RX_DP6
PE4_RX_DP7
PE4_RX_DP8
PE4_RX_DP9
PE4_RX_DP10
PE4_RX_DP11
PE4_RX_DP12
PE4_RX_DP13
PE4_RX_DP14
PE4_RX_DP15
PE4_RX_DN0
PE4_RX_DN1
PE4_RX_DN2
PE4_RX_DN3
PE4_RX_DN4
PE4_RX_DN5
PE4_RX_DN6
PE4_RX_DN7
PE4_RX_DN8
PE4_RX_DN9
PE4_RX_DN10
PE4_RX_DN11
PE4_RX_DN12
PE4_RX_DN13
PE4_RX_DN14
PE4_RX_DN15
SHEETDATE
DEPARTMENT
SIZE
PROJECT DOCUMENT NUMBER REV
REVIEWER
DESIGNER
123
7 3 2 1 6 5 4
E
A
B
C
E
D
C
B
A
7 6 5 4
D
IN
IN
OUT
OUT
C



Fri Aug 25 14:00:16 2023N/AN/AN/AN/AV0532 OF 312SPR CPU0 - UPI0 (20 OF 30)
646464 64SMLFIOSOCKET4677_AZIF0045-P001C01CSUPI_CPU0_CPU1_P0P1_DP<23:0>UPI_CPU1_CPU0_P1P0_DN<23:0>UPI_CPU1_CPU0_P1P0_DP<23:0>UPI_CPU0_CPU1_P0P1_DN<23:0>DP/DN SWAP DP/DN SWAP
BU3
BN3
BL3
BJ1
BG3
BE1
BC3
BA1
AW3
AV2
AR3
AN1
AL3
AJ1
AG3
AE1
AC3
AB2
W3
V2
R3
P2
L3
J3
BT2
BR3
BM2
BK2
BH2
BF2
BD2
BB2
AY2
AU1
AT2
AP2
AM2
AK2
AH2
AF2
AD2
AA1
Y2
U1
T2
N1
M2
K4
BT6
BP6
BM6
BL7
BH6
BG7
BD6
BC7
AY6
AW7
AT6
AR7
AM6
AL7
AJ5
AG7
AD6
AC7
Y6
W7
T6
R7
M6
L7
BU5
BR7
BN5
BK6
BJ5
BF6
BE5
BB6
BA5
AV6
AU5
AP6
AN5
AK6
AH6
AF6
AE5
AB6
AA5
V6
U5
P6
N5
K6
23
20
2
1
22
2
1
0
4
6
7
8
9
23
19
18
17
16
14
10
11
9
8
22
8
9
5
3
5
3
11
10
11
10
21
23
21
14
15
16
17
18
19
20
14
15
16
17
18
19
20
13
13
12
12 12
15
13
22
21
1
0
2
7
6
5
3
4
2
0
1
7
6
5
4
3
10
8
9
11
12
15
13
14
16
17
18
19
20
21
23
22
7
6
0
4
U2
22/42
UPI0_TX_DP0
UPI0_TX_DP1
UPI0_TX_DP2
UPI0_TX_DP3
UPI0_TX_DP4
UPI0_TX_DP5
UPI0_TX_DP6
UPI0_TX_DP7
UPI0_TX_DP8
UPI0_TX_DP9
UPI0_TX_DP10
UPI0_TX_DP11
UPI0_TX_DP12
UPI0_TX_DP13
UPI0_TX_DP14
UPI0_TX_DP15
UPI0_TX_DP16
UPI0_TX_DP17
UPI0_TX_DP18
UPI0_TX_DP19
UPI0_TX_DP20
UPI0_TX_DP21
UPI0_TX_DP22
UPI0_TX_DP23
UPI0_TX_DN0
UPI0_TX_DN1
UPI0_TX_DN2
UPI0_TX_DN3
UPI0_TX_DN4
UPI0_TX_DN5
UPI0_TX_DN6
UPI0_TX_DN7
UPI0_TX_DN8
UPI0_TX_DN9
UPI0_TX_DN10
UPI0_TX_DN11
UPI0_TX_DN12
UPI0_TX_DN13
UPI0_TX_DN14
UPI0_TX_DN15
UPI0_TX_DN16
UPI0_TX_DN17
UPI0_TX_DN18
UPI0_TX_DN19
UPI0_TX_DN20
UPI0_TX_DN21
UPI0_TX_DN22
UPI0_TX_DN23
UPI0_RX_DP0
UPI0_RX_DP1
UPI0_RX_DP2
UPI0_RX_DP3
UPI0_RX_DP4
UPI0_RX_DP5
UPI0_RX_DP6
UPI0_RX_DP7
UPI0_RX_DP8
UPI0_RX_DP9
UPI0_RX_DP10
UPI0_RX_DP11
UPI0_RX_DP12
UPI0_RX_DP13
UPI0_RX_DP14
UPI0_RX_DP15
UPI0_RX_DP16
UPI0_RX_DP17
UPI0_RX_DP18
UPI0_RX_DP19
UPI0_RX_DP20
UPI0_RX_DP21
UPI0_RX_DP22
UPI0_RX_DP23
UPI0_RX_DN0
UPI0_RX_DN1
UPI0_RX_DN2
UPI0_RX_DN3
UPI0_RX_DN4
UPI0_RX_DN5
UPI0_RX_DN6
UPI0_RX_DN7
UPI0_RX_DN8
UPI0_RX_DN9
UPI0_RX_DN10
UPI0_RX_DN11
UPI0_RX_DN12
UPI0_RX_DN13
UPI0_RX_DN14
UPI0_RX_DN15
UPI0_RX_DN16
UPI0_RX_DN17
UPI0_RX_DN18
UPI0_RX_DN19
UPI0_RX_DN20
UPI0_RX_DN21
UPI0_RX_DN22
UPI0_RX_DN23
DESIGN NOTE: DESIGN NOTE:
SHEETDATE
DEPARTMENT
SIZE
PROJECT DOCUMENT NUMBER REV
REVIEWER
DESIGNER
123
7 3 2 1 6 5 4
E
A
B
C
E
D
C
B
A
7 6 5 4
D
OUT
IN
IN OUT
C



Fri Aug 25 14:00:17 2023N/AN/AN/AN/AV0533 OF 312SPR CPU0 - UPI1 (21 OF 30)
636363 63SMLFIOSOCKET4677_AZIF0045-P001C01CSUPI_CPU0_CPU1_P1P0_DP<23:0>UPI_CPU1_CPU0_P0P1_DN<23:0>UPI_CPU1_CPU0_P0P1_DP<23:0>UPI_CPU0_CPU1_P1P0_DN<23:0>DP/DN SWAP DP/DN SWAP
BW7
CB6
CC7
CF6
CG7
CK6
CL7
CP6
CR7
CV6
CW7
DB6
DC7
DF6
DG7
DJ5
DM6
DN5
DR7
DU5
DW7
EA5
ED6
EE5
BY6
CA5
CD6
CE5
CH6
CJ5
CM6
CN5
CT6
CU5
CY6
DA5
DD6
DE5
DH6
DK6
DL7
DP6
DT6
DV6
DY6
EB6
EC7
EF6
BY2
CC3
CE1
CG3
CK2
CM2
CP2
CT2
CU1
CW3
DA1
DC3
DF2
DH2
DK2
DM2
DP2
DR3
DV2
DW3
EB2
EC3
EG3
EJ3
CB2
CD2
CF2
CH2
CJ1
CL3
CN1
CR3
CV2
CY2
DB2
DD2
DE1
DG3
DJ1
DL3
DN1
DT2
DU1
DY2
EA1
ED2
EE3
EH2
22
8
6
7
8
9
4
6
1
2
22
0
7
9
8
5
7
6
4
2
1
0
4
21
18
16
15
14
13
3
11
9
10
8
7
6
4
5
3
1
0
22
21
20
17
1
16
15
13
2
2
18
18
14
14
14
20
21
23
19
17
16
15
13
12
11
11
10
5
3
19
17
16
15
13
1212
11
10
5
3
23
21
20
18
19
10
23
12
17
19
20
22
23
9
0
U2
23/42
UPI1_TX_DP0
UPI1_TX_DP1
UPI1_TX_DP2
UPI1_TX_DP3
UPI1_TX_DP4
UPI1_TX_DP5
UPI1_TX_DP6
UPI1_TX_DP7
UPI1_TX_DP8
UPI1_TX_DP9
UPI1_TX_DP10
UPI1_TX_DP11
UPI1_TX_DP12
UPI1_TX_DP13
UPI1_TX_DP14
UPI1_TX_DP15
UPI1_TX_DP16
UPI1_TX_DP17
UPI1_TX_DP18
UPI1_TX_DP19
UPI1_TX_DP20
UPI1_TX_DP21
UPI1_TX_DP22
UPI1_TX_DP23
UPI1_TX_DN0
UPI1_TX_DN1
UPI1_TX_DN2
UPI1_TX_DN3
UPI1_TX_DN4
UPI1_TX_DN5
UPI1_TX_DN6
UPI1_TX_DN7
UPI1_TX_DN8
UPI1_TX_DN9
UPI1_TX_DN10
UPI1_TX_DN11
UPI1_TX_DN12
UPI1_TX_DN13
UPI1_TX_DN14
UPI1_TX_DN15
UPI1_TX_DN16
UPI1_TX_DN17
UPI1_TX_DN18
UPI1_TX_DN19
UPI1_TX_DN20
UPI1_TX_DN21
UPI1_TX_DN22
UPI1_TX_DN23
UPI1_RX_DP0
UPI1_RX_DP1
UPI1_RX_DP2
UPI1_RX_DP3
UPI1_RX_DP4
UPI1_RX_DP5
UPI1_RX_DP6
UPI1_RX_DP7
UPI1_RX_DP8
UPI1_RX_DP9
UPI1_RX_DP10
UPI1_RX_DP11
UPI1_RX_DP12
UPI1_RX_DP13
UPI1_RX_DP14
UPI1_RX_DP15
UPI1_RX_DP16
UPI1_RX_DP17
UPI1_RX_DP18
UPI1_RX_DP19
UPI1_RX_DP20
UPI1_RX_DP21
UPI1_RX_DP22
UPI1_RX_DP23
UPI1_RX_DN0
UPI1_RX_DN1
UPI1_RX_DN2
UPI1_RX_DN3
UPI1_RX_DN4
UPI1_RX_DN5
UPI1_RX_DN6
UPI1_RX_DN7
UPI1_RX_DN8
UPI1_RX_DN9
UPI1_RX_DN10
UPI1_RX_DN11
UPI1_RX_DN12
UPI1_RX_DN13
UPI1_RX_DN14
UPI1_RX_DN15
UPI1_RX_DN16
UPI1_RX_DN17
UPI1_RX_DN18
UPI1_RX_DN19
UPI1_RX_DN20
UPI1_RX_DN21
UPI1_RX_DN22
UPI1_RX_DN23
DESIGN NOTE: DESIGN NOTE:
SHEETDATE
DEPARTMENT
SIZE
PROJECT DOCUMENT NUMBER REV
REVIEWER
DESIGNER
123
7 3 2 1 6 5 4
E
A
B
C
E
D
C
B
A
7 6 5 4
D
IN
IN OUT
OUT
C



Fri Aug 25 14:00:18 2023N/AN/AN/AN/AV0534 OF 312SPR CPU0 - UPI2 (22 OF 30)
6565 6565SMLFIOSOCKET4677_AZIF0045-P001C01CSUPI_CPU1_CPU0_P2P2_DN<23:0>UPI_CPU1_CPU0_P2P2_DP<23:0>UPI_CPU0_CPU1_P2P2_DN<23:0>UPI_CPU0_CPU1_P2P2_DP<23:0>1.DP/DN SWAP2.LANE REVERSAL1.DP/DN SWAP2.LANE REVERSAL
BN72
BE80
BG82
BC80
BD83
BA82
BB81
AU82
AV83
AT81
AM83
AP81
AV79
BA78
W82
Y83
V81
P83
T81
G86
H87
E88
F85
D85
BM71
BG80
BF81
BD79
BE82
BC82
BA80
AV81
AT83
AR80
AN82
AM81
AU78
AW78
Y81
V83
U80
R82
P81
H85
F87
D87
E84
B85
BC74
BL74
BM75
BJ74
BN76
BK77
BG76
AV75
BD75
BA76
AY73
BB73
AJ82
AH81
AF83
AG80
AC82
AE80
K81
L82
M79
H83
E82
G80
BD73
BK73
BN74
BG74
BL76
BJ76
BH75
AW74
BB75
AY75
AV73
BA72
AG82
AJ80
AE82
AF79
AD81
AC80
L80
J82
K79
G82
F81
E80
1
0
2
3
4
8
10
9
7
5
17
6
11
12
15
14
13
17
16
19
18
18
20
22
0
23
21
1
2
3
5
4
19
7
6
9
8
10
12
11
14
13
15
20
16
17
20
18
19
23
22
21
1
23
6
5
10
9
13
17
18
19
20
23
1
5
6
9
10
13
21
21
0
2
3
4
7
8
14
15
12
11
16
22
0
2
3
4
7
8
14
15
12
11
16
22
U2
24/42
UPI2_TX_DP0
UPI2_TX_DP1
UPI2_TX_DP2
UPI2_TX_DP3
UPI2_TX_DP4
UPI2_TX_DP5
UPI2_TX_DP6
UPI2_TX_DP7
UPI2_TX_DP8
UPI2_TX_DP9
UPI2_TX_DP10
UPI2_TX_DP11
UPI2_TX_DP12
UPI2_TX_DP13
UPI2_TX_DP14
UPI2_TX_DP15
UPI2_TX_DP16
UPI2_TX_DP17
UPI2_TX_DP18
UPI2_TX_DP19
UPI2_TX_DP20
UPI2_TX_DP21
UPI2_TX_DP22
UPI2_TX_DP23
UPI2_TX_DN0
UPI2_TX_DN1
UPI2_TX_DN2
UPI2_TX_DN3
UPI2_TX_DN4
UPI2_TX_DN5
UPI2_TX_DN6
UPI2_TX_DN7
UPI2_TX_DN8
UPI2_TX_DN9
UPI2_TX_DN10
UPI2_TX_DN11
UPI2_TX_DN12
UPI2_TX_DN13
UPI2_TX_DN14
UPI2_TX_DN15
UPI2_TX_DN16
UPI2_TX_DN17
UPI2_TX_DN18
UPI2_TX_DN19
UPI2_TX_DN20
UPI2_TX_DN21
UPI2_TX_DN22
UPI2_TX_DN23
UPI2_RX_DP0
UPI2_RX_DP1
UPI2_RX_DP2
UPI2_RX_DP3
UPI2_RX_DP4
UPI2_RX_DP5
UPI2_RX_DP6
UPI2_RX_DP7
UPI2_RX_DP8
UPI2_RX_DP9
UPI2_RX_DP10
UPI2_RX_DP11
UPI2_RX_DP12
UPI2_RX_DP13
UPI2_RX_DP14
UPI2_RX_DP15
UPI2_RX_DP16
UPI2_RX_DP17
UPI2_RX_DP18
UPI2_RX_DP19
UPI2_RX_DP20
UPI2_RX_DP21
UPI2_RX_DP22
UPI2_RX_DP23
UPI2_RX_DN0
UPI2_RX_DN1
UPI2_RX_DN2
UPI2_RX_DN3
UPI2_RX_DN4
UPI2_RX_DN5
UPI2_RX_DN6
UPI2_RX_DN7
UPI2_RX_DN8
UPI2_RX_DN9
UPI2_RX_DN10
UPI2_RX_DN11
UPI2_RX_DN12
UPI2_RX_DN13
UPI2_RX_DN14
UPI2_RX_DN15
UPI2_RX_DN16
UPI2_RX_DN17
UPI2_RX_DN18
UPI2_RX_DN19
UPI2_RX_DN20
UPI2_RX_DN21
UPI2_RX_DN22
UPI2_RX_DN23
DESIGN NOTE: DESIGN NOTE:
SHEETDATE
DEPARTMENT
SIZE
PROJECT DOCUMENT NUMBER REV
REVIEWER
DESIGNER
123
7 3 2 1 6 5 4
E
A
B
C
E
D
C
B
A
7 6 5 4
D
IN
IN
OUT
OUT
C



20211122 MODIFY FOR GT
20211129 CHANGE TX FLOATINGFri Aug 25 14:00:19 2023N/AN/AN/AN/AV0535 OF 312SPR CPU0 - UPI3 (23 OF 30)
SOCKET4677_AZIF0045-P001C01CSSMLFIO
CD73
CW74
CK75
CH75
CF77
CL76
CJ78
CM77
CU74
CR76
CV77
DA76
DN80
DL82
DP83
DR80
DU82
DT81
EL88
EH87
EP87
EN86
EM85
EK85
CF73
CV73
CJ74
CF75
CG76
CM75
CH77
CK77
CR74
CT75
CU76
CW76
DL80
DM81
DN82
DP79
DR82
DU80
EK87
EJ86
EM87
EP85
EL84
EH85
DB79
CU80
CR80
CN82
CV81
CT83
CW82
DE78
DD81
DB83
DF81
DH83
DG82
DH79
DL78
EB81
DY83
ED81
EF83
EE82
EJ82
EN82
ER82
EL80
DA78
CT79
CN80
CP81
CW80
CR82
CU82
DF77
DB81
DC82
DE80
DF83
DH81
DG78
DJ78
DY81
EA82
EC80
ED83
EF81
EK81
EL82
EP81
EJ80
U2
25/42
UPI3_TX_DP0
UPI3_TX_DP1
UPI3_TX_DP2
UPI3_TX_DP3
UPI3_TX_DP4
UPI3_TX_DP5
UPI3_TX_DP6
UPI3_TX_DP7
UPI3_TX_DP8
UPI3_TX_DP9
UPI3_TX_DP10
UPI3_TX_DP11
UPI3_TX_DP12
UPI3_TX_DP13
UPI3_TX_DP14
UPI3_TX_DP15
UPI3_TX_DP16
UPI3_TX_DP17
UPI3_TX_DP18
UPI3_TX_DP19
UPI3_TX_DP20
UPI3_TX_DP21
UPI3_TX_DP22
UPI3_TX_DP23
UPI3_TX_DN0
UPI3_TX_DN1
UPI3_TX_DN2
UPI3_TX_DN3
UPI3_TX_DN4
UPI3_TX_DN5
UPI3_TX_DN6
UPI3_TX_DN7
UPI3_TX_DN8
UPI3_TX_DN9
UPI3_TX_DN10
UPI3_TX_DN11
UPI3_TX_DN12
UPI3_TX_DN13
UPI3_TX_DN14
UPI3_TX_DN15
UPI3_TX_DN16
UPI3_TX_DN17
UPI3_TX_DN18
UPI3_TX_DN19
UPI3_TX_DN20
UPI3_TX_DN21
UPI3_TX_DN22
UPI3_TX_DN23
UPI3_RX_DP0
UPI3_RX_DP1
UPI3_RX_DP2
UPI3_RX_DP3
UPI3_RX_DP4
UPI3_RX_DP5
UPI3_RX_DP6
UPI3_RX_DP7
UPI3_RX_DP8
UPI3_RX_DP9
UPI3_RX_DP10
UPI3_RX_DP11
UPI3_RX_DP12
UPI3_RX_DP13
UPI3_RX_DP14
UPI3_RX_DP15
UPI3_RX_DP16
UPI3_RX_DP17
UPI3_RX_DP18
UPI3_RX_DP19
UPI3_RX_DP20
UPI3_RX_DP21
UPI3_RX_DP22
UPI3_RX_DP23
UPI3_RX_DN0
UPI3_RX_DN1
UPI3_RX_DN2
UPI3_RX_DN3
UPI3_RX_DN4
UPI3_RX_DN5
UPI3_RX_DN6
UPI3_RX_DN7
UPI3_RX_DN8
UPI3_RX_DN9
UPI3_RX_DN10
UPI3_RX_DN11
UPI3_RX_DN12
UPI3_RX_DN13
UPI3_RX_DN14
UPI3_RX_DN15
UPI3_RX_DN16
UPI3_RX_DN17
UPI3_RX_DN18
UPI3_RX_DN19
UPI3_RX_DN20
UPI3_RX_DN21
UPI3_RX_DN22
UPI3_RX_DN23
SHEETDATE
DEPARTMENT
SIZE
PROJECT DOCUMENT NUMBER REV
REVIEWER
DESIGNER
123
7 3 2 1 6 5 4
E
A
B
C
E
D
C
B
A
7 6 5 4
D
C



36 OF 312N/A V05Fri Aug 25 14:00:19 2023N/AN/AN/A
PVCCIN_CPU0 PVCCIN_CPU0PVCCIN_CPU0PVCCIN_CPU0
SPR CPU0 POWER - VCCIN (24 OF 30)
SMLFIOSOCKET4677_AZIF0045-P001C01CSSMLFIOSOCKET4677_AZIF0045-P001C01CS
BW78
BW76
BW74
BW72
BW70
BW68
BW66
BW64
BW62
BW60
BW58
BW56
BW54
BW52
BW50
BW48
BW45
BW43
BW41
BW39
BW37
BW35
BW33
BV89
BV87
BV85
BV83
BV81
BV79
BV77
BV75
BV73
BV71
BV69
BV67
BV65
BV63
BV61
BV59
BV57
BV55
BV53
BV51
BV49
BV47
BV44
BV42
BV40
BV38
BV36
BV34
BV32
BU90
BU88
BU86
BU84
BU82
BU80
BU78
BU76
BU74
BU72
BU70
BU68
BU66
BU64
BU62
BU60
BU58
BU56
BU54
BU52
BU50
BU48
BU45
BU43
BU41
BU39
BU37
BU35
BU33
BT89
BT87
BT85
BT83
BT81
BT79
BT77
BT75
BT73
BT71
BT69
BT67
BT65
BT63
BT61
BT59
BT57
BT55
BT53
BT51
BT49
BT47
BT44
BT42
BT40
BT38
BT36
BT34
BT32
BR78
BR62
BR60
BP89
BP87
BP85
BP83
BP81
BP79
BP61
BP59
BP57
BP55
BP53
BP51
BP49
BP47
BP44
BP42
BP40
BP38
BP36
BP34
BP32
BN90
BN88
BN86
BN84
BN82
BN80
BN78
BN60
BN58
BN56
BN54
BN52
BN50
BN48
BN45
BN43
CM89
CP89
CN90
CN88
CM91
CM87
CL90
CL88
CL86
CL84
CK91
CK89
CK87
CK85
CK83
CJ90
CJ88
CJ86
CJ84
CJ82
CH91
CH81
CG90
CG88
CG86
CG84
CG82
CG80
CF91
CF89
CF87
CF85
CF83
CF81
CF79
CE90
CE88
CE86
CE84
CE82
CE80
CD89
CD87
CD85
CD83
CD81
CD79
CD59
CD57
CD55
CD53
CD51
CD49
CD47
CD44
CD42
CD40
CD38
CD36
CD34
CD32
CC90
CC88
CC86
CC84
CC82
CC80
CC78
CC76
CC60
CC58
CC56
CC54
CC52
CC50
CC48
CC45
CC43
CC41
CC39
CC37
CC35
CC33
CB77
CB75
CB61
CA90
CA88
CA86
CA84
CA82
CA80
CA78
CA76
CA74
CA72
CA70
CA68
CA66
CA64
CA62
CA60
CA58
CA56
CA54
CA52
CA50
CA48
CA45
CA43
CA41
CA39
CA37
CA35
CA33
BY89
BY87
BY85
BY83
BY81
BY79
BY77
BY75
BY73
BY71
BY69
BY67
BY65
BY63
BY61
BY59
BY57
BY55
BY53
BY51
BY49
BY47
BY44
BY42
BY40
BY38
BY36
BY34
BY32
BW90
BW88
BW86
BW84
BW82
BW80
U2U2
27/42
VCCIN40
VCCIN41
VCCIN42
VCCIN43
VCCIN44
VCCIN45
VCCIN46
VCCIN47
VCCIN48
VCCIN49
VCCIN50
VCCIN51
VCCIN52
VCCIN53
VCCIN54
VCCIN55
VCCIN56
VCCIN57
VCCIN58
VCCIN59
VCCIN60
VCCIN61
VCCIN62
VCCIN63
VCCIN64
VCCIN65
VCCIN66
VCCIN67
VCCIN68
VCCIN69
VCCIN70
VCCIN71
VCCIN72
VCCIN73
VCCIN74
VCCIN75
VCCIN76
VCCIN77
VCCIN78
VCCIN79
VCCIN80
VCCIN81
VCCIN82
VCCIN83
VCCIN84
VCCIN85
VCCIN86
VCCIN87
VCCIN88
VCCIN89
VCCIN90
VCCIN91
VCCIN92
VCCIN93
VCCIN94
VCCIN95
VCCIN96
VCCIN97
VCCIN98
VCCIN99
VCCIN100
VCCIN101
VCCIN102
VCCIN103
VCCIN104
VCCIN105
VCCIN106
VCCIN107
VCCIN108
VCCIN109
VCCIN110
VCCIN111
VCCIN112
VCCIN113
VCCIN114
VCCIN115
VCCIN116
VCCIN117
VCCIN118
VCCIN119
VCCIN120
VCCIN121
VCCIN122
VCCIN123
VCCIN124
VCCIN125
VCCIN126
VCCIN127
VCCIN128
VCCIN129
VCCIN130
VCCIN131
VCCIN132
VCCIN133
VCCIN134
VCCIN135
VCCIN136
VCCIN137
VCCIN138
VCCIN139
VCCIN140
VCCIN141
VCCIN142
VCCIN143
VCCIN144
VCCIN145
VCCIN146
VCCIN147
VCCIN148
VCCIN149
VCCIN150
VCCIN151
VCCIN152
VCCIN153
VCCIN154
VCCIN155
VCCIN156
VCCIN157
VCCIN158
VCCIN159
VCCIN160
VCCIN161
VCCIN162
VCCIN163
VCCIN164
VCCIN165
VCCIN166
VCCIN167
VCCIN168
VCCIN169
VCCIN170
VCCIN171
VCCIN172
VCCIN173
VCCIN174
VCCIN175
VCCIN176
VCCIN177
VCCIN178
VCCIN179
VCCIN180
VCCIN181
VCCIN182
VCCIN183
VCCIN184
VCCIN185
VCCIN186
VCCIN187
VCCIN188
VCCIN189
26/42
VCCIN190
VCCIN191
VCCIN192
VCCIN193
VCCIN194
VCCIN195
VCCIN196
VCCIN197
VCCIN198
VCCIN199
VCCIN200
VCCIN201
VCCIN202
VCCIN203
VCCIN204
VCCIN205
VCCIN206
VCCIN207
VCCIN208
VCCIN209
VCCIN210
VCCIN211
VCCIN212
VCCIN213
VCCIN214
VCCIN215
VCCIN216
VCCIN217
VCCIN218
VCCIN219
VCCIN220
VCCIN221
VCCIN222
VCCIN223
VCCIN224
VCCIN225
VCCIN226
VCCIN227
VCCIN228
VCCIN229
VCCIN230
VCCIN231
VCCIN232
VCCIN233
VCCIN234
VCCIN235
VCCIN236
VCCIN237
VCCIN238
VCCIN239
VCCIN240
VCCIN241
VCCIN242
VCCIN243
VCCIN244
VCCIN245
VCCIN246
VCCIN247
VCCIN248
VCCIN249
VCCIN250
VCCIN251
VCCIN252
VCCIN253
VCCIN254
VCCIN255
VCCIN256
VCCIN257
VCCIN258
VCCIN259
VCCIN260
VCCIN261
VCCIN262
VCCIN263
VCCIN264
VCCIN265
VCCIN266
VCCIN267
VCCIN268
VCCIN269
VCCIN270
VCCIN271
VCCIN272
VCCIN273
VCCIN274
VCCIN275
VCCIN276
VCCIN277
VCCIN278
VCCIN279
VCCIN280
VCCIN281
VCCIN282
VCCIN283
VCCIN284
VCCIN285
VCCIN286
VCCIN287
VCCIN288
VCCIN289
VCCIN290
VCCIN291
VCCIN292
VCCIN293
VCCIN294
VCCIN295
VCCIN296
VCCIN297
VCCIN298
VCCIN299
VCCIN300
VCCIN301
VCCIN302
VCCIN303
VCCIN304
VCCIN305
VCCIN306
VCCIN307
VCCIN308
VCCIN309
VCCIN310
VCCIN311
VCCIN312
VCCIN313
VCCIN314
VCCIN315
VCCIN316
VCCIN317
VCCIN318
VCCIN319
VCCIN320
VCCIN321
VCCIN322
VCCIN323
VCCIN324
VCCIN325
VCCIN326
VCCIN327
VCCIN328
VCCIN329
VCCIN330
VCCIN331
VCCIN332
VCCIN333
VCCIN334
VCCIN335
VCCIN336
VCCIN337
VCCIN338
VCCIN339
SHEETDATE
DEPARTMENT
SIZE
PROJECT DOCUMENT NUMBER REV
REVIEWER
DESIGNER
123
7 3 2 1 6 5 4
E
A
B
C
E
D
C
B
A
7 6 5 4
D
C



37 OF 312Fri Aug 25 14:00:20 2023V05N/AN/AN/AN/A
PVNN_MAIN_CPU0PVCCINFAON_CPU0PVCCD_HV_CPU0PVCCINFAON_CPU0PVCCIN_CPU0P3V3_AUXPVPP_HBM_CPU0PVNN_MAIN_CPU0PVCCFA_EHV_CPU0SPR CPU0 POWER - VCCIN/VCCINFAON (25)
SOCKET4677_AZIF0045-P001C01CSIOSMLFSOCKET4677_AZIF0045-P001C01CSIOSMLFC04026.3VX6S10UF20%
CG68
BA21
BC21
CC68
CD67
CE68
CF67
BN19
BJ19
BE19
BA19
DJ11
DE7
DA7
DA3
CW64
CR66
DJ7
DJ3
DJ15
DE3
DE15
DE11
DA64
DA15
DA11
CY67
CY65
CW66
CV67
CV65
CU7
CU64
CU3
CU15
CU11
CT67
CT65
CP67
CP65
CN7
CN66
CN64
CN3
CN15
CN11
CJ7
CJ3
CJ15
CE15
U3
N3
AW60
AV61
AU60
AT61
AN3
AJ3
AE3
AA3
CY53
CY36
CY34
CW56
CW54
CW52
CW37
CW35
CE7
CA7
BN7
BJ7
BJ3
BJ11
BE7
BE3
BE11
BA7
BA3
AV55
AV53
AV36
AV34
AU7
AU54
AU35
AU3
AT55
AT36
DA21
CW62
CV63
CV61
CT63
CP63
CN19
CJ19
CJ11
CE19
CA15
BN15
BK61
BJ60
BJ15
BG60
BE60
BE15
BC60
BA15
AY18
BN41
BN39
BN37
BN35
BN33
BM91
BM89
BM87
BM85
BM83
BM81
BM79
BL90
BL88
BL86
BL84
BL82
BL80
BK91
BK89
BK87
BK85
BK83
BK81
BH91
BH89
BH87
BH85
BG90
BG88
BG86
BG84
BF91
BF89
BF87
BF85
BE90
BE88
BE86
BD91
U2
U2 29/42
VPP_HBM4
VPP_HBM3
VPP_HBM2
VPP_HBM1
VPP_HBM
VCCVNN0
VCCVNN1
VCCVNN2
VCCVNN3
VCCINFAON0
VCCINFAON1
VCCINFAON2
VCCINFAON3
VCCINFAON4
VCCINFAON5
VCCINFAON6
VCCINFAON7
VCCINFAON8
VCCINFAON9
VCCINFAON10
VCCINFAON11
VCCINFAON12
VCCINFAON13
VCCINFAON14
VCCINFAON15
VCCINFAON16
VCCINFAON17
VCCINFAON18
VCCINFAON19
VCCINFAON20
VCCINFAON21
VCCINFAON22
VCCINFAON23
VCCINFAON24
VCCINFAON25
VCCINFAON26
VCCINFAON27
VCCINFAON28
VCCINFAON29
VCCINFAON30
VCCINFAON31
VCCINFAON32
VCCINFAON54
VCCINFAON55
VCCINFAON56
VCCINFAON57
VCCINFAON58
VCCINFAON59
VCCFA_EHV0
VCCFA_EHV1
VCCFA_EHV2
VCCFA_EHV3
VCCFA_EHV4
VCCFA_EHV5
VCCFA_EHV6
VCCFA_EHV7
VCCFA_EHV9
VCCFA_EHV8
VCCD_HV0
VCCD_HV1
VCCD_HV2
VCCD_HV3
VCCD_HV4
VCCD_HV5
VCCD_HV6
VCCD_HV7
VCCD_HV8
VCCD_HV9
VCCD_HV10
VCCD_HV11
VCCD_HV12
VCCD_HV13
VCCD_HV14
VCCD_HV15
VCCD_HV16
VCCD_HV17
VCCD_HV18
VCCD_HV19
VCCD_HV20
VCCD_HV21
VCCD_HV22
VCCD_HV23
VCCD_HV25
VCCD_HV26
VCCD_HV24
VCCD_HV27
VCCD_HV28
VCC_3P3_AUX1
VCC_3P3_AUX0
28/42
VCCINFAON33
VCCINFAON34
VCCINFAON35
VCCINFAON36
VCCINFAON37
VCCINFAON38
VCCINFAON39
VCCINFAON40
VCCINFAON41
VCCINFAON42
VCCINFAON43
VCCINFAON44
VCCINFAON45
VCCINFAON46
VCCINFAON47
VCCINFAON48
VCCINFAON49
VCCINFAON50
VCCINFAON51
VCCINFAON52
VCCINFAON53
VCCIN0
VCCIN1
VCCIN2
VCCIN3
VCCIN4
VCCIN5
VCCIN6
VCCIN7
VCCIN8
VCCIN9
VCCIN10
VCCIN11
VCCIN12
VCCIN13
VCCIN14
VCCIN15
VCCIN16
VCCIN17
VCCIN18
VCCIN19
VCCIN20
VCCIN21
VCCIN22
VCCIN23
VCCIN24
VCCIN25
VCCIN26
VCCIN27
VCCIN28
VCCIN29
VCCIN30
VCCIN31
VCCIN32
VCCIN33
VCCIN34
VCCIN35
VCCIN36
VCCIN37
VCCIN38
VCCIN39
SHEETDATE
DEPARTMENT
SIZE
PROJECT DOCUMENT NUMBER REV
REVIEWER
DESIGNER
123
7 3 2 1 6 5 4
E
A
B
C
E
D
C
B
A
7 6 5 4
D
C1
C



38 OF 312N/AFri Aug 25 14:00:21 2023V05N/AN/AN/A
PVCCFA_EHV_FIVRA_CPU0PVCCFA_EHV_FIVRA_CPU0
SPR CPU0 POWER - VCCFA EHV FIVRA (26)
SOCKET4677_AZIF0045-P001C01CSIOSMLF
Y89
Y85
Y79
W80
U7
U15
U11
T89
T85
R80
P79
N7
N11
M89
M85
L84
K87
J80
J7
J11
H89
EN84
EJ84
EJ15
EG80
EF79
EE84
EE7
EE15
EE11
ED89
ED85
ED79
EC78
EA7
EA3
EA15
EA11
DY89
DY85
DU7
DU3
DU15
DU11
DT89
DT85
DT79
DN7
DN3
DN15
DN11
DM89
DM85
DM83
DH89
DD89
DD85
DD83
DD77
CY89
CY85
CY79
CY75
CT85
CT77
CP73
CN78
CM73
CK79
CK73
CE74
C88
C84
BJ78
BJ72
BH79
BF77
BE72
AY89
AW76
AU15
AT89
AT73
AN80
AN7
AN15
AN11
AM89
AM85
AM79
AJ7
AJ15
AJ11
AH89
AH85
AG78
AF77
AE7
AE15
AE11
AD89
AD85
AA7
AA15
AA11
U2
30/42
VCCFA_EHV_FIVRA0
VCCFA_EHV_FIVRA1
VCCFA_EHV_FIVRA2
VCCFA_EHV_FIVRA3
VCCFA_EHV_FIVRA4
VCCFA_EHV_FIVRA5
VCCFA_EHV_FIVRA6
VCCFA_EHV_FIVRA7
VCCFA_EHV_FIVRA8
VCCFA_EHV_FIVRA9
VCCFA_EHV_FIVRA10
VCCFA_EHV_FIVRA11
VCCFA_EHV_FIVRA12
VCCFA_EHV_FIVRA13
VCCFA_EHV_FIVRA14
VCCFA_EHV_FIVRA15
VCCFA_EHV_FIVRA16
VCCFA_EHV_FIVRA17
VCCFA_EHV_FIVRA18
VCCFA_EHV_FIVRA19
VCCFA_EHV_FIVRA20
VCCFA_EHV_FIVRA21
VCCFA_EHV_FIVRA22
VCCFA_EHV_FIVRA23
VCCFA_EHV_FIVRA24
VCCFA_EHV_FIVRA25
VCCFA_EHV_FIVRA26
VCCFA_EHV_FIVRA27
VCCFA_EHV_FIVRA28
VCCFA_EHV_FIVRA29
VCCFA_EHV_FIVRA30
VCCFA_EHV_FIVRA31
VCCFA_EHV_FIVRA32
VCCFA_EHV_FIVRA33
VCCFA_EHV_FIVRA34
VCCFA_EHV_FIVRA35
VCCFA_EHV_FIVRA36
VCCFA_EHV_FIVRA37
VCCFA_EHV_FIVRA38
VCCFA_EHV_FIVRA39
VCCFA_EHV_FIVRA40
VCCFA_EHV_FIVRA41
VCCFA_EHV_FIVRA42
VCCFA_EHV_FIVRA43
VCCFA_EHV_FIVRA44
VCCFA_EHV_FIVRA45
VCCFA_EHV_FIVRA46
VCCFA_EHV_FIVRA47
VCCFA_EHV_FIVRA48
VCCFA_EHV_FIVRA49
VCCFA_EHV_FIVRA50
VCCFA_EHV_FIVRA51
VCCFA_EHV_FIVRA52
VCCFA_EHV_FIVRA53
VCCFA_EHV_FIVRA54
VCCFA_EHV_FIVRA55
VCCFA_EHV_FIVRA56
VCCFA_EHV_FIVRA57
VCCFA_EHV_FIVRA58
VCCFA_EHV_FIVRA59
VCCFA_EHV_FIVRA60
VCCFA_EHV_FIVRA61
VCCFA_EHV_FIVRA62
VCCFA_EHV_FIVRA63
VCCFA_EHV_FIVRA64
VCCFA_EHV_FIVRA65
VCCFA_EHV_FIVRA66
VCCFA_EHV_FIVRA67
VCCFA_EHV_FIVRA68
VCCFA_EHV_FIVRA69
VCCFA_EHV_FIVRA70
VCCFA_EHV_FIVRA71
VCCFA_EHV_FIVRA72
VCCFA_EHV_FIVRA73
VCCFA_EHV_FIVRA74
VCCFA_EHV_FIVRA75
VCCFA_EHV_FIVRA76
VCCFA_EHV_FIVRA77
VCCFA_EHV_FIVRA78
VCCFA_EHV_FIVRA79
VCCFA_EHV_FIVRA80
VCCFA_EHV_FIVRA81
VCCFA_EHV_FIVRA82
VCCFA_EHV_FIVRA83
VCCFA_EHV_FIVRA84
VCCFA_EHV_FIVRA85
VCCFA_EHV_FIVRA86
VCCFA_EHV_FIVRA87
VCCFA_EHV_FIVRA88
VCCFA_EHV_FIVRA89
VCCFA_EHV_FIVRA90
VCCFA_EHV_FIVRA91
VCCFA_EHV_FIVRA92
VCCFA_EHV_FIVRA93
VCCFA_EHV_FIVRA94
VCCFA_EHV_FIVRA95
VCCFA_EHV_FIVRA96
VCCFA_EHV_FIVRA97
VCCFA_EHV_FIVRA98
VCCFA_EHV_FIVRA99
VCCFA_EHV_FIVRA100
VCCFA_EHV_FIVRA101
VCCFA_EHV_FIVRA102
VCCFA_EHV_FIVRA103
VCCFA_EHV_FIVRA104
SHEETDATE
DEPARTMENT
SIZE
PROJECT DOCUMENT NUMBER REV
REVIEWER
DESIGNER
123
7 3 2 1 6 5 4
E
A
B
C
E
D
C
B
A
7 6 5 4
D
C



39 OF 312N/AFri Aug 25 14:00:22 2023N/AV05N/AN/ASPR CPU0 POWER - GND (27 OF 30)
SOCKET4677_AZIF0045-P001C01CSIOSMLFSOCKET4677_AZIF0045-P001C01CSIOSMLFSOCKET4677_AZIF0045-P001C01CSIOSMLF
DW9
DW64
DW62
DW58
DW56
DW54
DW52
DW50
DW5
DW48
DW45
DW43
DW41
DW39
DW37
DW35
DW33
DW31
DW29
DW27
DW25
DW23
DW19
DW17
DW13
DW1
DV91
DV87
DV83
DV81
DV8
DV79
DV77
DU88
DU84
DU78
DU76
DU33
DU27
DU21
DT8
DT75
DT71
DT69
DT65
DT57
DT47
DT40
DT38
DT34
DT32
DT28
DT22
DT12
DR9
DR88
DR84
DR78
DR74
DR66
DR56
DR50
DR48
DR43
DR41
DR37
DR31
DR29
DR23
DR19
DR13
DR1
DP87
DP81
DP8
DP73
DP49
DP4
DP36
DP30
DP16
DN88
DN84
DN78
DM8
DM79
DM77
DM75
DM71
DM69
DM67
DM65
DM63
DM61
DM59
DM57
DM55
DM53
DM49
DM47
DM44
DM42
DM40
DM4
DM38
DM36
DM34
DM32
DM30
DM28
DM26
DM24
DM22
DM20
DM18
DM16
DM12
DW60
DW21
DV42
DV4
DV16
DV12
DU70
DU64
DU58
DU52
DU45
DU39
DT83
DT63
DT59
DT53
DT51
DT44
DT4
DT26
DT20
DT16
DR72
DR68
DR62
DR60
DR54
DR5
DR35
DR25
DP91
DP67
DP61
DP55
DP42
DP24
DP18
DP12
DN52
DN39
DN17
DM73
DM51
EH4
EH30
EH24
EH16
EG90
EG9
EG88
EG86
EG84
EG82
EG39
EF87
EF85
EF8
EF77
EF71
EF69
EF67
EF65
EF63
EF61
EF59
EF57
EF55
EF53
EF49
EF47
EF44
EF42
EF40
EF4
EF38
EF36
EF34
EF32
EF30
EF28
EF26
EF24
EF22
EF20
EF2
EF18
EF16
EF12
EE88
EE80
EE78
ED8
ED49
ED4
ED36
ED30
ED24
ED16
EC9
EC88
EC84
EC82
EC74
EC72
EC66
EC56
EC50
EC48
EC43
EC41
EH6
EC37
EC31
EC29
EC23
EC19
EC13
EC1
EB87
EB83
EB8
EH18
EB79
EH14
EH12
EB75
EB71
EB69
EB65
EB57
EB47
EB40
EG7
EB38
EB32
EG52
EG5
EB28
EB22
EB12
EA88
EA84
EG13
EF89
EA80
EA78
EA76
EA70
EA33
EF75
EF73
EA27
EA21
DY8
DY77
DW88
DW84
EF51
DW82
DW80
DW76
DW74
DW72
DW70
DW68
DW66
EE52
EE39
EE17
ED73
ED67
ED61
ED55
ED42
ED18
ED12
EC68
EC62
EC60
EC54
EC5
EC35
EC25
EB91
EB63
EB59
EB53
EB51
EB44
EB4
EB34
EB26
EB20
EB16
EA64
EA58
EA52
EA45
EA39
DY42
DY4
DY16
DY12
ER50
ER48
ER43
ER41
ET57
ET38
ET34
ET28
ET22
ET16
ET10
ER86
ER84
ER80
ER78
ER74
ER70
ER7
ER5
ER33
ER27
EP83
EP67
EN80
EN78
EN64
EN56
EN54
EN52
EN50
EN48
EN45
EN43
EN41
EN37
EN35
EN33
EN31
EN29
EN27
EN25
EN23
EN21
EN19
EN17
EN15
EN13
EN11
EM83
EM81
EM8
EM73
ET59
EM42
ET53
EL76
EL64
EL5
EL45
ET32
EL39
ET26
EL33
ET20
EL3ET14
EL27
ER9
EL21
EK75
EK69
EK65
EK57
EK47
EK40
ER64
ER58
EK4
EK38
ER52
EK34
ER39
EK32
EK28
EK22
EK2
ER21
ER15
EK14
EP77
EP71
EP69
EK10
EJ9
EJ88
EJ78
EJ74
EN9
EN88
EJ7
EJ66
EJ60
EN72
EN66
EJ56
EN62
EN60
EN58
EJ50
EJ48
EJ43
EJ41
EJ37
EJ31
EJ29
EJ23
EN39
EJ19
EJ13
EH83
EH81
EH73
EH49
EH36
EM79
EM49
EL9
EL86
EL72
EL70
EL7
EL58
EL52
EL15
EK89
EK83
EK79
EK77
EK71
EK63
EK59
EK53
EK51
EK44
EK26
EK20
EK16
EJ72
EJ68
EJ62
EJ54
EJ35
EJ25
EJ17
EJ11
EH79
EH67
EH61
EH55
EH42
U2U2U2
32/42
VSS1111
VSS1112
VSS1115
VSS1116
VSS1141
VSS1142
VSS1144
VSS1145
VSS1146
VSS1155
VSS1156
VSS1158
VSS1161
VSS1163
VSS1165
VSS1167
VSS1168
VSS1170
VSS1171
VSS1180
VSS1185
VSS1188
VSS1193
VSS1195
VSS1197
VSS1198
VSS1200
VSS1208
VSS1210
VSS1217
VSS1220
VSS1223
VSS1224
VSS1225
VSS1232
VSS1235
VSS1237
VSS1257
VSS1258
VSS1259
VSS1260
VSS1261
VSS1262
VSS1263
VSS1264
VSS1265
VSS1266
VSS1267
VSS1269
VSS1270
VSS1274
VSS1275
VSS1276
VSS1277
VSS1278
VSS1279
VSS1280
VSS1281
VSS1282
VSS1283
VSS1284
VSS1285
VSS1286
VSS1287
VSS1288
VSS1289
VSS1290
VSS1291
VSS1292
VSS1293
VSS1294
VSS1295
VSS1296
VSS1297
VSS1298
VSS1299
VSS1300
VSS1301
VSS1302
VSS1303
VSS1304
VSS1305
VSS1306
VSS1307
VSS1308
VSS1309
VSS1310
VSS1311
VSS1313
VSS1314
VSS1316
VSS1317
VSS1318
VSS1321
VSS1323
VSS1324
VSS1326
VSS1327
VSS1329
VSS1330
VSS1332
VSS1333
VSS1335
VSS1336
VSS1337
VSS1338
VSS1339
VSS1341
VSS1342
VSS1344
VSS1346
VSS1348
VSS1349
VSS1350
VSS1351
VSS1352
VSS1353
VSS1354
VSS1356
VSS1358
VSS1360
VSS1361
VSS1362
VSS1363
VSS1364
VSS1365
VSS1367
VSS1370
VSS1373
VSS1374
VSS1376
VSS1382
VSS1383
VSS1384
VSS1385
VSS1386
VSS1387
VSS1388
VSS1389
VSS1390
VSS1392
VSS1393
VSS1395
VSS1399
VSS1402
VSS1403
VSS1404
VSS1406
VSS1407
VSS1408
VSS1410
VSS1411
VSS1412
VSS1413
VSS1414
VSS1415
VSS1416
VSS1417
VSS1418
VSS1420
33/42
VSS934
VSS945
VSS955
VSS957
VSS959
VSS966
VSS968
VSS969
VSS973
VSS976
VSS979
VSS980
VSS985
VSS990
VSS993
VSS998
VSS1000
VSS1002
VSS1003
VSS1005
VSS1006
VSS1013
VSS1014
VSS1016
VSS1021
VSS1023
VSS1025
VSS1026
VSS1028
VSS1029
VSS1036
VSS1047
VSS1048
VSS1050
VSS1051
VSS1052
VSS1054
VSS1059
VSS1060
VSS1063
VSS1064
VSS1077
VSS1097
VSS1100
VSS1101
VSS1102
VSS1103
VSS1104
VSS1105
VSS1106
VSS1107
VSS1108
VSS1109
VSS1110
VSS1113
VSS1114
VSS1117
VSS1118
VSS1119
VSS1120
VSS1121
VSS1122
VSS1123
VSS1124
VSS1127
VSS1128
VSS1130
VSS1132
VSS1133
VSS1134
VSS1135
VSS1136
VSS1137
VSS1138
VSS1139
VSS1140
VSS1143
VSS1147
VSS1148
VSS1149
VSS1150
VSS1151
VSS1152
VSS1153
VSS1154
VSS1157
VSS1159
VSS1160
VSS1162
VSS1164
VSS1166
VSS1169
VSS1172
VSS1173
VSS1174
VSS1175
VSS1176
VSS1177
VSS1178
VSS1179
VSS1181
VSS1182
VSS1183
VSS1184
VSS1186
VSS1187
VSS1189
VSS1190
VSS1191
VSS1192
VSS1194
VSS1196
VSS1199
VSS1201
VSS1202
VSS1203
VSS1204
VSS1205
VSS1206
VSS1207
VSS1209
VSS1211
VSS1212
VSS1213
VSS1214
VSS1215
VSS1216
VSS1218
VSS1219
VSS1221
VSS1222
VSS1226
VSS1227
VSS1228
VSS1229
VSS1230
VSS1231
VSS1233
VSS1234
VSS1236
VSS1238
VSS1239
VSS1240
VSS1241
VSS1242
VSS1243
VSS1244
VSS1245
VSS1246
VSS1247
VSS1248
VSS1249
VSS1250
VSS1251
VSS1252
VSS1253
VSS1254
VSS1255
VSS1256
VSS1268
31/42
VSS1312
VSS1315
VSS1319
VSS1320
VSS1322
VSS1325
VSS1328
VSS1331
VSS1334
VSS1340
VSS1343
VSS1345
VSS1347
VSS1355
VSS1357
VSS1359
VSS1366
VSS1368
VSS1369
VSS1371
VSS1372
VSS1375
VSS1377
VSS1378
VSS1379
VSS1380
VSS1381
VSS1391
VSS1394
VSS1396
VSS1397
VSS1398
VSS1400
VSS1401
VSS1405
VSS1409
VSS1419
VSS1421
VSS1422
VSS1423
VSS1424
VSS1425
VSS1426
VSS1427
VSS1428
VSS1429
VSS1430
VSS1431
VSS1432
VSS1433
VSS1434
VSS1435
VSS1436
VSS1437
VSS1438
VSS1439
VSS1440
VSS1441
VSS1442
VSS1443
VSS1444
VSS1445
VSS1446
VSS1447
VSS1448
VSS1449
VSS1450
VSS1451
VSS1452
VSS1453
VSS1454
VSS1455
VSS1456
VSS1457
VSS1458
VSS1459
VSS1460
VSS1461
VSS1462
VSS1463
VSS1464
VSS1465
VSS1466
VSS1467
VSS1468
VSS1469
VSS1470
VSS1471
VSS1472
VSS1473
VSS1474
VSS1475
VSS1476
VSS1477
VSS1478 VSS1479
VSS1480
VSS1481
VSS1482
VSS1483
VSS1484
VSS1485
VSS1486
VSS1488
VSS1489
VSS1491
VSS1492
VSS1493
VSS1496
VSS1497
VSS1498
VSS1499
VSS1500
VSS1501
VSS1503
VSS1505
VSS1506
VSS1512
VSS1513
VSS1515
VSS1517
VSS1518
VSS1520
VSS1522
VSS1524
VSS1525
VSS1526
VSS1528
VSS1529
VSS1530
VSS1531
VSS1533
VSS1537
VSS1539
VSS1540
VSS1541
VSS1542
VSS1543
VSS1545
VSS1547
VSS1548
VSS1549
VSS1550
VSS1551
VSS1552
VSS1553
VSS1554
VSS1555
VSS1556
VSS1557
VSS1559
VSS1561
VSS1562
VSS1563
VSS1565
VSS1569
VSS1837
VSS1836
VSS1835
VSS1834
SHEETDATE
DEPARTMENT
SIZE
PROJECT DOCUMENT NUMBER REV
REVIEWER
DESIGNER
123
7 3 2 1 6 5 4
E
A
B
C
E
D
C
B
A
7 6 5 4
D
C



Fri Aug 25 14:00:23 2023N/AN/AN/AN/AV0540 OF 312SPR CPU0 POWER - GND (28 OF 30)
SOCKET4677_AZIF0045-P001C01CSIOSMLFSOCKET4677_AZIF0045-P001C01CSIOSMLFSOCKET4677_AZIF0045-P001C01CSIOSMLF
CK8
CK26
CK20
CK16
CK12
CJ80
CJ60
CH89
CH87
CH85
CH83
CH8
CH79
CH73
CH67
CH4
CH20
CH16
CH12
CG9
CG78
CG74
CG72
CG70
CG64
CG62
CG5
CG25
CG23
CG21
CG17
CG13
CG1
CF8
CF71
CF69
CF4
CF20
CF16
CF12
CE78
CE76
CE72
CE66
CE60
CE3
CD8
CD77
CD75
CD61
CD4
CD20
CD16
CD12
CC9
CC74
CC72
CC70
CC62
CC5
CC31
CC17
CC13
CB89
CB87
CB85
CB83
CB81
CB8
CB79
CB73
CB71
CB69
CB67
CB65
CB63
CB59
CB57
CB55
CB53
CB51
CB49
CB47
CB44
CB42
CB40
CB4
CB38
CB36
CB34
CB32
CB28
CB26
CB24
CB22
CB20
CB16
CB12
CA31
CA3
BY8
BY4
BY20
BY16
BY12
BW9
BW5
BW31
BW3
BW29
BW27
BW17
BW13
BV8
BV6
BV4
BV20
BV2
BV18
BV16
BV12
BU7
BU31
BU25
BU23
BU21
BU19
BU15
BT8
BT4
BT20
BT16
BT12
BR90
BR88
BR86
BR84
BR82
BR80
BR76
BR74
BR72
BR70
BR68
BR66
BR64
BR58
BR56
BR54
BR52
BR50
BR48
BR45
BR43
BR41
BR39
BR37
BR35
CK4
CJ76
DB87
DB8
DB77
DB71
DB65
DB57
DB47
DB40
DB4
DB38
DB32
DB28
DB22
DB12
DA88
DA84
DA82
DA80
DA74
DA72
DA66
DA62
DA60
DA58
DA56
DA54
DA50
DA48
DA41
DA37
DA35
DA33
DA31
DA29
DA25
DA23
DA19
CY83
CY81
CY8
CY77
CY73
CY63
CY30
CY26
CY18
CY16
CY12
CW9
CW88
CW84
CW78
CW72
CW5
CW17
CW13
CW1
CV91
CV87
CV83
CV8
CV75
CV4
CV12
CU88
CU84
CU68
CU66
CU60
CU23
CU21
CU19
CT81
CT73
CT69
CT12
CT10
CR90
CR9
CR88
CR84
CR64
CR62
CR5
CR17
CR13
CR11
CR1
CP91
CP87
CP83
CP8
CP77
CP75
CP4
CP18
CP12
CN86
CN84
CN74
CN72
CN70
CN68
CM85
CM83
CM81
CM8
CM79
CM67
CM65
CM61
CM4
CM24
CM20
CM12
CL9
CL82
CL80
CL78
CL74
CL62
CL5
CL17
CL13
CL1
CK81
CK69
CK63
DB75
DB69
DB63
DB59
DB53
DB51
DB44
DB34
DB26
DB20
DB16
DA68
DA43
CY4
CW70
CW33
CV79
CV26
CV16
CU78
CU72
CU25
CT89
CT8
CT4
CT16
CR78
CP79
CP16
CN76
CM22
CM16
DL9
DL88
DL84
DL39
DK91
DK87
DK83
DK81
DK8
DK79
DK77
DK73
DK49
DK4
DK36
DK30
DK16
DJ88
DJ84
DJ82
DJ80
DJ74
DJ72
DJ66
DJ60
DJ56
DJ50
DJ48
DJ43
DJ41
DJ37
DJ31
DJ29
DJ23
DJ19
DH85
DH8
DH77
DH71
DH65
DH57
DH47
DH40
DH4
DH38
DH32
DH28
DH22
DH12
DG9
DG88
DG84
DG80
DG76
DG70
DG5
DG45
DG39
DG33
DG27
DF87
DF8
DF79
DF4
DE88
DE84
DE82
DE76
DE74
DE72
DE68
DE66
DE64
DE62
DE60
DE58
DE56
DE54
DE52
DE50
DE48
DE45
DE43
DE41
DE37
DE35
DE33
DE31
DE29
DE27
DE25
DE23
DE21
DE19
DE17
DD8
DD79
DD4
DC9
DC88
DC84
DC80
DC78
DC76
DC70
DC5
DC45
DC39
DC33
DC27
DL52
DL5
DL17
DL13
DL1
DK67
DK61
DK55
DK42
DK24
DK18
DK12
DJ68
DJ62
DJ54
DJ35
DJ25
DH75
DH69
DH63
DH59
DH53
DH51
DH44
DH34
DH26
DH20
DH16
DG64
DG58
DG52
DG21
DG13
DG1
DF91
DF49
DF16
DF12
DE70
DE39
DD49
DD16
DD12
DC64
DC58
DC52
DC21
DC13
DC1
DB91
U2U2U2
36/42
VSS383
VSS396
VSS542
VSS543
VSS545
VSS546
VSS547
VSS548
VSS549
VSS550
VSS551
VSS552
VSS555
VSS556
VSS557
VSS559
VSS560
VSS561
VSS563
VSS564
VSS565
VSS566
VSS567
VSS568
VSS569
VSS570
VSS573
VSS574
VSS575
VSS576
VSS577
VSS578
VSS579
VSS580
VSS581
VSS582
VSS584
VSS585
VSS586
VSS587
VSS588
VSS589
VSS590
VSS591
VSS592
VSS593
VSS594
VSS596
VSS597
VSS598
VSS599
VSS600
VSS601
VSS602
VSS603
VSS604
VSS605
VSS606
VSS607
VSS608
VSS620
VSS621
VSS622
VSS623
VSS624
VSS625
VSS626
VSS627
VSS628
VSS629
VSS630
VSS631
VSS632
VSS633
VSS634
VSS635
VSS636
VSS637
VSS638
VSS639
VSS640
VSS641
VSS642
VSS643
VSS644
VSS645
VSS646
VSS647
VSS648
VSS649
VSS650
VSS651
VSS652
VSS653
VSS654
VSS655
VSS656
VSS660
VSS661
VSS664
VSS665
VSS666
VSS667
VSS668
VSS669
VSS670
VSS671
VSS672
VSS673
VSS674
VSS675
VSS676
VSS677
VSS678
VSS680
VSS681
VSS682
VSS683
VSS684
VSS685
VSS686
VSS687
VSS688
VSS689
VSS691
VSS692
VSS693
VSS694
VSS695
VSS696
VSS697
VSS698
VSS701
VSS703
VSS704
VSS706
VSS707
VSS708
VSS710
VSS713
VSS716
VSS718
VSS720
VSS721
VSS722
VSS727
VSS728
VSS729
VSS730
VSS731
VSS732
VSS733
VSS734
VSS736
VSS737
VSS740
VSS741
VSS742
VSS743
VSS746
35/42
VSS436
VSS438
VSS471
VSS478
VSS493
VSS514
VSS521
VSS526
VSS534
VSS537
VSS544
VSS553
VSS554
VSS558
VSS562
VSS571
VSS583
VSS595
VSS611
VSS679
VSS690
VSS699
VSS700
VSS702
VSS705
VSS709
VSS711
VSS712
VSS714
VSS715
VSS717
VSS719
VSS744
VSS745
VSS749
VSS750
VSS751
VSS752
VSS754
VSS755
VSS756
VSS757
VSS758
VSS759
VSS760
VSS761
VSS762
VSS763
VSS764
VSS765
VSS766
VSS767
VSS768
VSS769
VSS770
VSS771
VSS772
VSS773
VSS774
VSS775
VSS777
VSS778
VSS779
VSS780
VSS781
VSS782
VSS783
VSS784
VSS785
VSS786
VSS787
VSS788
VSS789
VSS790
VSS792
VSS793
VSS794
VSS795
VSS796
VSS797
VSS800
VSS801
VSS803
VSS804
VSS805
VSS810
VSS811
VSS812
VSS813
VSS814
VSS815
VSS816
VSS818
VSS819
VSS822
VSS823
VSS824
VSS825
VSS826
VSS827
VSS828
VSS831
VSS833
VSS834
VSS836
VSS837
VSS838
VSS840
VSS843
VSS846
VSS848
VSS850
VSS851
VSS852
VSS853
VSS854
VSS855
VSS856
VSS858
VSS859
VSS860
VSS862
VSS863
VSS910
VSS911
VSS912
VSS913
VSS914
VSS915
VSS916
VSS917
VSS918
VSS919
VSS920
VSS921
VSS922
VSS923
VSS924
VSS925
VSS926
VSS927
VSS928
VSS929
VSS930
VSS931
VSS932
VSS933
VSS935
VSS936
VSS937
VSS938
VSS939
VSS940
VSS941
VSS942
VSS943
VSS944
VSS946
VSS947
VSS948
34/42
VSS723
VSS724
VSS725
VSS726
VSS735
VSS738
VSS739
VSS747
VSS748
VSS753
VSS776
VSS791
VSS798
VSS799
VSS802
VSS806
VSS807
VSS808
VSS809
VSS817
VSS820
VSS821
VSS829
VSS830
VSS832
VSS835
VSS839
VSS841
VSS842
VSS844
VSS845
VSS847
VSS849
VSS857
VSS861
VSS867
VSS870
VSS872
VSS880
VSS882
VSS883
VSS887
VSS890
VSS893
VSS894
VSS903
VSS904
VSS905
VSS908
VSS909
VSS949
VSS950
VSS951
VSS952
VSS953
VSS954
VSS956
VSS958
VSS960
VSS961
VSS962
VSS963
VSS964
VSS965
VSS967
VSS970
VSS971
VSS972
VSS974
VSS975
VSS977
VSS978
VSS981
VSS982
VSS983
VSS984
VSS986
VSS987
VSS988
VSS989
VSS991
VSS992
VSS994
VSS995
VSS996
VSS997
VSS999
VSS1001
VSS1004
VSS1007
VSS1008
VSS1009
VSS1010
VSS1011
VSS1012
VSS1015
VSS1017
VSS1018
VSS1019
VSS1020
VSS1022
VSS1024
VSS1027
VSS1030
VSS1031
VSS1032
VSS1033
VSS1034
VSS1035
VSS1037
VSS1038
VSS1039
VSS1040
VSS1041
VSS1042
VSS1043
VSS1044
VSS1045
VSS1046
VSS1049
VSS1053
VSS1055
VSS1056
VSS1057
VSS1058
VSS1061
VSS1062
VSS1065
VSS1066
VSS1067
VSS1068
VSS1069
VSS1070
VSS1071
VSS1072
VSS1073
VSS1074
VSS1075
VSS1076
VSS1078
VSS1079
VSS1080
VSS1081
VSS1082
VSS1083
VSS1084
VSS1085
VSS1086
VSS1087
VSS1088
VSS1089
VSS1090
VSS1091
VSS1092
VSS1093
VSS1094
VSS1095
VSS1096
VSS1098
VSS1099
SHEETDATE
DEPARTMENT
SIZE
PROJECT DOCUMENT NUMBER REV
REVIEWER
DESIGNER
123
7 3 2 1 6 5 4
E
A
B
C
E
D
C
B
A
7 6 5 4
D
C



Fri Aug 25 14:00:24 2023N/AN/AN/AN/AV0541 OF 312SPR CPU0 POWER - GND (29 OF 30)
SOCKET4677_AZIF0045-P001C01CSIOSMLFSOCKET4677_AZIF0045-P001C01CSIOSMLFSOCKET4677_AZIF0045-P001C01CSIOSMLF
AJ88
AJ84
AJ78
AJ74
AJ72
AJ68
AJ66
AJ62
AJ60
AJ56
AJ54
AJ50
AJ48
AJ43
AJ41
AJ37
AJ35
AJ31
AJ29
AJ25
AJ23
AJ19
AH83
AH8
AH79
AH77
AH75
AH71
AH69
AH65
AH63
AH59
AH57
AH53
AH51
AH47
AH44
AH40
AH4
AH38
AH34
AH32
AH28
AH26
AH22
AH20
AH16
AH12
AG9
AG88
AG84
AG76
AG70
AG64
AG58
AG52
AG5
AG45
AG39
AG33
AG27
AG21
AG13
AG1
AF91
AF87
AF81
AF8
AF42
AF4
AF16
AF12
AE88
AE84
AE78
AE76
AE74
AE72
AE70
AE68
AE66
AE64
AE62
AE60
AE58
AE56
AE54
AE52
AE50
AE48
AE45
AE43
AE41
AE39
AE37
AE35
AE33
AE31
AE29
AE27
AE25
AE23
AE21
AE19
AE17
AD83
AD8
AD79
AD42
AD4
AD16
AD12
AC9
AC88
AC84
AC76
AC70
AC64
AC58
AC52
AC5
AC45
AC39
AC33
AC27
AC21
AC13
AC1
AB91
AB87
AB83
AB81
AB8
AB79
AB77
AB75
AB71
AB69
AB65
AB63
AB59
AB57
AB53
AB51
AB47
AB44
AB40
AB4
AB38
AB34
AB32
AB28
AB26
AB22
AB20
AB16
AB12
AA88
AA84
AA82
AW9
AW5
AW13
AW1
AV91
AV87
AV8
AV77
AV4
AV16
AV12
AU88
AU84
AU80
AU76
AU74
AU72
AU70
AU48
AU45
AU41
AU39
AU37
AU31
AU27
AT8
AT79
AT77
AT75
AT71
AT69
AT65
AT63
AT59
AT57
AT53
AT51
AT44
AT40
AT4
AT38
AT34
AT32
AT28
AT26
AT22
AT20
AT16
AT12
AR9
AR88
AR84
AR82
AR78
AR74
AR72
AR68
AR66
AR62
AR60
AR56
AR54
AR50
AR5
AR48
AR43
AR41
AR37
AR35
AR31
AR29
AR25
AR23
AR19
AR13
AR1
AP91
AP87
AP83
AP8
AP79
AP73
AP67
AP61
AP55
AP49
AP42
AP4
AP36
AP30
AP24
AP18
AP16
AP12
AN88
AN84
AN52
AM8
AM77
AM75
AM73
AM71
AM69
AM67
AM65
AM63
AM61
AM59
AM57
AM55
AM53
AM51
AM49
AM47
AM44
AM42
AM40
AM4
AM38
AM36
AM34
AM32
AM30
AM28
AM26
AM24
AM22
AM20
AM18
AM16
AM12
AL9
AL88
AL84
AL82
AL80
AL52
AL5
AL17
AL13
AL1
AK91
AK87
AK83
AK81
AK8
AK79
AK73
AK67
AK61
AK55
AK49
AK42
AK4
AK36
AK30
AK24
AK18
AK16
AK12
BR9
BR33
BR31
BR29
BR27
BR17
BR13
BP8
BP77
BP75
BP73
BP71
BP63
BP4
BP20
BP2
BP16
BP12
BN70
BN62
BN31
BM8
BM77
BM73
BM61
BM4
BM26
BM24
BM22
BM20
BM16
BM12
BL9
BL78
BL72
BL70
BL68
BL5
BL17
BL13
BL1
BK8
BK79
BK75
BK71
BK65
BK4
BK20
BK16
BK12
BJ90
BJ88
BJ86
BJ84
BJ82
BJ80
BJ68
BJ62
BH83
BH81
BH8
BH77
BH73
BH67
BH4
BH20
BH16
BH12
BG9
BG70
BG5
BG25
BG23
BG21
BG17
BG13
BG1
BF83
BF8
BF79
BF75
BF73
BF63
BF61
BF4
BF20
BF16
BF12
BE84
BE78
BE76
BE74
BE68
BE66
BE64
BD89
BD85
BD81
BD8
BD4
BD20
BD16
BD12
BC9
BC88
BC86
BC84
BC78
BC76
BC72
BC66
BC62
BC5
BC17
BC13
BC1
BB91
BB87
BB83
BB8
BB79
BB77
BB71
BB69
BB63
BB4
BB26
BB24
BB22
BB20
BB16
BB12
BB10
BA88
BA84
BA74
BA64
BA60
BA17
AY83
AY81
AY8
AY79
AY77
AY71
AY4
AY16
AY12
AW88
AW84
AW82
AW80
AW72
AW68
AW66
AW62
AW25
AW23
AW21
BR5
U2U2U2
37/42
VSS0
VSS356
VSS357
VSS358
VSS360
VSS361
VSS362
VSS363
VSS364
VSS365
VSS366
VSS367
VSS369
VSS370
VSS371
VSS372
VSS373
VSS374
VSS375
VSS376
VSS377
VSS393
VSS394
VSS395
VSS397
VSS398
VSS399
VSS400
VSS401
VSS402
VSS403
VSS404
VSS405
VSS406
VSS407
VSS408
VSS409
VSS410
VSS411
VSS412
VSS413
VSS414
VSS415
VSS416
VSS417
VSS418
VSS419
VSS420
VSS421
VSS422
VSS423
VSS424
VSS425
VSS426
VSS427
VSS428
VSS429
VSS430
VSS431
VSS432
VSS433
VSS434
VSS435
VSS437
VSS439
VSS440
VSS441
VSS442
VSS443
VSS444
VSS445
VSS446
VSS447
VSS448
VSS449
VSS450
VSS451
VSS452
VSS453
VSS454
VSS455
VSS456
VSS457
VSS458
VSS459
VSS460
VSS461
VSS462
VSS463
VSS464
VSS465
VSS466
VSS467
VSS468
VSS469
VSS470
VSS472
VSS473
VSS474
VSS475
VSS476
VSS477
VSS479
VSS480
VSS481
VSS482
VSS483
VSS484
VSS485
VSS486
VSS487
VSS488
VSS489
VSS490
VSS491
VSS492
VSS494
VSS495
VSS496
VSS497
VSS498
VSS499
VSS500
VSS501
VSS502
VSS503
VSS504
VSS505
VSS506
VSS507
VSS508
VSS509
VSS510
VSS511
VSS512
VSS513
VSS515
VSS516
VSS517
VSS518
VSS519
VSS520
VSS522
VSS523
VSS524
VSS525
VSS527
VSS528
VSS529
VSS530
VSS531
VSS532
VSS533
VSS535
VSS536
VSS538
VSS539
VSS540
VSS541
VSS572
39/42
VSS38
VSS39
VSS40
VSS41
VSS42
VSS43
VSS44
VSS45
VSS46
VSS47
VSS48
VSS49
VSS50
VSS51
VSS52
VSS53
VSS54
VSS55
VSS56
VSS57
VSS58
VSS59
VSS60
VSS61
VSS62
VSS63
VSS64
VSS65
VSS66
VSS67
VSS68
VSS69
VSS70
VSS71
VSS72
VSS73
VSS74
VSS75
VSS76
VSS77
VSS78
VSS79
VSS80
VSS81
VSS82
VSS83
VSS84
VSS85
VSS86
VSS87
VSS88
VSS89
VSS90
VSS91
VSS92
VSS93
VSS94
VSS95
VSS96
VSS97
VSS98
VSS99
VSS100
VSS101
VSS102
VSS103
VSS104
VSS105
VSS106
VSS107
VSS108
VSS109
VSS110
VSS111
VSS112
VSS113
VSS114
VSS115
VSS116
VSS117
VSS118
VSS119
VSS120
VSS121
VSS122
VSS123
VSS124
VSS125
VSS126
VSS127
VSS128
VSS129
VSS130
VSS131
VSS132
VSS133
VSS134
VSS135
VSS136
VSS137
VSS138
VSS139
VSS140
VSS141
VSS142
VSS143
VSS144
VSS145
VSS146
VSS147
VSS148
VSS149
VSS150
VSS151
VSS152
VSS153
VSS154
VSS155
VSS156
VSS157
VSS158
VSS159
VSS160
VSS161
VSS162
VSS163
VSS164
VSS165
VSS166
VSS167
VSS168
VSS169
VSS170
VSS171
VSS172
VSS173
VSS174
VSS175
VSS176
VSS177
VSS178
VSS179
VSS180
VSS181
VSS182
VSS183
VSS184
VSS185
VSS186
VSS187
VSS188
VSS189
VSS190
VSS191
VSS192
VSS193
VSS194
VSS195
VSS196
VSS197
38/42
VSS198
VSS199
VSS200
VSS201
VSS202
VSS203
VSS204
VSS205
VSS206
VSS207
VSS208
VSS209
VSS210
VSS211
VSS212
VSS213
VSS214
VSS215
VSS216
VSS217
VSS218
VSS219
VSS220
VSS221
VSS222
VSS223
VSS224
VSS225
VSS226
VSS227
VSS228
VSS229
VSS230
VSS231
VSS232
VSS233
VSS234
VSS235
VSS236
VSS237
VSS238
VSS239
VSS240
VSS241
VSS242
VSS243
VSS244
VSS245
VSS246
VSS247
VSS248
VSS249
VSS250
VSS251
VSS252
VSS253
VSS254
VSS255
VSS256
VSS257
VSS258
VSS259
VSS260
VSS261
VSS262
VSS263
VSS264
VSS265
VSS266
VSS267
VSS268
VSS269
VSS270
VSS271
VSS272
VSS273
VSS274
VSS275
VSS276
VSS277
VSS278
VSS279
VSS280
VSS281
VSS282
VSS283
VSS284
VSS285
VSS286
VSS287
VSS288
VSS289
VSS290
VSS291
VSS292
VSS293
VSS294
VSS295
VSS296
VSS297
VSS298
VSS299
VSS300
VSS301
VSS302
VSS303
VSS304
VSS305
VSS306
VSS307
VSS308
VSS309
VSS310
VSS311
VSS312
VSS313
VSS314
VSS315
VSS316
VSS317
VSS318
VSS319
VSS320
VSS321
VSS322
VSS323
VSS324
VSS325
VSS326
VSS327
VSS328
VSS329
VSS330
VSS331
VSS332
VSS333
VSS334
VSS335
VSS336
VSS337
VSS338
VSS339
VSS340
VSS341
VSS342
VSS343
VSS344
VSS345
VSS346
VSS347
VSS348
VSS349
VSS350
VSS351
VSS352
VSS353
VSS354
VSS355
VSS359
VSS368
SHEETDATE
DEPARTMENT
SIZE
PROJECT DOCUMENT NUMBER REV
REVIEWER
DESIGNER
123
7 3 2 1 6 5 4
E
A
B
C
E
D
C
B
A
7 6 5 4
D
C



Fri Aug 25 14:00:25 2023N/AN/AN/AN/AV0542 OF 312SPR CPU0 POWER - GND (30 OF 30)
SOCKET4677_AZIF0045-P001C01CSIOSMLFSOCKET4677_AZIF0045-P001C01CSIOSMLFSOCKET4677_AZIF0045-P001C01CSIOSMLF
E39
E5
D83
D81
D71
D69
D61
D6
D59
D57
D55
D53
D51
D49
D47
D44
D42
D40
D38
D36
D34
D32
D30
D28
D26
D24
D22
D20
D18
D16
D14
D12
D10
D8
D79
D67
D65
D63
C86
C82
C80
C78
C74
C72
C52
C5
C45
C39
B87
B83
B75
B67
B61
B6
B55
B49
B42
B36
B30
B24
B18
B12
A62
A60
A56
A54
A50
A41
A37
A35
A31
A29
A25
A23
A19
A17
A13
A11
N70
N58
N52
N45
N33
N27
N15
M83
M81
L78
L76
L74
L72
L68
L66
L64
L62
L60
L56
N64
L54
L52
L50
L5
L48
N39
L45
L43
L41
L39
N21
L37
L35
L33
L31
L29
L27
M8
L25
L23
M49
M42
M4
L21
L17
M12
L90
L9
L88
L15
L13
K85
K83
K8
L70
K77
J86
J84
J78
J76
L58
J58
J52
J45
J33
J27
J15
H81
H8
H79
H71
H69
H63
H6
H59
H53
H47
H44
H40
H4
L19
H38
H34
H32
H28
H26
H22
H20
H16
H10
G90
K49
K42
G88
G84
K2
K14
K12
J9
J88
G72
G62
G56
G54
G50
J70
G43
J64
G41
G37
G31
G29
J5
G23
J39
G19
G13
F89
F83
J21
F49
F4
F36
F30
F24
H75
H65
H57
H51
H2
H14
G74
G7
G68
G66
G60
G48
G35
G3
G25
G17
G11
F79
F73
F67
F61
F6
F55
F42
F18
F12
E86
E76
E78
E74
E52
Y73
Y8
Y55
Y49
Y67
Y61
Y42
Y4
Y36
Y30
Y24
Y18
Y16
Y12
W9
W88
W84
W39
W52
W5
V87
V8
V79
V77
W13
W1
V91
V75
V69
V67
V65
V63
V73
V71
V61
V59
V57
V55
V53
V51
V47
V44
V42
V40
V49
V4
V38
V36
V34
V32
V30
V28
V26
V24
V22
V20
V18
V16
V12
U88
U84
U82
U39
T83
T8
T79
T73
U52
T67
T61
T42
T4
T30
T24
R9
R88
R84
R78
R74
R72
R68
R62
R56
T55
T49
R54
R50
T36
R5
R43
R41
R37
T18
T16
T12
R35
R31
R29
R25
R17
R13
P91
P87
R66
P8
R60
P77
P75
P69
P65
R48
P63
P59
P53
P47
P44
P40
P4
R23
R19
P38
P34
R1
P28
P26
P22
P20
P16
P12
P71
N88
N84
N82
N80
P57
N78
P51
N76
P32
AA80
AA78
AA74
AA72
AA68
AA66
AA62
AA60
AA56
AA54
AA50
AA48
AA43
AA41
AA37
AA35
AA31
AA29
AA25
AA23
AA19
U2U2U2
42/42
VSS1
VSS2
VSS3
VSS4
VSS5
VSS6
VSS7
VSS8
VSS9
VSS10
VSS11
VSS12
VSS13
VSS14
VSS15
VSS16
VSS378
VSS379
VSS380
VSS381
VSS382
VSS384
VSS385
VSS386
VSS387
VSS388
VSS389
VSS390
VSS391
VSS392
VSS609
VSS610
VSS612
VSS613
VSS614
VSS615
VSS616
VSS617
VSS618
VSS619
VSS657
VSS658
VSS659
VSS662
VSS663
VSS864
VSS865
VSS866
VSS868
VSS869
VSS871
VSS873
VSS874
VSS875
VSS876
VSS877
VSS878
VSS879
VSS881
VSS884
VSS885
VSS886
VSS888
VSS889
VSS891
VSS892
VSS895
VSS896
VSS897
VSS898
VSS899
VSS900
VSS901
VSS902
VSS906
VSS907
VSS1125
VSS1271
41/42
VSS1126
VSS1129
VSS1131
VSS1272
VSS1273
VSS1494
VSS1495
VSS1502
VSS1504
VSS1507
VSS1508
VSS1509
VSS1510
VSS1511
VSS1514
VSS1516
VSS1519
VSS1521
VSS1523
VSS1527
VSS1532
VSS1534
VSS1535
VSS1536
VSS1538
VSS1544
VSS1546
VSS1558
VSS1560
VSS1564
VSS1567
VSS1570
VSS1571
VSS1572
VSS1573
VSS1574
VSS1575
VSS1576
VSS1577
VSS1578
VSS1579
VSS1580
VSS1581
VSS1582
VSS1583
VSS1584
VSS1585
VSS1586
VSS1587
VSS1588
VSS1589
VSS1590
VSS1591
VSS1592
VSS1593
VSS1594
VSS1595
VSS1596
VSS1597
VSS1598
VSS1599
VSS1600
VSS1601
VSS1602
VSS1603
VSS1604
VSS1605
VSS1606
VSS1607
VSS1608
VSS1609
VSS1610
VSS1611
VSS1612
VSS1613
VSS1614
VSS1615
VSS1616
VSS1617
VSS1618
VSS1619
VSS1620
VSS1621
VSS1622
VSS1623
VSS1624
VSS1625
VSS1626
VSS1627
VSS1628
VSS1629
VSS1630
VSS1631
VSS1632
VSS1633
VSS1634
VSS1635
VSS1636
VSS1637
VSS1638
VSS1639
VSS1640
VSS1641
VSS1642
VSS1643
VSS1644
VSS1645
VSS1646
VSS1647
VSS1648
VSS1649
VSS1650
VSS1651
VSS1652
VSS1653
VSS1654
VSS1655
VSS1656
VSS1657
VSS1658
VSS1659
VSS1660
VSS1661
VSS1662
VSS1663
VSS1664
VSS1665
VSS1666
VSS1667
VSS1668
VSS1669
VSS1670
VSS1671
VSS1672
VSS1673
VSS1674
VSS1675
VSS1676
VSS1677
VSS1678
VSS1679
VSS1680
VSS1681
VSS1682
VSS1683
VSS1684
VSS1685
VSS1686
VSS1687
VSS1688
VSS1689
VSS1691
VSS1692
VSS1693
VSS1694
VSS1695
40/42
VSS17
VSS18
VSS19
VSS20
VSS21
VSS22
VSS23
VSS24
VSS25
VSS26
VSS27
VSS28
VSS29
VSS30
VSS31
VSS32
VSS33
VSS34
VSS35
VSS36
VSS37
VSS1690
VSS1696
VSS1697
VSS1698
VSS1699
VSS1700
VSS1701
VSS1702
VSS1703
VSS1704
VSS1705
VSS1706
VSS1707
VSS1708
VSS1709
VSS1710
VSS1711
VSS1712
VSS1713
VSS1714
VSS1715
VSS1716
VSS1717
VSS1718
VSS1719
VSS1720
VSS1721
VSS1722
VSS1723
VSS1724
VSS1725
VSS1726
VSS1727
VSS1728
VSS1729
VSS1730
VSS1731
VSS1732
VSS1733
VSS1734
VSS1735
VSS1736
VSS1737
VSS1738
VSS1739
VSS1740
VSS1741
VSS1742
VSS1743
VSS1744
VSS1745
VSS1746
VSS1747
VSS1748
VSS1749
VSS1750
VSS1751
VSS1752
VSS1753
VSS1754
VSS1755
VSS1756
VSS1757
VSS1758
VSS1759
VSS1760
VSS1761
VSS1762
VSS1763
VSS1764
VSS1765
VSS1766
VSS1767
VSS1768
VSS1769
VSS1770
VSS1771
VSS1772
VSS1773
VSS1774
VSS1775
VSS1776
VSS1777
VSS1778
VSS1779
VSS1780
VSS1781
VSS1782
VSS1783
VSS1784
VSS1785
VSS1786
VSS1787
VSS1788
VSS1789
VSS1790
VSS1791
VSS1792
VSS1793
VSS1794
VSS1795
VSS1796
VSS1797
VSS1798
VSS1799
VSS1800
VSS1801
VSS1802
VSS1803
VSS1804
VSS1805
VSS1806
VSS1807
VSS1808
VSS1809
VSS1810
VSS1811
VSS1812
VSS1813
VSS1814
VSS1815
VSS1816
VSS1817
VSS1818
VSS1819
VSS1820
VSS1821
VSS1822
VSS1823
VSS1824
VSS1825
VSS1826
VSS1827
VSS1828
VSS1829
VSS1830
VSS1831
VSS1832
VSS1833
SHEETDATE
DEPARTMENT
SIZE
PROJECT DOCUMENT NUMBER REV
REVIEWER
DESIGNER
123
7 3 2 1 6 5 4
E
A
B
C
E
D
C
B
A
7 6 5 4
D
C



43 OF 312V05Fri Aug 25 14:00:26 2023N/AN/AN/AN/ASPR CPU0 IBL/S3M SERIAL RESISTORS
15434643154621543 4621515430402LF0402LFPD_JTAG_CPU0_PLD_TCKPWRGD_PLT_AUX_CPU1_LVT3PWRGD_PLT_AUX_CPU0_LVT3CHIP 1/16W10K1%10K1/16WCHIP1%0402LF1%CHIP 1/16W10K10KCHIP 1/16W0402LF1%PD_JTAG_CPU1_PLD_TCK33.21%CHIP 1/16W0402LFPWRGD_PLT_AUX_CPU1_LVT3_R PWRGD_PLT_AUX_CPU1_LVT3CHIP 1/16W1%33.20402LFPWRGD_PLT_AUX_CPU0_LVT3_R PWRGD_PLT_AUX_CPU0_LVT3
21R1227
21R1226
21
21
21R68
21R67
SHEETDATE
DEPARTMENT
SIZE
PROJECT DOCUMENT NUMBER REV
REVIEWER
DESIGNER
123
7 3 2 1 6 5 4
E
A
B
C
E
D
C
B
A
7 6 5 4
D
IN
IN
IN
IN
IN
OUT
OUT
IN
R70
R69
C



N/AN/AN/AN/AV0544 OF 312Fri Aug 25 14:00:27 2023SPR CPU1 MISC:CLK/JTAG/STRAPS(1/30)
20911920620620620620620620620611911923023012812823023012812811911911911921411921411921444119214119214119119119119119119133119119209441319713313132132131311341821313213IOCLK_25M_NSSC_CPU1_DNCPU1_RSVD<153>PUD_XTAL_CPU1_MODE0CLK_100M_DB2000_CPU1_BCLK0_DNCLK_100M_DB2000_CPU1_BCLK1_DPCLK_100M_DB2000_CPU1_BCLK1_DNCLK_100M_DB2000_CPU1_BCLK0_DPCLK_100M_DB2000_CPU1_BCLK2_DNCLK_100M_DB2000_CPU1_BCLK2_DPCLK_100M_DB2000_CPU1_BCLK3_DNCLK_100M_DB2000_CPU1_BCLK3_DPPD_CPU1_BIST_ENABLEH_CPU1_BMCINIT_LVC1I3C_SPD_DDRABCD_CPU1_SCLI3C_SPD_DDRABCD_CPU1_SDARST_CPU1_DRAM_AB_NRST_CPU1_DRAM_CD_NI3C_SPD_DDREFGH_CPU1_SCLI3C_SPD_DDREFGH_CPU1_SDARST_CPU1_DRAM_EF_NRST_CPU1_DRAM_GH_NPD_CPU1_DMIMODE_OVERRIDEPU_CPU1_FRMAGENTPU_CPU1_LEGACY_SKTTP_CPU1_BR23PECI_CPU1_GTL_RFM_CPU1_PKGID2FM_CPU1_PKGID1FM_CPU1_PKGID0H_CPU1_PRDY_QS_GTL_R_NH_CPU1_PREQ_QS_GTL_R_NPD_CPU1_PROCDIS_COD_GTL_NFM_CPU1_PROC_ID1FM_CPU1_PROC_ID0PUD_XTAL_CPU1_MODE1CPU1_RSVD<157>PD_EXT_CLK_SEL_CPU1CPU1_RSVD<82>CPU1_RSVD<85>PU_CPU1_SAFE_MODE_BOOTPU_CPU1_SOCKET_ID2PU_CPU1_SOCKET_ID1PU_CPU1_SOCKET_ID0JTAG_DBP_CPU1_GTL_R_TCKJTAG_DBP_CPU1_GTL_R_TDIJTAG_CPU1_MUX_GTL_TDOJTAG_DBP_CPU1_QS_GTL_R_TMSPU_CPU1_TXT_AGENTPD_CPU1_TXT_PLTENCLK_25M_NSSC_CPU1_DPSMLFSOCKET4677_AZIF0045-P001C01CSPD_CPU1_PROCDIS_COD_GTL_NPECI_CPU_GTL33.2 0402LF1%CHIP1/16WJTAG_MUX_CPU1_GTL_TDICHIP1%200 0402LF1/16WEMPTY1/16W1%2400402LFH_CPU_PRDY_QS_GTL_N0402LF1/16WCHIP1%10H_CPU_PREQ_QS_GTL_N1/16WCHIP0402LF1%100JTAG_DBP_CPU_GTL_TCK0402LF1%100JTAG_DBP_CPU_QS_GTL_TMS0402LF1/16WCHIP1%100
R61
R62
R63
R64
R65
R66
G5
D4
CL72
CJ72
CE70
CD71
BY24
BR23
CT18
CU17
BY22
BT22
CY32
CW31
CT20
BT26
BR25 BW25
BV24
BT24
CT61
CY61
CW60
AU23
DA52
BH71
BG72
AV22
BP26
BN64
AY63
BL64
BH24
CY59
AU17
AW17
CY55
CY42
AV51
AU50
BN23
AT18
DA27
CW27
AV28
AU29
CW29
CY28
AV30
AT30
U1
1/42
XTAL_CLK_DN
RSVD157
RSVD120
BCLK0_DN
BCLK1_DP
BCLK1_DN
BCLK0_DP
BCLK2_DN
BCLK2_DP
BCLK3_DN
BCLK3_DP
BIST_ENABLE
BMCINIT
DDR0123_SPDSCL
DDR0123_SPDSDA
DDR01_RESET_N
DDR23_RESET_N
DDR4567_SPDSCL
DDR4567_SPDSDA
DDR45_RESET_N
DDR67_RESET_N
DMIMODE_OVERRIDE
FRMAGENT
LEGACY_SKT
RSVD72
PECI
PKG_ID2
PKG_ID1
PKG_ID0
PRDY_N
PREQ_N
PROCDIS_N
PROC_ID1
PROC_ID0
RSVD108
RSVD161
RSVD76
RSVD88
RSVD91
SAFE_MODE_BOOT
SOCKET_ID2
SOCKET_ID1
SOCKET_ID0
TCK
TDI
TDOTMS
TXT_AGENT
TXT_PLTEN
XTAL_CLK_DP
2
1
21 21
21
21 21 21
SHEETDATE
DEPARTMENT
SIZE
PROJECT DOCUMENT NUMBER REV
REVIEWER
DESIGNER
123
7 3 2 1 6 5 4
E
A
B
C
E
D
C
B
A
7 6 5 4
D
IN
ININ
OUT
IN
IN
IN
OUT
ININ
IN
IN
INININOUTOUTOUT
IN
OUTOUT
IN
ININ
OUTOUTOUTOUT
BI
OUT
IN
IN
IN
IN
IN
IN
IN
IN
IN
ININ
OUTBI
OUTBI
IN
R1270
C



20210818 MODIFY FOR GT
Fri Aug 25 14:00:27 2023N/AEAGLE_STERAMN/AN/AN/AV0545 OF 312PVNN_TERM_CPU1SPR CPU1 MISC:SMBUS/SVID/ERRORS(2/30)
2362361271271191332221251251414127127119125125125125235235235121121117123123122122131 14225225225118
28429245452962964545284292
45284 29245296284 29245284 29229645296TP_H_CPU1_PMSYNC_PCH_INTRP_RSMB_S3M_CPU1_PIROM_3V3AUX_SCLSMB_S3M_CPU1_PIROM_3V3AUX_SDAPD_PIROM_CPU1_ADDR1PD_PIROM_CPU1_ADDR2PU_TAP_ODT_CPU1_ENFM_CPU1_SKTOCC_LVT3_NCPU1_RSVD<107>RST_CPU1_LVC1_NPWRGD_CPU1_LVC1H_CPU0_PMDOWN_CPU1TP_H_SBLINK2_CPU1_PMSYNCTP_H_SBLINK3_CPU1_PMSYNCTP_H_SBLINK4_CPU1_PMSYNCTP_H_SBLINK5_CPU1_PMSYNCTP_H_SBLINK6_CPU1_PMSYNCTP_H_SBLINK7_CPU1_PMSYNCTP_H_CPU1_PMDOWN_PCH_RH_CPU0_PMSYNC_CPU1TP_H_SBLINK2_CPU1_PMDOWNTP_H_SBLINK3_CPU1_PMDOWNTP_H_SBLINK4_CPU1_PMDOWNTP_H_SBLINK5_CPU1_PMDOWNTP_H_SBLINK6_CPU1_PMDOWNTP_H_SBLINK7_CPU1_PMDOWNPU_PIROM_CPU1_SM_WPSMB_S3M_CPU1_PIROM_3V3AUX_SDA_R1SMB_S3M_CPU1_PIROM_3V3AUX_SCL_R1PU_PIROM_CPU1_ADDR0PD_CPU1_ENH_MCECC_DISPWRGD_DRAMPWRGD_CPU1_GH_LVC1_RPWRGD_DRAMPWRGD_CPU1_EF_LVC1_RPWRGD_DRAMPWRGD_CPU1_CD_LVC1_RPWRGD_DRAMPWRGD_CPU1_AB_LVC1_RFM_PEHPCPU1_ALERT_NSMB_PEHPCPU1_GTL_SDASMB_PEHPCPU1_GTL_SCLH_CPU1_THERMTRIP_LVC1_R_NTP_EV_CPU1_EXT_BGREFSVID_DIO1_CPU1SVID_DIO0_CPU1SVID_CLK1_CPU1SVID_CLK0_CPU1SVID_ALERT1_CPU1_NSVID_ALERT0_CPU1_NCPU1_RSVD<98>CPU1_RSVD<65>CPU1_RSVD<64>CPU1_RSVD<6>CPU1_RSVD<54>CPU1_RSVD<4>CPU1_RSVD<27>CPU1_RSVD<25>CPU1_RSVD<15>CPU1_RSVD<144>CPU1_RSVD<140>CPU1_RSVD<139>CPU1_RSVD<135>CPU1_RSVD<126>CPU1_RSVD<120>CPU1_RSVD<115>CPU1_RSVD<110>H_CPU1_PROCHOT_LVC1_NH_CPU1_PM_FAST_WAKE_NH_CPU1_NMI_LVC1_NH_CPU1_MEMTRIP_LVC1_R_NH_CPU1_MEMHOT_OUT_LVC1_R_NH_CPU1_MEMHOT_IN_LVC1_NFM_CPU_FBRK_DEBUG_R_NH_CPU1_ERR0_LVC1_R_NH_CPU1_ERR1_LVC1_R_NH_CPU1_ERR2_LVC1_R_NH_CPU1_CATERR_LVC1_R_NSOCKET4677_AZIF0045-P001C01CSIOSMLF
SVID_ALERT0_CPU1_R_NSVID_DIO1_CPU1_RSVID_ALERT1_CPU1_R_N1/16W1001%49.949.9 CHIP1/16W0402LFSVID_DIO0_CPU1_R
0402LF0402LF33.2
1001/16W0402LF1%CHIPCHIP1%
33.21%CHIP1/16WCHIP1%0402LF
1%0402LF1/16W
SVID_ALERT0_CPU1_R_N0402LFCHIP1/16W1%200SVID_ALERT1_CPU1_R_N1/16W CHIP1%200SVID_CLK0_CPU1_R0402LF5%0SVID_DIO0_CPU1_R0402LF1/16WCHIP5%0SVID_CLK1_CPU1_R5%0SVID_DIO1_CPU1_R5%0402LF0
0402LFCHIP
R1935
R1934
R57
R56
R55
R60
R59
R58
CW68
CW25
CW23
CV24
CR23
CN62
CM63
CL64
CL21
CJ62
CH22
BP69
BP67
BJ70
AY65
AY26
AV59
AV26
AU25
AT24
AV20
CR72
CM71
CU70
CP71
CT71
CR70
BD22
AY22
BF22
BL62
AY20
BL25
BD26
BF26
BH26
BJ25
BK26
CG66
BH61
AU19
DA39
CF24
CH24
CR19
CE25
CH26
CL25
CN25
CP20
CY40
CC25
CE23
CV18
CD24
CM26
CP26
CW39
AV18
AV24
CF26
AU21
AV57
CW45
CY44
F47
A43
BY26
CA25
BV26
BP24
U1
2/42
THERMTRIP_N
RSVD19
TAP_ODT_EN
SVIDDATA1
SVIDDATA0
SVIDCLK1
SVIDCLK0
SVIDALERT1_N
SVIDALERT0_N
SKTOCC_N
RSVD104
RSVD70
RSVD69
RSVD6
RSVD59
RSVD4
RSVD29
RSVD27
RSVD15
RSVD150
RSVD146
RSVD145
RSVD141
RSVD132
RSVD126
RSVD121
RSVD116
RSVD113
RESET_N
PWRGOOD
PROCHOT_N
PMSYNC_PCH
PMSYNC0
PMSYNC1
PMSYNC2
PMSYNC3
PMSYNC4
PMSYNC5
PMSYNC6
PMFAST_WAKE_N
PMDOWN_PCH
PMDOWN0
PMDOWN1
PMDOWN2
PMDOWN3
PMDOWN4
PMDOWN5
PMDOWN6
PIROM_SM_WP
PIROM_SDA
PIROM_SCL
PIROM_AD0
PIROM_AD1
PIROM_AD2
NMI
MEMTRIP_N
MEMHOT_OUT_N
MEMHOT_IN_N
FBRK_N
ERROR_N0
ERROR_N1
ERROR_N2
RSVD96
DDR67_DRAM_PWR_OK
DDR45_DRAM_PWR_OK
DDR23_DRAM_PWR_OK
DDR01_DRAM_PWR_OK
CXPSMBUS_ALERT_N
CXPSMBUSSDA
CXPSMBUSSCL
CATERR_N
21 21
21
21
21
21
21 21 21
21 21 21
R557
R558
R560
R559
SHEETDATE
DEPARTMENT
SIZE
PROJECT DOCUMENT NUMBER REV
REVIEWER
DESIGNER
123
7 3 2 1 6 5 4
E
A
B
C
E
D
C
B
A
7 6 5 4
D
IN
BI
IN
IN
OUT
OUT
OUT
IN
OUT
BIOUTIN
BIOUTIN
OUTOUTOUT
BIININOUTOUTOUTIN
IN
BI
ININ
IN
OUTBI
IN
IN
OUT
IN
IN
OUTIN
IN
IN
IN
C



CPU1 SPI FLASH
N/AN/AV0546 OF 312Fri Aug 25 14:00:29 2023N/AN/ASPR CPU1 MISC:(3 OF 30)
80808023623612012012012012012043 8021343NC_FM_IBL_ADR_TRIGGER_CPU1_RNC_FM_IBL_ADR_COMPLETE_CPU1_RNC_FM_IBL_ADR_ACK_CPU1PU_S3M_CPU1_CPLD_STATUSFM_S3M_CPU1_CPLD_CONFIG_NPU_S3M_CPU1_CPLD_CONFDSMB_S3M_CPU1_SDASMB_S3M_CPU1_SCLFM_S3M_CPU1_LVC1_GPIO_0FM_S3M_CPU1_LVC1_GPIO_1FM_S3M_CPU1_LVC1_GPIO_2FM_S3M_CPU1_LVC1_GPIO_3FM_S3M_CPU1_LVC1_GPIO_4TP_SGPIO_S3M_CPU1_GSXDLOADTP_I2C_S3M_RTC_CPU1_RST_NTP_I2C_S3M_RTC_CPU1_SDATP_CPU1_IBL_GRST_WARN_CPU1_NTP_PWRGD_S0_PWROK_CPU1_LVC1TP_SGPIO_S3M_CPU1_GSXDINTP_SGPIO_S3M_CPU1_GSXDOUTTP_SGPIO_S3M_CPU1_GSXCLKPUD_PCH_BOOT_MODE_CPU1TP_SGPIO_S3M_CPU1_GSXRST_NNC_ESPI_IBL_CPU1_IO3NC_ESPI_IBL_CPU1_IO0NC_ESPI_IBL_CPU1_IO1NC_ESPI_IBL_CPU1_CS1_NNC_ESPI_IBL_CPU1_OE_NNC_ESPI_IBL_CPU1_RESET_NNC_ESPI_IBL_CPU1_CLKNC_ESPI_IBL_CPU1_CS0_NNC_ESPI_IBL_CPU1_ALERT0_NTP_I3C_MNG3_BMC_SW_SCLNC_SPI_S3M_CPU1_IO2_LVC1_RNC_ESPI_IBL_CPU1_ALERT1_NNC_SPI_S3M_CPU1_IO3_LVC1_RNC_SPI_S3M_CPU1_CLK_LVC1_RTP_I3C_MNG3_BMC_SW_SDANC_SPI_CPU1_NCM_OE_NNC_SPI_S3M_CPU1_CS0_LVC1_R_NNC_SPI_S3M_CPU1_OE_LVC1_R_NNC_SPI_CPU1_NCM_IO0NC_SPI_S3M_CPU1_IO0_LVC1_RNC_SPI_CPU1_NCM_CS0_NNC_SPI_CPU1_NCM_IO1NC_SPI_S3M_CPU1_IO1_LVC1_RTP_FM_WAKE_CPU1_NNC_SPI_S3M_CPU1_CS1_LVC1_R_NNC_UART_IBL_CPU1_RTSNC_UART_IBL_CPU1_RXDPD_JTAG_CPU1_PLD_TCKFM_S3M_CPU1_CPLD_CRC_ERRORTP_FM_IBL_SLPS5_CPU1_R_NNC_UART_IBL_CPU1_CTSNC_UART_IBL_CPU1_TXDTP_JTAG_CPU1_PLD_TMSTP_JTAG_CPU1_PLD_TDITP_FM_IBL_SLPS3_CPU1_R_NTP_JTAG_CPU1_PLD_TDO_RNC_ESPI_IBL_CPU1_IO2TP_FM_IBL_SLPS4_CPU1_R_NTP_CPU1_SSC_SYNCNC_SPI_CPU1_NCM_CLKTP_I2C_S3M_RTC_CPU1_SCLTP_FM_IBL_PWRBTN_CPU1_NTP_FM_SYS_RST_CPU1_NPWRGD_PLT_AUX_CPU1_LVT3SOCKET4677_AZIF0045-P001C01CSIOSMLF
AY69
AV69
CF61
CY22
CH65
CK65
CJ64
CY71
CY69
CW21
CV71
CV69
CV22
CT24
CT22
CR21
CP24
CP22
CN23
CN21
CL66
CL23
CK24
CK22
CJ66
CJ25
CJ23
CJ21
CH71
CH63
CF65
CF63
CD65
BM63
BK63
BJ64
BH65
BH63
BG64
BG62
BF65
BE62
BE25
BD65
BD63
BD61
BC64
BC25
BB67
BB61
BA68
BA66
BA62
AY67
AY61
AW70
AW64
AW19
AV63
AU64
AU62
AV71
BA70
CY20
CD63
CE64
CV20
U1
3/42
TEST_3
TEST_2
TEST_1
SMB_DATA
SMB_CLK
PARTITION_ID0
PARTITION_ID1
TEST_7
TEST_8
RSVD25
RSVD105
RSVD103
RSVD102
RSVD101
RSVD100
RSVD98
RSVD94
RSVD93
TEST_6
RSVD86
RSVD64
RSVD61
RSVD58
RSVD56
RSVD55
RSVD53
RSVD52
RSVD50
RSVD48
RSVD47
RSVD42
RSVD41
RSVD40
RSVD39
RSVD38
RSVD36
RSVD35
RSVD34
RSVD33
RSVD32
RSVD30
RSVD28
RSVD24
RSVD23
RSVD20
RSVD156
RSVD155
TEST_5
CD_INIT_ERROR
RSVD144
RSVD143
RSVD142
RSVD140
RSVD137
RSVD136
RSVD131
RSVD128
RSVD127
RSVD12
RSVD124
RSVD123
RSVD117
RSVD11
RSVD114
RSVD110
RSVD109
PLT_AUX_PWRGOOD
SHEETDATE
DEPARTMENT
SIZE
PROJECT DOCUMENT NUMBER REV
REVIEWER
DESIGNER
123
7 3 2 1 6 5 4
E
A
B
C
E
D
C
B
A
7 6 5 4
D
IN IN
IN
OUT
IN
OUTININ
OUTOUTOUTOUTOUT
BI
C



N/AFri Aug 25 14:00:30 202347 OF 312V05N/AN/AN/A
PVNN_TERM_CPU1
SPR CPU1 MISC:DDRVIEW & VSENSE(4/30)
28429229228429628429229228429611711816132161321616NC_CPU1_DDR45_VIEWDIG1VSENSE_PVCCIN_CPU1_DNVSENSE_PVCCINFAON_CPU1_DNVSENSE_PVCCFA_EHV_CPU1_DNVSENSE_PVCCFA_EHV_FIVRA_CPU1_DNVSENSE_PVCCD_HV_CPU1_DNVSENSE_PVCCIN_CPU1_DPVSENSE_PVCCINFAON_CPU1_DPVSENSE_PVCCFA_EHV_CPU1_DPVSENSE_PVCCFA_EHV_FIVRA_CPU1_DPVSENSE_PVCCD_HV_CPU1_DPNC_CPU1_DDR01_VIEWDIG1NC_CPU1_DDR23_VIEWDIG1NC_CPU1_DDR23_VIEWDIG0NC_CPU1_DDR67_VIEWDIG0NC_CPU1_DDR67_VIEWDIG1NC_CPU1_DDR45_VIEWDIG0NC_CPU1_DDR01_VIEWDIG0H_PMAX_TRIGGER_IO_CPU1NC_CPU1_LGSSPARE4NC_CPU1_THERMADANC_CPU1_THERMADCTP_CPU1_A0_DEBUG_ENNC_CPU1_LGSSPARE0NC_CPU1_LGSSPARE5NC_CPU1_LGSSPARE1NC_CPU1_LGSSPARE2NC_CPU1_LGSSPARE3H_CPU1_RMCA_LVC1_R_NDBP_CPU1_HOOK9_MBP3_GTL_QS_R_NDBP_CPU1_HOOK8_MBP2_GTL_QS_R_NDBP_CPU1_MBP1_GTL_R_NDBP_CPU1_MBP0_GTL_R_NTP_CPU1_IFST_TRIG_LVC1_RTP_CPU1_IFST_KOT_LVC1_RTP_CPU1_IFST_DONE_LVC1_RSOCKET4677_AZIF0045-P001C01CSIOSMLF4991/16W0402LF1%CHIPCHIP4991%0402LF1/16WDBP_CPU_HOOK8_MBP2_GTL_QS_NCHIP1%100402LF1/16WDBP_CPU_HOOK9_MBP3_GTL_QS_N1%10CHIP0402LF1/16WDBP_CPU_MBP1_GTL_NCHIP1%1000402LF1/16WDBP_CPU_MBP0_GTL_NCHIP1001%0402LF1/16W
H12
DA45
CY49
CY38
CY24
CU62
CR60
CP61
CN60
CE62
CC64
BF24
BE23
BC23
AV40
AV38
AV32
AU58
AU56
AU33
CE11
BC90
BA11
AT85
BN11
CA11
BD87
AU11
AY85
BU11
BH22
BD24
BK24
BJ23
BN25
BL23
U1
4/42
VSS_VCCIN_SENSE
VSS_VCCINFAON_SENSE
VSS_VCCFA_EHV_SENSE
VSS_VCCFA_EHV_FIVRA_SENSE
VSS_VCCD_HV_SENSE
VCCIN_SENSE
VCCINFAON_SENSE
VCCFA_EHV_SENSE
VCCFA_EHV_FIVRA_SENSE
VCCD_HV_SENSE
RSVD81
RSVD9
RSVD7
RSVD18
RSVD17
RSVD16 RSVD162
RSVD158
RSVD153
RSVD152
RSVD151
RSVD134
RSVD129
RSVD125
RSVD139
RSVD90
RSVD10
RMCA_N
PMAX_TRIGGER_IO
MBP3_N
MBP2_N
MBP1_N
MBP0_N
RSVD49
RSVD46
RSVD37
2
1
2
1
21 21
21 21
R52R51
R53R54
SHEETDATE
DEPARTMENT
SIZE
PROJECT DOCUMENT NUMBER REV
REVIEWER
DESIGNER
123
7 3 2 1 6 5 4
E
A
B
C
E
D
C
B
A
7 6 5 4
D
OUTOUT
OUTOUT
OUT
IN
BIBIBIBI
OUT
BI
OUT
OUTOUT
OUT
R50R49
C



48 OF 312V05N/AN/AFri Aug 25 14:00:31 2023N/AN/ASPR CPU1 MISC:VIEW MDFI/HBM(5 OF 30)
NC_CPU1_HBM0_VIEWDIG1NC_CPU1_HBM1_VIEWDIG0NC_CPU1_MDFI_DIE11_EW1NC_CPU1_MDFI_DIE10_NS0NC_CPU1_MDFI_DIE10_EW1NC_CPU1_MDFI_DIE10_EW0NC_CPU1_MDFI_DIE10_NS1NC_CPU1_MDFI_DIE01_EW1NC_CPU1_MDFI_DIE00_EW1NC_CPU1_SOC_SPARE5NC_CPU1_MDFI_DIE00_EW0NC_CPU1_SOC_SPARE1NC_CPU1_HBM3_VIEWDIG1NC_CPU1_MDFI_DIE00_NS0NC_CPU1_MDFI_DIE00_NS1NC_CPU1_HBM3_VIEWDIG0NC_CPU1_MDFI_DIE01_NS0TP_CPU1_DIE_HVM_EN_LVC1NC_CPU1_MDFI_DIE01_NS1NC_CPU1_SOC_SPARE4NC_CPU1_SOC_SPARE0NC_CPU1_MDFI_DIE01_EW0NC_CPU1_HBM0_VIEWDIG0NC_CPU1_VIEWPIN_GNR3NC_CPU1_VIEWPIN_GNR1NC_CPU1_HBM1_VIEWDIG1NC_CPU1_VIEWPIN_GNR0NC_CPU1_VIEWPIN_GNR2NC_CPU1_MDFI_DIE11_NS1NC_CPU1_MDFI_DIE11_EW0NC_CPU1_MDFI_DIE11_NS0NC_CPU1_HBM2_VIEWDIG1NC_CPU1_HBM2_VIEWDIG0SOCKET4677_AZIF0045-P001C01CSIOSMLF
W17
U17
EG17
CY57
CW58
CW41
CT26
CR25
CK67
CJ70
CJ68
CH69
CF22
CD30
CD26
CD22
CC66
BR21
BP65
BP22
BM65
BL60
BK22
BJ21
BG78
BF71
BE21
BD71
BA25
AY24
AV65
AD77
AC78
U1
5/42
RSVD99
RSVD92
RSVD85
RSVD84
RSVD83
RSVD82
RSVD71
RSVD68
RSVD67
RSVD65
RSVD63
RSVD60
RSVD57
RSVD54
RSVD51
RSVD45
RSVD43
RSVD31
RSVD26
RSVD21
RSVD165
RSVD164
RSVD160
RSVD154
RSVD149
RSVD147
RSVD138
RSVD133
RSVD112
RSVD107
RSVD106RSVD1
RSVD0
SHEETDATE
DEPARTMENT
SIZE
PROJECT DOCUMENT NUMBER REV
REVIEWER
DESIGNER
123
7 3 2 1 6 5 4
E
A
B
C
E
D
C
B
A
7 6 5 4
D
C



Fri Aug 25 14:00:32 2023N/AN/AN/AN/AV0549 OF 312SPR CPU1 MISC:SPARE(6 OF 30)
TP_CPU1_PPDTP_CPU1_SPARE10TP_CPU1_SPARE8TP_CPU1_SPARE11TP_CPU1_SPARE5TP_CPU1_SPARE9TP_CPU1_SPARE13TP_CPU1_SPARE4TP_CPU1_SPARE6TP_CPU1_SPARE7TP_CPU1_SPARE12SMLFIOSOCKET4677_AZIF0045-P001C01CS
J13
DA70
CW43
CL70
CL60
CK61
CH61
CG60
CD69
BD77
AU52
U1
6/42
RSVD163
RSVD95
RSVD111
RSVD87
RSVD8
RSVD97
RSVD44
RSVD159
RSVD148
RSVD115
RSVD119
SHEETDATE
DEPARTMENT
SIZE
PROJECT DOCUMENT NUMBER REV
REVIEWER
DESIGNER
123
7 3 2 1 6 5 4
E
A
B
C
E
D
C
B
A
7 6 5 4
D
C



Fri Aug 25 14:00:33 2023N/AN/AN/AN/AV0550 OF 312SPR CPU1 MISC:7 OF 30)
126126126126PU_CPU1_UPI3_AC_COUPLINGPU_CPU1_UPI2_AC_COUPLINGPU_CPU1_UPI1_AC_COUPLINGPU_CPU1_UPI0_AC_COUPLINGNC_CPU1_PE1_APROBE<0>NC_CPU1_PE2_APROBE<0>NC_CPU1_PE1_APROBE<1>NC_CPU1_UPI1_APROBE<1>NC_CPU1_DMI_APROBE<0>NC_CPU1_PE2_APROBE<1>NC_CPU1_DMI_APROBE<1>NC_CPU1_UPI1_APROBE<0>NC_CPU1_PE0_APROBE<0>NC_CPU1_PE0_APROBE<1>NC_CPU1_UPI2_APROBE<1>NC_CPU1_UPI0_APROBE<1>NC_CPU1_PE4_APROBE<0>NC_CPU1_UPI0_APROBE<0>NC_CPU1_UPI2_APROBE<0>NC_CPU1_PE4_APROBE<1>NC_CPU1_UPI3_APROBE<1>NC_CPU1_UPI3_APROBE<0>NC_CPU1_PE3_APROBE<1>NC_CPU1_PE3_APROBE<0>TP_TRC_CPU1_PTI3_CLKTP_TRC_CPU1_PTI2_CLKTP_TRC_CPU1_PTI<16>TP_TRC_CPU1_PTI<17>TP_TRC_CPU1_PTI<18>TP_TRC_CPU1_PTI<19>TP_TRC_CPU1_PTI<20>TP_TRC_CPU1_PTI<21>TP_TRC_CPU1_PTI<22>TP_TRC_CPU1_PTI<23>TP_TRC_CPU1_PTI<24>TP_TRC_CPU1_PTI<25>TP_TRC_CPU1_PTI<26>TP_TRC_CPU1_PTI<27>TP_TRC_CPU1_PTI<28>TP_TRC_CPU1_PTI<29>TP_TRC_CPU1_PTI<30>TP_TRC_CPU1_PTI<31>TP_TRC_CPU1_PTI1_CLKTP_TRC_CPU1_PTI0_CLKTP_TRC_CPU1_PTI<0>TP_TRC_CPU1_PTI<1>TP_TRC_CPU1_PTI<2>TP_TRC_CPU1_PTI<3>TP_TRC_CPU1_PTI<4>TP_TRC_CPU1_PTI<5>TP_TRC_CPU1_PTI<6>TP_TRC_CPU1_PTI<7>TP_TRC_CPU1_PTI<8>TP_TRC_CPU1_PTI<9>TP_TRC_CPU1_PTI<10>TP_TRC_CPU1_PTI<11>TP_TRC_CPU1_PTI<12>TP_TRC_CPU1_PTI<13>TP_TRC_CPU1_PTI<14>TP_TRC_CPU1_PTI<15>SOCKET4677_AZIF0045-P001C01CSIOSMLF
CR68
CP69
CM69
CL68
CE21
CC23
CC21CA23
CA21
BW23
BW21
BV22
BN21
BL21
AV67
AU68
AU66
AT67
AR17
AN17
CK71
BB65
CW19
BA23
BN66
BM67
BL66
BJ66
BG66
BN68
BM69
BK69
BD67
BG68
BC68
BP30
BH69
BN29
BF69
BP28
BD69
BN27
BE70
BT30
BC70
BU29
BT28
BU27
BV28
CA27
BV30
CA29
BY30
CC27
BK67
BF67
CD28
BY28
CB30
CC29
U1
7/42
UPI3_AC_COUPLING
UPI2_AC_COUPLING
UPI1_AC_COUPLING
UPI0_AC_COUPLING
RSVD89
RSVD80
RSVD79RSVD78
RSVD77
RSVD75
RSVD74
RSVD73
RSVD66
RSVD62
RSVD5
RSVD3
RSVD22
RSVD2
RSVD14
RSVD13
RSVD135
RSVD130
RSVD122
RSVD118
PTI_DIE01_STB_1
PTI_DIE01_STB_0
PTI_DIE010
PTI_DIE011
PTI_DIE012
PTI_DIE013
PTI_DIE014
PTI_DIE015
PTI_DIE016
PTI_DIE017
PTI_DIE018
PTI_DIE019
PTI_DIE0110
PTI_DIE0111
PTI_DIE0112
PTI_DIE0113
PTI_DIE0114
PTI_DIE0115
PTI_DIE00_STB_1
PTI_DIE00_STB_0
PTI_DIE000
PTI_DIE001
PTI_DIE002
PTI_DIE003
PTI_DIE004
PTI_DIE005
PTI_DIE006
PTI_DIE007
PTI_DIE008
PTI_DIE009
PTI_DIE0010
PTI_DIE0011
PTI_DIE0012
PTI_DIE0013
PTI_DIE0014
PTI_DIE0015
SHEETDATE
DEPARTMENT
SIZE
PROJECT DOCUMENT NUMBER REV
REVIEWER
DESIGNER
123
7 3 2 1 6 5 4
E
A
B
C
E
D
C
B
A
7 6 5 4
D
ININININ
C



Fri Aug 25 14:00:33 2023N/A51 OF 312V05N/AN/AN/ASPR CPU1 - DDR CH A (8 OF 30)
9899
98 9998 999899989998 99989998999899 98 9998 9998 9998 999899 98 9998 9998 9998 999899
M_A_CPU1_SA_DQ<31:0>
M_A_CPU1_SB_PARM_A_CPU1_SA_PARM_A_CPU1_SB_RSP<0>M_A_CPU1_SB_RSP<1>M_A_CPU1_SA_RSP<0>M_A_CPU1_SA_RSP<1>M_A_CPU1_ALERT_N
SOCKET4677_AZIF0045-P001C01CSIOSMLFM_A_CPU1_SB_DQ<31:0>M_A_CPU1_CLK_DN<1:0>M_A_CPU1_CLK_DP<1:0>M_A_CPU1_SA_CA<6:0>M_A_CPU1_SA_CS_N<3:0>M_A_CPU1_SA_DQS_DN<9:0>M_A_CPU1_SA_DQS_DP<9:0>M_A_CPU1_SA_CB<7:0>M_A_CPU1_SB_CA<6:0>M_A_CPU1_SB_CS_N<3:0>M_A_CPU1_SB_DQS_DN<9:0>M_A_CPU1_SB_DQS_DP<9:0>M_A_CPU1_SB_CB<7:0>
B8
F10
E11
E37
F38
C37
B38
F53
E54
B53
C54
G39
F34
E35
B34
C35
E31
F32
C31
B32
C33
E9
E21
E27
P30
E33
C9
C21
C27
K30
A33
G9
G21
G27
M30
G33
A9
A21
A27
H30
E7
F8
C7
B10
C11
E19
F20
C19
B20
F22
E23
B22
C23
E25
F26
C25
B26
F28
E29
B28
C29
M28
N29
K28
J29
N31
M32
J31
K32
A39
F40
B40
E41
C41
F44
E43
E48
E56
F57
C56
B57
F59
E60
B59
C60
E58
E64
E70
M67
F77
C58
C64
C70
K67
D77
G58
G64
G70
P67
H77
A58
A64
B71
H67
B77
E62
F63
C62
B63
F65
E66
B65
C66
E68
F69
C68
B69
F71
D73
E72
B73
M65
N66
K65
J66
N68
M69
J68
K69
F75
G76
D75
C76
G78
M77
B79
B81
C48
E50
C50
F51
B51
G52
A52
E45
C43
G45
B44
AV42
AV44
AT49
AU43
AT42
28
2
1
0
2
3
0
1
29
30
0
31
27
26
25
24
22
23
21
1
20
19
16
18
17
15
14
12
13
11
0
10
9
8
6
7
5
4
3
1
2
1
0
7
6
5
4
3
2
1
0
31
28
29
30
25
27
26
24
23
20
22
21
19
18
15
17
16
14
13
10
11
12
8
9
7
5
6
4
3
2
0
1
7
8
9
6
5
7
4
3
2
0
1
8
9
6
7
4
6
5
3
1
2
0
7
8
9
6
5
5
3
2
4
1
0
9
8
7
6
5
3
4
3
1
2
0
4
5
4
6
3
2
2
1
0
4
6
5
2
3
1
0
3
1
0
U1
8/42
DDR0_SB_PAR
DDR0_SB_ECC0
DDR0_SB_ECC1
DDR0_SB_ECC2
DDR0_SB_ECC3
DDR0_SB_ECC4
DDR0_SB_ECC5
DDR0_SB_ECC6
DDR0_SB_ECC7
DDR0_SB_DQS_DP0
DDR0_SB_DQS_DP1
DDR0_SB_DQS_DP2
DDR0_SB_DQS_DP3
DDR0_SB_DQS_DP4
DDR0_SB_DQS_DP5
DDR0_SB_DQS_DP6
DDR0_SB_DQS_DP7
DDR0_SB_DQS_DP8
DDR0_SB_DQS_DP9
DDR0_SB_DQS_DN0
DDR0_SB_DQS_DN1
DDR0_SB_DQS_DN2
DDR0_SB_DQS_DN3
DDR0_SB_DQS_DN4
DDR0_SB_DQS_DN5
DDR0_SB_DQS_DN6
DDR0_SB_DQS_DN7
DDR0_SB_DQS_DN8
DDR0_SB_DQS_DN9
DDR0_SB_DQ0
DDR0_SB_DQ1
DDR0_SB_DQ2
DDR0_SB_DQ3
DDR0_SB_DQ4
DDR0_SB_DQ5
DDR0_SB_DQ6
DDR0_SB_DQ7
DDR0_SB_DQ8
DDR0_SB_DQ9
DDR0_SB_DQ10
DDR0_SB_DQ11
DDR0_SB_DQ12
DDR0_SB_DQ13
DDR0_SB_DQ14
DDR0_SB_DQ15
DDR0_SB_DQ16
DDR0_SB_DQ17
DDR0_SB_DQ18
DDR0_SB_DQ19
DDR0_SB_DQ20
DDR0_SB_DQ21
DDR0_SB_DQ22
DDR0_SB_DQ23
DDR0_SB_DQ24
DDR0_SB_DQ25
DDR0_SB_DQ26
DDR0_SB_DQ27
DDR0_SB_DQ28
DDR0_SB_DQ29
DDR0_SB_DQ30
DDR0_SB_DQ31
DDR0_SB_CS_N0
DDR0_SB_CS_N1
DDR0_SB_CS_N2
DDR0_SB_CS_N3
DDR0_SB_CA0
DDR0_SB_CA1
DDR0_SB_CA2
DDR0_SB_CA3
DDR0_SB_CA4
DDR0_SB_CA5
DDR0_SB_CA6
DDR0_SA_PAR
DDR0_SA_ECC0
DDR0_SA_ECC1
DDR0_SA_ECC2
DDR0_SA_ECC3
DDR0_SA_ECC4
DDR0_SA_ECC5
DDR0_SA_ECC6
DDR0_SA_ECC7
DDR0_SA_DQS_DP0
DDR0_SA_DQS_DP1
DDR0_SA_DQS_DP2
DDR0_SA_DQS_DP3
DDR0_SA_DQS_DP4
DDR0_SA_DQS_DP5
DDR0_SA_DQS_DP6
DDR0_SA_DQS_DP7
DDR0_SA_DQS_DP8
DDR0_SA_DQS_DP9
DDR0_SA_DQS_DN0
DDR0_SA_DQS_DN1
DDR0_SA_DQS_DN2
DDR0_SA_DQS_DN3
DDR0_SA_DQS_DN4
DDR0_SA_DQS_DN5
DDR0_SA_DQS_DN6
DDR0_SA_DQS_DN7
DDR0_SA_DQS_DN8
DDR0_SA_DQS_DN9
DDR0_SA_DQ0
DDR0_SA_DQ1
DDR0_SA_DQ2
DDR0_SA_DQ3
DDR0_SA_DQ4
DDR0_SA_DQ5
DDR0_SA_DQ6
DDR0_SA_DQ7
DDR0_SA_DQ8
DDR0_SA_DQ9
DDR0_SA_DQ10
DDR0_SA_DQ11
DDR0_SA_DQ12
DDR0_SA_DQ13
DDR0_SA_DQ14
DDR0_SA_DQ15
DDR0_SA_DQ16
DDR0_SA_DQ17
DDR0_SA_DQ18
DDR0_SA_DQ19
DDR0_SA_DQ20
DDR0_SA_DQ21
DDR0_SA_DQ22
DDR0_SA_DQ23
DDR0_SA_DQ24
DDR0_SA_DQ25
DDR0_SA_DQ26
DDR0_SA_DQ27
DDR0_SA_DQ28
DDR0_SA_DQ29
DDR0_SA_DQ30
DDR0_SA_DQ31
DDR0_SA_CS_N0
DDR0_SA_CS_N1
DDR0_SA_CS_N2
DDR0_SA_CS_N3
DDR0_SA_CA0
DDR0_SA_CA1
DDR0_SA_CA2
DDR0_SA_CA3
DDR0_SA_CA4
DDR0_SA_CA5
DDR0_SA_CA6
DDR0_CLK_DP0
DDR0_CLK_DP1
DDR0_CLK_DN0
DDR0_CLK_DN1
DDR0_B_RSP0
DDR0_B_RSP1
DDR0_A_RSP0
DDR0_A_RSP1
DDR0_ALERT_N
SHEETDATE
DEPARTMENT
SIZE
PROJECT DOCUMENT NUMBER REV
REVIEWER
DESIGNER
123
7 3 2 1 6 5 4
E
A
B
C
E
D
C
B
A
7 6 5 4
D
IN
BI
BI
BI
BI
OUT
OUT
BI
BI
BI
BI
BI
OUT
BI
OUT
OUT
OUT
ININ
ININ
C



Fri Aug 25 14:00:34 202352 OF 312N/AN/AV05N/AN/ASPR CPU1 - DDR CH B (9 OF 30)M_B_CPU1_CLK_DN<1:0>100101100101100101100101100101
100101
100101100101100101100101
100101100101100101100101100101100101100101100101100101M_B_CPU1_SB_PARM_B_CPU1_SA_PARM_B_CPU1_SB_RSP<0>M_B_CPU1_SB_RSP<1>M_B_CPU1_SA_RSP<0>M_B_CPU1_SA_RSP<1>M_B_CPU1_ALERT_N
SOCKET4677_AZIF0045-P001C01CSIOSMLFM_B_CPU1_SA_DQS_DP<9:0>
M_B_CPU1_CLK_DP<1:0>M_B_CPU1_SA_CA<6:0>M_B_CPU1_SA_CS_N<3:0>
M_B_CPU1_SA_DQ<31:0>M_B_CPU1_SA_DQS_DN<9:0>M_B_CPU1_SA_CB<7:0>M_B_CPU1_SB_CA<6:0>M_B_CPU1_SB_CS_N<3:0>M_B_CPU1_SB_DQ<31:0>M_B_CPU1_SB_DQS_DN<9:0>M_B_CPU1_SB_DQS_DP<9:0>M_B_CPU1_SB_CB<7:0>
M40
N41
K40
J41
N50
M51
J50
K51
P42
N37
M38
J37
K38
M34
N35
K34
J35
H36
G15
P18
P24
AA27
M36
C15
K18
K24
U27
K36
E15
M18
M24
W27
P36
A15
H18
H24
R27
F14
B14
E13
C13
F16
E17
B16
C17
M16
N17
K16
J17
N19
M20
J19
K20
M22
N23
K22
J23
N25
M26
J25
K26
W25
Y26
U25
T26
Y28
W29
T28
U29
H42
N43
J43
M44
K44
U43
T44
W43
M53
N54
K53
J54
N56
M57
J56
K57
P55
W58
P61
W70
P73
K55
U58
K61
U70
K73
M55
AA58
M61
AA70
M73
H55
R58
H61
R70
H73
W56
Y57
U56
T57
Y59
W60
T59
U60
M59
N60
K59
J60
N62
M63
J62
K63
W68
Y69
U68
T69
Y71
W72
T71
U72
M71
N72
K71
J72
N74
M75
J74
K75
Y44
M47
K47
N48
J48
P49
H49
AA45
U45
W45
R45
AP47
AN48
AV49
AK47
AL48
2
3
1
0
31
1
30
29
28
26
27
24
25
23
21
22
19
20
18
16
17
15
14
13
12
11
10
9
8
6
7
5
4
3
2
1
0
0
7
6
4
5
3
2
1
1
0
30
31
29
28
27
26
25
23
24
1
22
21
20
18
19
17
16
15
13
14
0
12
11
10
9
8
7
5
6
4
3
2
1
0
7
9
8
7
4
2
5
6
3
6
9
0
1
8
2
4
5
7
6
3
5
1
0
9
4
6
7
8
5
0
3
4
2
1
5
6
7
8
9
0
2
3
3
4
1
5
6
4
0
3
2
1
3
2
4
5
6
2
0
1
3
1
2
0
0
U1
9/42
DDR1_SB_PAR
DDR1_SB_ECC0
DDR1_SB_ECC1
DDR1_SB_ECC2
DDR1_SB_ECC3
DDR1_SB_ECC4
DDR1_SB_ECC5
DDR1_SB_ECC6
DDR1_SB_ECC7
DDR1_SB_DQS_DP0
DDR1_SB_DQS_DP1
DDR1_SB_DQS_DP2
DDR1_SB_DQS_DP3
DDR1_SB_DQS_DP4
DDR1_SB_DQS_DP5
DDR1_SB_DQS_DP6
DDR1_SB_DQS_DP7
DDR1_SB_DQS_DP8
DDR1_SB_DQS_DP9
DDR1_SB_DQS_DN0
DDR1_SB_DQS_DN1
DDR1_SB_DQS_DN2
DDR1_SB_DQS_DN3
DDR1_SB_DQS_DN4
DDR1_SB_DQS_DN5
DDR1_SB_DQS_DN6
DDR1_SB_DQS_DN7
DDR1_SB_DQS_DN8
DDR1_SB_DQS_DN9
DDR1_SB_DQ0
DDR1_SB_DQ1
DDR1_SB_DQ2
DDR1_SB_DQ3
DDR1_SB_DQ4
DDR1_SB_DQ5
DDR1_SB_DQ6
DDR1_SB_DQ7
DDR1_SB_DQ8
DDR1_SB_DQ9
DDR1_SB_DQ10
DDR1_SB_DQ11
DDR1_SB_DQ12
DDR1_SB_DQ13
DDR1_SB_DQ14
DDR1_SB_DQ15
DDR1_SB_DQ16
DDR1_SB_DQ17
DDR1_SB_DQ18
DDR1_SB_DQ19
DDR1_SB_DQ20
DDR1_SB_DQ21
DDR1_SB_DQ22
DDR1_SB_DQ23
DDR1_SB_DQ24
DDR1_SB_DQ25
DDR1_SB_DQ26
DDR1_SB_DQ27
DDR1_SB_DQ28
DDR1_SB_DQ29
DDR1_SB_DQ30
DDR1_SB_DQ31
DDR1_SB_CS_N0
DDR1_SB_CS_N1
DDR1_SB_CS_N2
DDR1_SB_CS_N3
DDR1_SB_CA0
DDR1_SB_CA1
DDR1_SB_CA2
DDR1_SB_CA3
DDR1_SB_CA4
DDR1_SB_CA5
DDR1_SB_CA6
DDR1_SA_PAR
DDR1_SA_ECC0
DDR1_SA_ECC1
DDR1_SA_ECC2
DDR1_SA_ECC3
DDR1_SA_ECC4
DDR1_SA_ECC5
DDR1_SA_ECC6
DDR1_SA_ECC7
DDR1_SA_DQS_DP0
DDR1_SA_DQS_DP1
DDR1_SA_DQS_DP2
DDR1_SA_DQS_DP3
DDR1_SA_DQS_DP4
DDR1_SA_DQS_DP5
DDR1_SA_DQS_DP6
DDR1_SA_DQS_DP7
DDR1_SA_DQS_DP8
DDR1_SA_DQS_DP9
DDR1_SA_DQS_DN0
DDR1_SA_DQS_DN1
DDR1_SA_DQS_DN2
DDR1_SA_DQS_DN3
DDR1_SA_DQS_DN4
DDR1_SA_DQS_DN5
DDR1_SA_DQS_DN6
DDR1_SA_DQS_DN7
DDR1_SA_DQS_DN8
DDR1_SA_DQS_DN9
DDR1_SA_DQ0
DDR1_SA_DQ1
DDR1_SA_DQ2
DDR1_SA_DQ3
DDR1_SA_DQ4
DDR1_SA_DQ5
DDR1_SA_DQ6
DDR1_SA_DQ7
DDR1_SA_DQ8
DDR1_SA_DQ9
DDR1_SA_DQ10
DDR1_SA_DQ11
DDR1_SA_DQ12
DDR1_SA_DQ13
DDR1_SA_DQ14
DDR1_SA_DQ15
DDR1_SA_DQ16
DDR1_SA_DQ17
DDR1_SA_DQ18
DDR1_SA_DQ19
DDR1_SA_DQ20
DDR1_SA_DQ21
DDR1_SA_DQ22
DDR1_SA_DQ23
DDR1_SA_DQ24
DDR1_SA_DQ25
DDR1_SA_DQ26
DDR1_SA_DQ27
DDR1_SA_DQ28
DDR1_SA_DQ29
DDR1_SA_DQ30
DDR1_SA_DQ31
DDR1_SA_CS_N0
DDR1_SA_CS_N1
DDR1_SA_CS_N2
DDR1_SA_CS_N3
DDR1_SA_CA0
DDR1_SA_CA1
DDR1_SA_CA2
DDR1_SA_CA3
DDR1_SA_CA4
DDR1_SA_CA5
DDR1_SA_CA6
DDR1_CLK_DP0
DDR1_CLK_DP1
DDR1_CLK_DN0
DDR1_CLK_DN1
DDR1_B_RSP0
DDR1_B_RSP1
DDR1_A_RSP0
DDR1_A_RSP1
DDR1_ALERT_N
SHEETDATE
DEPARTMENT
SIZE
PROJECT DOCUMENT NUMBER REV
REVIEWER
DESIGNER
123
7 3 2 1 6 5 4
E
A
B
C
E
D
C
B
A
7 6 5 4
D
IN
ININ
IN
BI
BI
BI
BI
OUT
BI
BI
BI
BI
BI
BI
OUT
OUT
OUT
OUT
IN
OUT
C



Fri Aug 25 14:00:35 2023N/AN/AV0553 OF 312N/AN/ASPR CPU1 - DDR CH C (10 OF 30)102 103102 103102103102103102 103102103102103102 103102 103
102103102 103102 103102103102 103102 103102103102 103102 103102103M_C_CPU1_SB_PARM_C_CPU1_SA_PARM_C_CPU1_SB_RSP<0>M_C_CPU1_SB_RSP<1>M_C_CPU1_SA_RSP<0>M_C_CPU1_SA_RSP<1>M_C_CPU1_ALERT_N
SOCKET4677_AZIF0045-P001C01CSIOSMLF
M_C_CPU1_CLK_DN<1:0>M_C_CPU1_CLK_DP<1:0>M_C_CPU1_SA_CA<6:0>M_C_CPU1_SA_CS_N<3:0>
M_C_CPU1_SA_DQ<31:0>M_C_CPU1_SA_DQS_DN<9:0>M_C_CPU1_SA_DQS_DP<9:0>M_C_CPU1_SA_CB<7:0>M_C_CPU1_SB_CA<6:0>M_C_CPU1_SB_CS_N<3:0>M_C_CPU1_SB_DQ<31:0>M_C_CPU1_SB_DQS_DN<9:0>M_C_CPU1_SB_DQS_DP<9:0>M_C_CPU1_SB_CB<7:0>
W37
Y38
U37
T38
Y53
W54
T53
U54
AA39
Y34
W35
T34
U35
W31
Y32
U31
T32
U33
AH18
AA21
AH30
AH36
AA33
AD18
U21
AD30
AD36
R33
AF18
W21
AF30
AF36
W33
AB18
R21
AB30
AB36
AJ17
AC17
AG17
AA17
AG19
AF20
AC19
AD20
W19
Y20
U19
T20
Y22
W23
T22
U23
AF28
AG29
AD28
AC29
AG31
AF32
AC31
AD32
AF34
AG35
AD34
AC35
AG37
AF38
AC37
AD38
R39
Y40
T40
W41
U41
Y47
W48
T47
AF53
AG54
AD53
AC54
AG56
AF57
AC56
AD57
AF55
AH61
W64
AF67
AA76
AB55
AD61
U64
AD67
U76
AH55
AF61
AA64
AH67
W76
AD55
AB61
R64
AB67
R76
AF59
AG60
AD59
AC60
AG62
AF63
AC62
AD63
W62
Y63
U62
T63
Y65
W66
T65
U66
AF65
AG66
AD65
AC66
AG68
AF69
AC68
AD69
W74
Y75
U74
T75
Y77
W78
T77
U78
U48
W50
U50
Y51
T51
AA52
R52
AH49
AD49
AF49
AB49
AF47
AG48
AT47
AD47
AC48
0
1
2
30
3
31
28
29
25
26
27
23
24
22
20
2
21
17
18
19
15
16
12
13
14
10
0
11
7
8
9
5
6
2
3
4
7
1
0
1
5
6
2
3
4
0
1
1
29
31
30
27
28
24
25
26
22
23
0
19
20
21
16
17
18
14
15
11
12
0
13
9
10
6
7
8
4
5
1
2
3
7
0
9
6
8
7
4
5
1
2
3
9
0
7
8
6
5
4
2
3
1
0
9
8
7
6
5
4
1
2
3
6
0
9
7
8
4
5
6
3
2
1
5
0
6
3
5
4
2
0
1
5
6
4
3
4
1
0
2
3
2
0
1
3
1
U1
10/42
DDR2_SB_PAR
DDR2_SB_ECC0
DDR2_SB_ECC1
DDR2_SB_ECC2
DDR2_SB_ECC3
DDR2_SB_ECC4
DDR2_SB_ECC5
DDR2_SB_ECC6
DDR2_SB_ECC7
DDR2_SB_DQS_DP0
DDR2_SB_DQS_DP1
DDR2_SB_DQS_DP2
DDR2_SB_DQS_DP3
DDR2_SB_DQS_DP4
DDR2_SB_DQS_DP5
DDR2_SB_DQS_DP6
DDR2_SB_DQS_DP7
DDR2_SB_DQS_DP8
DDR2_SB_DQS_DP9
DDR2_SB_DQS_DN0
DDR2_SB_DQS_DN1
DDR2_SB_DQS_DN2
DDR2_SB_DQS_DN3
DDR2_SB_DQS_DN4
DDR2_SB_DQS_DN5
DDR2_SB_DQS_DN6
DDR2_SB_DQS_DN7
DDR2_SB_DQS_DN8
DDR2_SB_DQS_DN9
DDR2_SB_DQ0
DDR2_SB_DQ1
DDR2_SB_DQ2
DDR2_SB_DQ3
DDR2_SB_DQ4
DDR2_SB_DQ5
DDR2_SB_DQ6
DDR2_SB_DQ7
DDR2_SB_DQ8
DDR2_SB_DQ9
DDR2_SB_DQ10
DDR2_SB_DQ11
DDR2_SB_DQ12
DDR2_SB_DQ13
DDR2_SB_DQ14
DDR2_SB_DQ15
DDR2_SB_DQ16
DDR2_SB_DQ17
DDR2_SB_DQ18
DDR2_SB_DQ19
DDR2_SB_DQ20
DDR2_SB_DQ21
DDR2_SB_DQ22
DDR2_SB_DQ23
DDR2_SB_DQ24
DDR2_SB_DQ25
DDR2_SB_DQ26
DDR2_SB_DQ27
DDR2_SB_DQ28
DDR2_SB_DQ29
DDR2_SB_DQ30
DDR2_SB_DQ31
DDR2_SB_CS_N0
DDR2_SB_CS_N1
DDR2_SB_CS_N2
DDR2_SB_CS_N3
DDR2_SB_CA0
DDR2_SB_CA1
DDR2_SB_CA2
DDR2_SB_CA3
DDR2_SB_CA4
DDR2_SB_CA5
DDR2_SB_CA6
DDR2_SA_PAR
DDR2_SA_ECC0
DDR2_SA_ECC1
DDR2_SA_ECC2
DDR2_SA_ECC3
DDR2_SA_ECC4
DDR2_SA_ECC5
DDR2_SA_ECC6
DDR2_SA_ECC7
DDR2_SA_DQS_DP0
DDR2_SA_DQS_DP1
DDR2_SA_DQS_DP2
DDR2_SA_DQS_DP3
DDR2_SA_DQS_DP4
DDR2_SA_DQS_DP5
DDR2_SA_DQS_DP6
DDR2_SA_DQS_DP7
DDR2_SA_DQS_DP8
DDR2_SA_DQS_DP9
DDR2_SA_DQS_DN0
DDR2_SA_DQS_DN1
DDR2_SA_DQS_DN2
DDR2_SA_DQS_DN3
DDR2_SA_DQS_DN4
DDR2_SA_DQS_DN5
DDR2_SA_DQS_DN6
DDR2_SA_DQS_DN7
DDR2_SA_DQS_DN8
DDR2_SA_DQS_DN9
DDR2_SA_DQ0
DDR2_SA_DQ1
DDR2_SA_DQ2
DDR2_SA_DQ3
DDR2_SA_DQ4
DDR2_SA_DQ5
DDR2_SA_DQ6
DDR2_SA_DQ7
DDR2_SA_DQ8
DDR2_SA_DQ9
DDR2_SA_DQ10
DDR2_SA_DQ11
DDR2_SA_DQ12
DDR2_SA_DQ13
DDR2_SA_DQ14
DDR2_SA_DQ15
DDR2_SA_DQ16
DDR2_SA_DQ17
DDR2_SA_DQ18
DDR2_SA_DQ19
DDR2_SA_DQ20
DDR2_SA_DQ21
DDR2_SA_DQ22
DDR2_SA_DQ23
DDR2_SA_DQ24
DDR2_SA_DQ25
DDR2_SA_DQ26
DDR2_SA_DQ27
DDR2_SA_DQ28
DDR2_SA_DQ29
DDR2_SA_DQ30
DDR2_SA_DQ31
DDR2_SA_CS_N0
DDR2_SA_CS_N1
DDR2_SA_CS_N2
DDR2_SA_CS_N3
DDR2_SA_CA0
DDR2_SA_CA1
DDR2_SA_CA2
DDR2_SA_CA3
DDR2_SA_CA4
DDR2_SA_CA5
DDR2_SA_CA6
DDR2_CLK_DP0
DDR2_CLK_DP1
DDR2_CLK_DN0
DDR2_CLK_DN1
DDR2_B_RSP0
DDR2_B_RSP1
DDR2_A_RSP0
DDR2_A_RSP1
DDR2_ALERT_N
SHEETDATE
DEPARTMENT
SIZE
PROJECT DOCUMENT NUMBER REV
REVIEWER
DESIGNER
123
7 3 2 1 6 5 4
E
A
B
C
E
D
C
B
A
7 6 5 4
D
IN
ININ
IN
IN
BI
OUT
BI
BI
BI
BI
BI
OUT
BI
OUT
OUT
BI
OUT
BI
BI
OUT
C



Fri Aug 25 14:00:36 2023N/AN/AN/AN/AV0554 OF 312SPR CPU1 - DDR CH D (11 OF 30)104105104 105104 105104105104105104 105104105104105104 105104 105
104105104 105104 105104105104 105104 105104105104 105104 105M_D_CPU1_SB_CB<7:0>M_D_CPU1_SB_PARM_D_CPU1_SA_PARM_D_CPU1_SB_RSP<0>M_D_CPU1_SB_RSP<1>M_D_CPU1_SA_RSP<0>M_D_CPU1_SA_RSP<1>M_D_CPU1_ALERT_N
SOCKET4677_AZIF0045-P001C01CSIOSMLF
M_D_CPU1_CLK_DN<1:0>M_D_CPU1_CLK_DP<1:0>M_D_CPU1_SA_CA<6:0>M_D_CPU1_SA_CS_N<3:0>
M_D_CPU1_SA_DQ<31:0>M_D_CPU1_SA_DQS_DN<9:0>M_D_CPU1_SA_DQS_DP<9:0>M_D_CPU1_SA_CB<7:0>M_D_CPU1_SB_CA<6:0>M_D_CPU1_SB_CS_N<3:0>M_D_CPU1_SB_DQ<31:0>M_D_CPU1_SB_DQS_DN<9:0>M_D_CPU1_SB_DQS_DP<9:0>
AD40
AF40
AG41
AC41
AP53
AN54
AK53
AL54
AH42
AP40
AN41
AK40
AL41
AN37
AP38
AL37
AK38
AL39
AR21
AH24
AR27
AR33
AN39
AL21
AD24
AL27
AL33
AJ39
AN21
AF24
AN27
AN33
AR39
AJ21
AB24
AJ27
AJ33
AN19
AP20
AL19
AK20
AP22
AN23
AK22
AL23
AF22
AG23
AD22
AC23
AG25
AF26
AC25
AD26
AN25
AP26
AL25
AK26
AP28
AN29
AK28
AL29
AN31
AP32
AL31
AK32
AP34
AN35
AK34
AL35
AB42
AG43
AC43
AF44
AD44
AL43
AK44
AP44
AN56
AP57
AL56
AK57
AP59
AN60
AK59
AL60
AR58
AR64
AR70
AR76
AF73
AL58
AL64
AL70
AL76
AD73
AN58
AN64
AN70
AN76
AH73
AJ58
AJ64
AJ70
AJ76
AB73
AN62
AP63
AL62
AK63
AP65
AN66
AK65
AL66
AN68
AP69
AL68
AK69
AP71
AN72
AK71
AL72
AN74
AP75
AL74
AK75
AP77
AN78
AK77
AL78
AF71
AG72
AD71
AC72
AG74
AF75
AC74
AD75
AN43
AN50
AL50
AP51
AK51
AR52
AJ52
AR45
AL45
AN45
AJ45
AG50
AF51
AV47
AC50
AD51
8
2
1
0
31
30
29
28
27
26
25
23
24
22
21
1
20
19
18
17
16
15
14
13
12
11
0
10
9
7
6
5
4
3
2
0
1
1
7
6
5
4
3
2
1
1
0
31
30
29
28
27
26
25
24
23
0
22
21
20
19
18
17
16
15
14
13
0
12
11
10
9
8
7
6
5
4
3
2
1
0
7
9
8
7
6
4
5
3
2
1
6
0
9
8
7
6
4
5
2
3
1
4
0
9
8
6
7
4
5
3
1
2
5
0
9
7
8
6
5
4
2
3
1
2
0
6
5
4
3
0
1
2
6
5
3
3
4
2
1
0
2
3
1
0
3
U1
11/42
DDR3_SB_PAR
DDR3_SB_ECC0
DDR3_SB_ECC1
DDR3_SB_ECC2
DDR3_SB_ECC3
DDR3_SB_ECC4
DDR3_SB_ECC5
DDR3_SB_ECC6
DDR3_SB_ECC7
DDR3_SB_DQS_DP0
DDR3_SB_DQS_DP1
DDR3_SB_DQS_DP2
DDR3_SB_DQS_DP3
DDR3_SB_DQS_DP4
DDR3_SB_DQS_DP5
DDR3_SB_DQS_DP6
DDR3_SB_DQS_DP7
DDR3_SB_DQS_DP8
DDR3_SB_DQS_DP9
DDR3_SB_DQS_DN0
DDR3_SB_DQS_DN1
DDR3_SB_DQS_DN2
DDR3_SB_DQS_DN3
DDR3_SB_DQS_DN4
DDR3_SB_DQS_DN5
DDR3_SB_DQS_DN6
DDR3_SB_DQS_DN7
DDR3_SB_DQS_DN8
DDR3_SB_DQS_DN9
DDR3_SB_DQ0
DDR3_SB_DQ1
DDR3_SB_DQ2
DDR3_SB_DQ3
DDR3_SB_DQ4
DDR3_SB_DQ5
DDR3_SB_DQ6
DDR3_SB_DQ7
DDR3_SB_DQ8
DDR3_SB_DQ9
DDR3_SB_DQ10
DDR3_SB_DQ11
DDR3_SB_DQ12
DDR3_SB_DQ13
DDR3_SB_DQ14
DDR3_SB_DQ15
DDR3_SB_DQ16
DDR3_SB_DQ17
DDR3_SB_DQ18
DDR3_SB_DQ19
DDR3_SB_DQ20
DDR3_SB_DQ21
DDR3_SB_DQ22
DDR3_SB_DQ23
DDR3_SB_DQ24
DDR3_SB_DQ25
DDR3_SB_DQ26
DDR3_SB_DQ27
DDR3_SB_DQ28
DDR3_SB_DQ29
DDR3_SB_DQ30
DDR3_SB_DQ31
DDR3_SB_CS_N0
DDR3_SB_CS_N1
DDR3_SB_CS_N2
DDR3_SB_CS_N3
DDR3_SB_CA0
DDR3_SB_CA1
DDR3_SB_CA2
DDR3_SB_CA3
DDR3_SB_CA4
DDR3_SB_CA5
DDR3_SB_CA6
DDR3_SA_PAR
DDR3_SA_ECC0
DDR3_SA_ECC1
DDR3_SA_ECC2
DDR3_SA_ECC3
DDR3_SA_ECC4
DDR3_SA_ECC5
DDR3_SA_ECC6
DDR3_SA_ECC7
DDR3_SA_DQS_DP0
DDR3_SA_DQS_DP1
DDR3_SA_DQS_DP2
DDR3_SA_DQS_DP3
DDR3_SA_DQS_DP4
DDR3_SA_DQS_DP5
DDR3_SA_DQS_DP6
DDR3_SA_DQS_DP7
DDR3_SA_DQS_DP8
DDR3_SA_DQS_DP9
DDR3_SA_DQS_DN0
DDR3_SA_DQS_DN1
DDR3_SA_DQS_DN2
DDR3_SA_DQS_DN3
DDR3_SA_DQS_DN4
DDR3_SA_DQS_DN5
DDR3_SA_DQS_DN6
DDR3_SA_DQS_DN7
DDR3_SA_DQS_DN8
DDR3_SA_DQS_DN9
DDR3_SA_DQ0
DDR3_SA_DQ1
DDR3_SA_DQ2
DDR3_SA_DQ3
DDR3_SA_DQ4
DDR3_SA_DQ5
DDR3_SA_DQ6
DDR3_SA_DQ7
DDR3_SA_DQ8
DDR3_SA_DQ9
DDR3_SA_DQ10
DDR3_SA_DQ11
DDR3_SA_DQ12
DDR3_SA_DQ13
DDR3_SA_DQ14
DDR3_SA_DQ15
DDR3_SA_DQ16
DDR3_SA_DQ17
DDR3_SA_DQ18
DDR3_SA_DQ19
DDR3_SA_DQ20
DDR3_SA_DQ21
DDR3_SA_DQ22
DDR3_SA_DQ23
DDR3_SA_DQ24
DDR3_SA_DQ25
DDR3_SA_DQ26
DDR3_SA_DQ27
DDR3_SA_DQ28
DDR3_SA_DQ29
DDR3_SA_DQ30
DDR3_SA_DQ31
DDR3_SA_CS_N0
DDR3_SA_CS_N1
DDR3_SA_CS_N2
DDR3_SA_CS_N3
DDR3_SA_CA0
DDR3_SA_CA1
DDR3_SA_CA2
DDR3_SA_CA3
DDR3_SA_CA4
DDR3_SA_CA5
DDR3_SA_CA6
DDR3_CLK_DP0
DDR3_CLK_DP1
DDR3_CLK_DN0
DDR3_CLK_DN1
DDR3_B_RSP0
DDR3_B_RSP1
DDR3_A_RSP0
DDR3_A_RSP1
DDR3_ALERT_N
SHEETDATE
DEPARTMENT
SIZE
PROJECT DOCUMENT NUMBER REV
REVIEWER
DESIGNER
123
7 3 2 1 6 5 4
E
A
B
C
E
D
C
B
A
7 6 5 4
D
ININ
ININ
IN
BI
BI
BI
OUT
BI
BI
BI
BI
BI
BI
OUT
OUT
OUT
OUT
BI
OUT
C



Fri Aug 25 14:00:37 2023N/A55 OF 312N/AN/AN/AV05SPR CPU1 - DDR CH E (12 OF 30)106 107106 107106107106107106 107106107106107106 107106 107
106107106 107106 107106107106 107106 107106107106 107106 107106107M_E_CPU1_SB_PARM_E_CPU1_SA_PARM_E_CPU1_SB_RSP<0>M_E_CPU1_SB_RSP<1>M_E_CPU1_SA_RSP<0>M_E_CPU1_SA_RSP<1>M_E_CPU1_ALERT_N
SOCKET4677_AZIF0045-P001C01CSIOSMLF
M_E_CPU1_CLK_DN<1:0>M_E_CPU1_CLK_DP<1:0>M_E_CPU1_SA_CA<6:0>M_E_CPU1_SA_CS_N<3:0>
M_E_CPU1_SA_DQ<31:0>M_E_CPU1_SA_DQS_DN<9:0>M_E_CPU1_SA_DQS_DP<9:0>M_E_CPU1_SA_CB<7:0>M_E_CPU1_SB_CA<6:0>M_E_CPU1_SB_CS_N<3:0>M_E_CPU1_SB_DQ<31:0>M_E_CPU1_SB_DQS_DN<9:0>M_E_CPU1_SB_DQS_DP<9:0>M_E_CPU1_SB_CB<7:0>
EL41
EM40
ET40
EP40
EL50
EM51
ET51
EP51
EP42
ER37
EP38
EL37
EM38
EP34
ER35
EM34
EL35
EM36
EP18
EP24
EP30
EG27
EP36
EM18
EM24
EM30
EC27
EK36
ET18
ET24
ET30
EJ27
ET36
EK18
EK24
EK30
EE27
EP16
ER17
EM16
EL17
ER19
EP20
EL19
EM20
EP22
ER23
EM22
EL23
ER25
EP26
EL25
EM26
EP28
ER29
EM28
EL29
ER31
EP32
EL31
EM32
EG25
EH26
EE25
ED26
EH28
EG29
ED28
EE29
EK42
ET42
EL43
EP44
EM44
EH44
EG43
EE43
EP53
ER54
EM53
EL54
ER56
EP57
EL56
EM57
EP55
EP61
EM67
EG70
EN74
EK55
EM61
EL68
EE70
EN76
ET55
ET61
EN68
EJ70
EM75
EM55
EK61
EK67
EC70
EP75
EP59
ER60
EM59
EL60
ER62
EP63
EL62
EM63
EP65
EL66
EM65
ER66
ER68
EN70
EM69
EM71
EG68
EH69
EE68
ED69
EH71
EG72
ED71
EE72
ER72
EP73
EK73
EL74
ER76
EP79
EM77
EL78
ED44
EP47
EM47
EL48
EK49
ET49
EP49
EC45
EG45
EE45
EJ45
DG43
DF44
CY47
DC43
DD44
17
9
2
3
1
2
0
31
30
28
29
27
26
25
24
23
22
21
20
18
19
17
16
15
14
13
12
10
11
9
8
7
5
6
4
3
2
1
0
1
7
6
5
3
4
2
0
1
0
31
30
29
27
28
26
25
24
22
23
0
21
20
19
18
16
15
14
13
12
1
11
9
10
8
7
6
4
5
3
2
1
0
7
7
6
8
2
6
1
4
3
5
8
9
0
7
2
3
5
4
6
5
1
0
9
4
5
8
7
4
6
0
3
2
1
8
9
7
6
4
3
5
0
2
2
1
3
4
3
5
6
2
1
0
1
3
4
5
6
2
0
1
1
0
3
0
U1
12/42
DDR4_SB_PAR
DDR4_SB_ECC0
DDR4_SB_ECC1
DDR4_SB_ECC2
DDR4_SB_ECC3
DDR4_SB_ECC4
DDR4_SB_ECC5
DDR4_SB_ECC6
DDR4_SB_ECC7
DDR4_SB_DQS_DP0
DDR4_SB_DQS_DP1
DDR4_SB_DQS_DP2
DDR4_SB_DQS_DP3
DDR4_SB_DQS_DP4
DDR4_SB_DQS_DP5
DDR4_SB_DQS_DP6
DDR4_SB_DQS_DP7
DDR4_SB_DQS_DP8
DDR4_SB_DQS_DP9
DDR4_SB_DQS_DN0
DDR4_SB_DQS_DN1
DDR4_SB_DQS_DN2
DDR4_SB_DQS_DN3
DDR4_SB_DQS_DN4
DDR4_SB_DQS_DN5
DDR4_SB_DQS_DN6
DDR4_SB_DQS_DN7
DDR4_SB_DQS_DN8
DDR4_SB_DQS_DN9
DDR4_SB_DQ0
DDR4_SB_DQ1
DDR4_SB_DQ2
DDR4_SB_DQ3
DDR4_SB_DQ4
DDR4_SB_DQ5
DDR4_SB_DQ6
DDR4_SB_DQ7
DDR4_SB_DQ8
DDR4_SB_DQ9
DDR4_SB_DQ10
DDR4_SB_DQ11
DDR4_SB_DQ12
DDR4_SB_DQ13
DDR4_SB_DQ14
DDR4_SB_DQ15
DDR4_SB_DQ16
DDR4_SB_DQ17
DDR4_SB_DQ18
DDR4_SB_DQ19
DDR4_SB_DQ20
DDR4_SB_DQ21
DDR4_SB_DQ22
DDR4_SB_DQ23
DDR4_SB_DQ24
DDR4_SB_DQ25
DDR4_SB_DQ26
DDR4_SB_DQ27
DDR4_SB_DQ28
DDR4_SB_DQ29
DDR4_SB_DQ30
DDR4_SB_DQ31
DDR4_SB_CS_N0
DDR4_SB_CS_N1
DDR4_SB_CS_N2
DDR4_SB_CS_N3
DDR4_SB_CA0
DDR4_SB_CA1
DDR4_SB_CA2
DDR4_SB_CA3
DDR4_SB_CA4
DDR4_SB_CA5
DDR4_SB_CA6
DDR4_SA_PAR
DDR4_SA_ECC0
DDR4_SA_ECC1
DDR4_SA_ECC2
DDR4_SA_ECC3
DDR4_SA_ECC4
DDR4_SA_ECC5
DDR4_SA_ECC6
DDR4_SA_ECC7
DDR4_SA_DQS_DP0
DDR4_SA_DQS_DP1
DDR4_SA_DQS_DP2
DDR4_SA_DQS_DP3
DDR4_SA_DQS_DP4
DDR4_SA_DQS_DP5
DDR4_SA_DQS_DP6
DDR4_SA_DQS_DP7
DDR4_SA_DQS_DP8
DDR4_SA_DQS_DP9
DDR4_SA_DQS_DN0
DDR4_SA_DQS_DN1
DDR4_SA_DQS_DN2
DDR4_SA_DQS_DN3
DDR4_SA_DQS_DN4
DDR4_SA_DQS_DN5
DDR4_SA_DQS_DN6
DDR4_SA_DQS_DN7
DDR4_SA_DQS_DN8
DDR4_SA_DQS_DN9
DDR4_SA_DQ0
DDR4_SA_DQ1
DDR4_SA_DQ2
DDR4_SA_DQ3
DDR4_SA_DQ4
DDR4_SA_DQ5
DDR4_SA_DQ6
DDR4_SA_DQ7
DDR4_SA_DQ8
DDR4_SA_DQ9
DDR4_SA_DQ10
DDR4_SA_DQ11
DDR4_SA_DQ12
DDR4_SA_DQ13
DDR4_SA_DQ14
DDR4_SA_DQ15
DDR4_SA_DQ16
DDR4_SA_DQ17
DDR4_SA_DQ18
DDR4_SA_DQ19
DDR4_SA_DQ20
DDR4_SA_DQ21
DDR4_SA_DQ22
DDR4_SA_DQ23
DDR4_SA_DQ24
DDR4_SA_DQ25
DDR4_SA_DQ26
DDR4_SA_DQ27
DDR4_SA_DQ28
DDR4_SA_DQ29
DDR4_SA_DQ30
DDR4_SA_DQ31
DDR4_SA_CS_N0
DDR4_SA_CS_N1
DDR4_SA_CS_N2
DDR4_SA_CS_N3
DDR4_SA_CA0
DDR4_SA_CA1
DDR4_SA_CA2
DDR4_SA_CA3
DDR4_SA_CA4
DDR4_SA_CA5
DDR4_SA_CA6
DDR4_CLK_DP0
DDR4_CLK_DP1
DDR4_CLK_DN0
DDR4_CLK_DN1
DDR4_B_RSP0
DDR4_B_RSP1
DDR4_A_RSP0
DDR4_A_RSP1
DDR4_ALERT_N
SHEETDATE
DEPARTMENT
SIZE
PROJECT DOCUMENT NUMBER REV
REVIEWER
DESIGNER
123
7 3 2 1 6 5 4
E
A
B
C
E
D
C
B
A
7 6 5 4
D
ININ
IN
BI
BI
BI
BI
OUT
BI
BI
BI
BI
BI
BI
OUT
OUT
OUT
OUT
ININ
OUT
C



Fri Aug 25 14:00:38 2023N/AN/AN/AN/AV0556 OF 312SPR CPU1 - DDR CH F (13 OF 30)108 109108 109108109108109108 109108109108109108109108 109108 109
108109108 109108 109108 109108 109108109108 109108 109108109M_F_CPU1_SB_PARM_F_CPU1_SA_PARM_F_CPU1_SB_RSP<0>M_F_CPU1_SB_RSP<1>M_F_CPU1_SA_RSP<0>M_F_CPU1_SA_RSP<1>M_F_CPU1_ALERT_N
SOCKET4677_AZIF0045-P001C01CSIOSMLFM_F_CPU1_SA_CB<7:0>M_F_CPU1_CLK_DN<1:0>M_F_CPU1_CLK_DP<1:0>M_F_CPU1_SA_CA<6:0>M_F_CPU1_SA_CS_N<3:0>
M_F_CPU1_SA_DQ<31:0>M_F_CPU1_SA_DQS_DN<9:0>M_F_CPU1_SA_DQS_DP<9:0>M_F_CPU1_SB_CA<6:0>M_F_CPU1_SB_CS_N<3:0>M_F_CPU1_SB_DQ<31:0>M_F_CPU1_SB_DQS_DN<9:0>M_F_CPU1_SB_DQS_DP<9:0>M_F_CPU1_SB_CB<7:0>
EE37
ED38
EG37
EH38
ED53
EE54
EH53
EG54
EJ39
EH34
EG35
ED34
EE35
EG31
EH32
EE31
ED32
EC33
EB18
EP12
EG21
DY30
EG33
DV18
EK12
EC21
DT30
EE33
DY18
ET12
EJ21
EB30
EJ33
DT18
EM12
EE21
DV30
DR17
EC17
DU17
EA17
EA19
DY20
DU19
DV20
EP10
ER11
EM10
EL11
ER13
EP14
EL13
EM14
EG19
EH20
EE19
ED20
EH22
EG23
ED22
EE23
DY28
EA29
DV28
DU29
EA31
DY32
DU31
DV32
EC39
EH40
ED40
EG41
EE41
DU50
DV51
EA50
EG56
EH57
EE56
ED57
EH59
EG60
ED59
EE60
EG58
DY55
EG64
DY67
EG76
EC58
DT55
EE64
DV67
EC76
EJ58
EB55
EJ64
EB67
EJ76
EE58
DV55
EC64
DT67
EE76
DY53
EA54
DV53
DU54
EA56
DY57
DU56
DV57
EG62
EH63
EE62
ED63
EH65
EG66
ED65
EE66
DY65
EA66
DV65
DU66
EA68
DY69
DU68
DV69
EG74
EH75
EE74
ED75
EG78
ED77
EH77
EB77
DY51
EG50
EE50
EH51
ED51
EJ52
EC52
DT49
EB49
DV49
DY49
DK47
DL48
CW48
DP47
DN48
11
7
2
1
3
0
31
2
30
29
28
26
27
25
23
24
21
22
1
18
20
19
17
16
15
13
14
12
11
0
10
8
9
6
7
5
3
4
2
0
0
1
6
3
5
4
0
1
1
2
30
31
29
28
27
26
25
24
23
0
22
20
21
17
19
18
16
15
14
12
1
13
10
9
7
8
5
6
4
2
3
1
7
0
9
7
8
6
5
4
2
3
5
1
0
8
9
7
6
5
3
2
4
6
0
1
7
9
8
5
4
6
3
2
3
1
0
7
8
9
5
6
4
3
2
4
1
0
6
4
5
3
1
2
0
6
4
3
5
1
2
0
3
0
2
1
U1
13/42
DDR5_SB_PAR
DDR5_SB_ECC0
DDR5_SB_ECC1
DDR5_SB_ECC2
DDR5_SB_ECC3
DDR5_SB_ECC4
DDR5_SB_ECC5
DDR5_SB_ECC6
DDR5_SB_ECC7
DDR5_SB_DQS_DP0
DDR5_SB_DQS_DP1
DDR5_SB_DQS_DP2
DDR5_SB_DQS_DP3
DDR5_SB_DQS_DP4
DDR5_SB_DQS_DP5
DDR5_SB_DQS_DP6
DDR5_SB_DQS_DP7
DDR5_SB_DQS_DP8
DDR5_SB_DQS_DP9
DDR5_SB_DQS_DN0
DDR5_SB_DQS_DN1
DDR5_SB_DQS_DN2
DDR5_SB_DQS_DN3
DDR5_SB_DQS_DN4
DDR5_SB_DQS_DN5
DDR5_SB_DQS_DN6
DDR5_SB_DQS_DN7
DDR5_SB_DQS_DN8
DDR5_SB_DQS_DN9
DDR5_SB_DQ0
DDR5_SB_DQ1
DDR5_SB_DQ2
DDR5_SB_DQ3
DDR5_SB_DQ4
DDR5_SB_DQ5
DDR5_SB_DQ6
DDR5_SB_DQ7
DDR5_SB_DQ8
DDR5_SB_DQ9
DDR5_SB_DQ10
DDR5_SB_DQ11
DDR5_SB_DQ12
DDR5_SB_DQ13
DDR5_SB_DQ14
DDR5_SB_DQ15
DDR5_SB_DQ16
DDR5_SB_DQ17
DDR5_SB_DQ18
DDR5_SB_DQ19
DDR5_SB_DQ20
DDR5_SB_DQ21
DDR5_SB_DQ22
DDR5_SB_DQ23
DDR5_SB_DQ24
DDR5_SB_DQ25
DDR5_SB_DQ26
DDR5_SB_DQ27
DDR5_SB_DQ28
DDR5_SB_DQ29
DDR5_SB_DQ30
DDR5_SB_DQ31
DDR5_SB_CS_N0
DDR5_SB_CS_N1
DDR5_SB_CS_N2
DDR5_SB_CS_N3
DDR5_SB_CA0
DDR5_SB_CA1
DDR5_SB_CA2
DDR5_SB_CA3
DDR5_SB_CA4
DDR5_SB_CA5
DDR5_SB_CA6
DDR5_SA_PAR
DDR5_SA_ECC0
DDR5_SA_ECC1
DDR5_SA_ECC2
DDR5_SA_ECC3
DDR5_SA_ECC4
DDR5_SA_ECC5
DDR5_SA_ECC6
DDR5_SA_ECC7
DDR5_SA_DQS_DP0
DDR5_SA_DQS_DP1
DDR5_SA_DQS_DP2
DDR5_SA_DQS_DP3
DDR5_SA_DQS_DP4
DDR5_SA_DQS_DP5
DDR5_SA_DQS_DP6
DDR5_SA_DQS_DP7
DDR5_SA_DQS_DP8
DDR5_SA_DQS_DP9
DDR5_SA_DQS_DN0
DDR5_SA_DQS_DN1
DDR5_SA_DQS_DN2
DDR5_SA_DQS_DN3
DDR5_SA_DQS_DN4
DDR5_SA_DQS_DN5
DDR5_SA_DQS_DN6
DDR5_SA_DQS_DN7
DDR5_SA_DQS_DN8
DDR5_SA_DQS_DN9
DDR5_SA_DQ0
DDR5_SA_DQ1
DDR5_SA_DQ2
DDR5_SA_DQ3
DDR5_SA_DQ4
DDR5_SA_DQ5
DDR5_SA_DQ6
DDR5_SA_DQ7
DDR5_SA_DQ8
DDR5_SA_DQ9
DDR5_SA_DQ10
DDR5_SA_DQ11
DDR5_SA_DQ12
DDR5_SA_DQ13
DDR5_SA_DQ14
DDR5_SA_DQ15
DDR5_SA_DQ16
DDR5_SA_DQ17
DDR5_SA_DQ18
DDR5_SA_DQ19
DDR5_SA_DQ20
DDR5_SA_DQ21
DDR5_SA_DQ22
DDR5_SA_DQ23
DDR5_SA_DQ24
DDR5_SA_DQ25
DDR5_SA_DQ26
DDR5_SA_DQ27
DDR5_SA_DQ28
DDR5_SA_DQ29
DDR5_SA_DQ30
DDR5_SA_DQ31
DDR5_SA_CS_N0
DDR5_SA_CS_N1
DDR5_SA_CS_N2
DDR5_SA_CS_N3
DDR5_SA_CA0
DDR5_SA_CA1
DDR5_SA_CA2
DDR5_SA_CA3
DDR5_SA_CA4
DDR5_SA_CA5
DDR5_SA_CA6
DDR5_CLK_DP0
DDR5_CLK_DP1
DDR5_CLK_DN0
DDR5_CLK_DN1
DDR5_B_RSP0
DDR5_B_RSP1
DDR5_A_RSP0
DDR5_A_RSP1
DDR5_ALERT_N
SHEETDATE
DEPARTMENT
SIZE
PROJECT DOCUMENT NUMBER REV
REVIEWER
DESIGNER
123
7 3 2 1 6 5 4
E
A
B
C
E
D
C
B
A
7 6 5 4
D
ININ
ININ
IN
BI
BI
OUT
BI
BI
BI
BI
BI
OUT
BI
OUT
OUT
OUT
BI
BI
OUT
C



Fri Aug 25 14:00:39 2023N/AN/AN/AN/AV0557 OF 312SPR CPU1 - DDR CH G (14 OF 30)110111110111110111110111110111110111
110111
110111110111110111110111
110111110111110111110111110111110111110111110111M_G_CPU1_SB_CB<7:0>M_G_CPU1_SB_PARM_G_CPU1_SA_PARM_G_CPU1_SB_RSP<0>M_G_CPU1_SB_RSP<1>M_G_CPU1_SA_RSP<0>M_G_CPU1_SA_RSP<1>M_G_CPU1_ALERT_N
SOCKET4677_AZIF0045-P001C01CSIOSMLFM_G_CPU1_SA_DQS_DP<9:0>
M_G_CPU1_CLK_DN<1:0>M_G_CPU1_CLK_DP<1:0>M_G_CPU1_SA_CA<6:0>M_G_CPU1_SA_CS_N<3:0>
M_G_CPU1_SA_DQ<31:0>M_G_CPU1_SA_DQS_DN<9:0>M_G_CPU1_SA_CB<7:0>M_G_CPU1_SB_CA<6:0>M_G_CPU1_SB_CS_N<3:0>M_G_CPU1_SB_DQ<31:0>M_G_CPU1_SB_DQS_DN<9:0>M_G_CPU1_SB_DQS_DP<9:0>
DV40
DU41
DY40
EA41
DK53
DL54
DP53
DN54
EB42
EA37
DY38
DU37
DV38
DY34
EA35
DV34
DU35
DT36
EN5
DY24
DR27
DN33
DY36
EN7
DT24
DL27
DL33
DV36
EM6
EB24
DN27
DR33
EB36
EP6
DV24
DJ27
DJ33
EM4
EP4
EJ5
EK6
ET8
EP8
EH8
EK8
DY22
EA23
DV22
DU23
EA25
DY26
DU25
DV26
DN25
DP26
DL25
DK26
DP28
DL29
DK28
DN29
DN31
DP32
DL31
DK32
DP34
DN35
DK34
DL35
DT42
EA43
DU43
DY44
DV44
DP44
DN43
DL43
DN56
DP57
DL56
DK57
DP59
DN60
DK59
DL60
DN58
DN64
DY61
DN70
DY73
DJ58
DJ64
DV61
DL70
DT73
DR58
DR64
EB61
DR70
EB73
DL58
DL64
DT61
DJ70
DV73
DN62
DP63
DL62
DK63
DP65
DN66
DK65
DL66
DY59
EA60
DV59
DU60
EA62
DY63
DU62
DV63
DN68
DP69
DL68
DK69
DP71
DN72
DK71
DL72
DY71
EA72
DV71
DU72
EA74
DY75
DU74
DV75
DK44
DN50
DL50
DP51
DK51
DR52
DJ52
DJ45
DN45
DL45
DR45
DV47
DU48
CW50
DY47
EA48
27
0
2
2
0
1
3
31
0
30
29
27
28
26
25
24
23
22
21
20
19
18
17
16
15
14
13
12
11
9
10
8
7
6
4
5
3
2
0
1
1
7
6
5
4
3
2
1
31
0
0
30
29
28
26
25
24
23
1
22
21
20
19
18
17
16
15
14
13
0
12
11
10
8
9
7
6
5
3
4
2
1
0
7
9
8
7
6
5
4
6
3
2
1
0
6
7
8
9
5
4
5
3
2
1
0
9
8
5
7
6
4
4
3
9
2
1
0
8
7
6
5
4
3
3
2
1
0
6
5
4
3
2
1
2
0
6
5
4
3
2
1
0
1
3
1
U1
14/42
DDR6_SB_PAR
DDR6_SB_ECC0
DDR6_SB_ECC1
DDR6_SB_ECC2
DDR6_SB_ECC3
DDR6_SB_ECC4
DDR6_SB_ECC5
DDR6_SB_ECC6
DDR6_SB_ECC7
DDR6_SB_DQS_DP0
DDR6_SB_DQS_DP1
DDR6_SB_DQS_DP2
DDR6_SB_DQS_DP3
DDR6_SB_DQS_DP4
DDR6_SB_DQS_DP5
DDR6_SB_DQS_DP6
DDR6_SB_DQS_DP7
DDR6_SB_DQS_DP8
DDR6_SB_DQS_DP9
DDR6_SB_DQS_DN0
DDR6_SB_DQS_DN1
DDR6_SB_DQS_DN2
DDR6_SB_DQS_DN3
DDR6_SB_DQS_DN4
DDR6_SB_DQS_DN5
DDR6_SB_DQS_DN6
DDR6_SB_DQS_DN7
DDR6_SB_DQS_DN8
DDR6_SB_DQS_DN9
DDR6_SB_DQ0
DDR6_SB_DQ1
DDR6_SB_DQ2
DDR6_SB_DQ3
DDR6_SB_DQ4
DDR6_SB_DQ5
DDR6_SB_DQ6
DDR6_SB_DQ7
DDR6_SB_DQ8
DDR6_SB_DQ9
DDR6_SB_DQ10
DDR6_SB_DQ11
DDR6_SB_DQ12
DDR6_SB_DQ13
DDR6_SB_DQ14
DDR6_SB_DQ15
DDR6_SB_DQ16
DDR6_SB_DQ17
DDR6_SB_DQ18
DDR6_SB_DQ19
DDR6_SB_DQ20
DDR6_SB_DQ21
DDR6_SB_DQ22
DDR6_SB_DQ23
DDR6_SB_DQ24
DDR6_SB_DQ25
DDR6_SB_DQ26
DDR6_SB_DQ27
DDR6_SB_DQ28
DDR6_SB_DQ29
DDR6_SB_DQ30
DDR6_SB_DQ31
DDR6_SB_CS_N0
DDR6_SB_CS_N1
DDR6_SB_CS_N2
DDR6_SB_CS_N3
DDR6_SB_CA0
DDR6_SB_CA1
DDR6_SB_CA2
DDR6_SB_CA3
DDR6_SB_CA4
DDR6_SB_CA5
DDR6_SB_CA6
DDR6_SA_PAR
DDR6_SA_ECC0
DDR6_SA_ECC1
DDR6_SA_ECC2
DDR6_SA_ECC3
DDR6_SA_ECC4
DDR6_SA_ECC5
DDR6_SA_ECC6
DDR6_SA_ECC7
DDR6_SA_DQS_DP0
DDR6_SA_DQS_DP1
DDR6_SA_DQS_DP2
DDR6_SA_DQS_DP3
DDR6_SA_DQS_DP4
DDR6_SA_DQS_DP5
DDR6_SA_DQS_DP6
DDR6_SA_DQS_DP7
DDR6_SA_DQS_DP8
DDR6_SA_DQS_DP9
DDR6_SA_DQS_DN0
DDR6_SA_DQS_DN1
DDR6_SA_DQS_DN2
DDR6_SA_DQS_DN3
DDR6_SA_DQS_DN4
DDR6_SA_DQS_DN5
DDR6_SA_DQS_DN6
DDR6_SA_DQS_DN7
DDR6_SA_DQS_DN8
DDR6_SA_DQS_DN9
DDR6_SA_DQ0
DDR6_SA_DQ1
DDR6_SA_DQ2
DDR6_SA_DQ3
DDR6_SA_DQ4
DDR6_SA_DQ5
DDR6_SA_DQ6
DDR6_SA_DQ7
DDR6_SA_DQ8
DDR6_SA_DQ9
DDR6_SA_DQ10
DDR6_SA_DQ11
DDR6_SA_DQ12
DDR6_SA_DQ13
DDR6_SA_DQ14
DDR6_SA_DQ15
DDR6_SA_DQ16
DDR6_SA_DQ17
DDR6_SA_DQ18
DDR6_SA_DQ19
DDR6_SA_DQ20
DDR6_SA_DQ21
DDR6_SA_DQ22
DDR6_SA_DQ23
DDR6_SA_DQ24
DDR6_SA_DQ25
DDR6_SA_DQ26
DDR6_SA_DQ27
DDR6_SA_DQ28
DDR6_SA_DQ29
DDR6_SA_DQ30
DDR6_SA_DQ31
DDR6_SA_CS_N0
DDR6_SA_CS_N1
DDR6_SA_CS_N2
DDR6_SA_CS_N3
DDR6_SA_CA0
DDR6_SA_CA1
DDR6_SA_CA2
DDR6_SA_CA3
DDR6_SA_CA4
DDR6_SA_CA5
DDR6_SA_CA6
DDR6_CLK_DP0
DDR6_CLK_DP1
DDR6_CLK_DN0
DDR6_CLK_DN1
DDR6_B_RSP0
DDR6_B_RSP1
DDR6_A_RSP0
DDR6_A_RSP1
DDR6_ALERT_N
SHEETDATE
DEPARTMENT
SIZE
PROJECT DOCUMENT NUMBER REV
REVIEWER
DESIGNER
123
7 3 2 1 6 5 4
E
A
B
C
E
D
C
B
A
7 6 5 4
D
ININ
IN
BI
BI
BI
BI
OUT
BI
BI
BI
BI
BI
OUT
BI
OUT
OUT
OUT
ININ
OUT
C



Fri Aug 25 14:00:40 2023N/AN/AN/AN/AV0558 OF 312SPR CPU1 - DDR CH H (15 OF 30)112 113112 113112113112113112 113112113112113112 113112 113
112113112 113112 113112113112 113112 113112113112 113112 113112113M_H_CPU1_SB_PARM_H_CPU1_SA_PARM_H_CPU1_SB_RSP<0>M_H_CPU1_SB_RSP<1>M_H_CPU1_SA_RSP<0>M_H_CPU1_SA_RSP<1>M_H_CPU1_ALERT_N
SOCKET4677_AZIF0045-P001C01CSIOSMLF
M_H_CPU1_CLK_DN<1:0>M_H_CPU1_CLK_DP<1:0>M_H_CPU1_SA_CA<6:0>M_H_CPU1_SA_CS_N<3:0>
M_H_CPU1_SA_DQ<31:0>M_H_CPU1_SA_DQS_DN<9:0>M_H_CPU1_SA_DQS_DP<9:0>M_H_CPU1_SA_CB<7:0>M_H_CPU1_SB_CA<6:0>M_H_CPU1_SB_CS_N<3:0>M_H_CPU1_SB_DQ<31:0>M_H_CPU1_SB_DQS_DN<9:0>M_H_CPU1_SB_DQS_DP<9:0>M_H_CPU1_SB_CB<7:0>
DP38
DK38
DN37
DL37
DC50
DD51
DG50
DF51
DR39
DC37
DD38
DG37
DF38
DF34
DG35
DD34
DC35
DB36
DH18
DN21
DF24
DF30
DF36
DD18
DJ21
DB24
DB30
DD36
DF18
DR21
DH24
DH30
DH36
DB18
DL21
DD24
DD30
DC17
DJ17
DA17
DG17
DG19
DF20
DC19
DD20
DN19
DP20
DL19
DK20
DP22
DN23
DK22
DL23
DF22
DG23
DD22
DC23
DG25
DF26
DC25
DD26
DD28
DG29
DF28
DC29
DG31
DF32
DC31
DD32
DJ39
DP40
DK40
DN41
DL41
DG41
DF40
DD40
DF53
DG54
DD53
DC54
DG56
DF57
DC56
DD57
DF55
DF61
DF67
DF73
DN76
DB55
DB61
DB67
DD73
DL76
DH55
DH61
DH67
DH73
DR76
DD55
DD61
DD67
DB73
DJ76
DF59
DG60
DD59
DC60
DG62
DF63
DC62
DD63
DF65
DG66
DD65
DC66
DG68
DF69
DC68
DD69
DF71
DG72
DD71
DC72
DG74
DF75
DC74
DD75
DN74
DP75
DL74
DK75
DP77
DW78
DT77
DY79
DC41
DF47
DD47
DG48
DC48
DH49
DB49
DB42
DF42
DD42
DH42
ED47
EE48
CY51
EH47
EG48
1
2
3
0
2
1
3
0
31
30
1
29
28
26
27
25
23
24
21
22
0
20
18
19
17
16
15
13
14
12
11
0
10
8
9
6
7
5
3
4
2
0
1
1
6
7
5
3
4
1
2
0
30
31
29
28
27
26
25
24
23
22
20
21
19
17
18
16
15
14
12
13
11
10
9
7
8
5
6
4
2
3
1
7
0
8
9
7
1
3
2
6
5
5
4
7
0
8
9
4
6
2
3
6
5
0
1
9
6
4
5
4
7
8
0
3
2
1
6
5
7
8
2
9
0
1
4
3
2
3
5
6
4
3
0
1
2
0
5
3
6
4
1
2
0
1
U1
15/42
DDR7_SB_PAR
DDR7_SB_ECC0
DDR7_SB_ECC1
DDR7_SB_ECC2
DDR7_SB_ECC3
DDR7_SB_ECC4
DDR7_SB_ECC5
DDR7_SB_ECC6
DDR7_SB_ECC7
DDR7_SB_DQS_DP0
DDR7_SB_DQS_DP1
DDR7_SB_DQS_DP2
DDR7_SB_DQS_DP3
DDR7_SB_DQS_DP4
DDR7_SB_DQS_DP5
DDR7_SB_DQS_DP6
DDR7_SB_DQS_DP7
DDR7_SB_DQS_DP8
DDR7_SB_DQS_DP9
DDR7_SB_DQS_DN0
DDR7_SB_DQS_DN1
DDR7_SB_DQS_DN2
DDR7_SB_DQS_DN3
DDR7_SB_DQS_DN4
DDR7_SB_DQS_DN5
DDR7_SB_DQS_DN6
DDR7_SB_DQS_DN7
DDR7_SB_DQS_DN8
DDR7_SB_DQS_DN9
DDR7_SB_DQ0
DDR7_SB_DQ1
DDR7_SB_DQ2
DDR7_SB_DQ3
DDR7_SB_DQ4
DDR7_SB_DQ5
DDR7_SB_DQ6
DDR7_SB_DQ7
DDR7_SB_DQ8
DDR7_SB_DQ9
DDR7_SB_DQ10
DDR7_SB_DQ11
DDR7_SB_DQ12
DDR7_SB_DQ13
DDR7_SB_DQ14
DDR7_SB_DQ15
DDR7_SB_DQ16
DDR7_SB_DQ17
DDR7_SB_DQ18
DDR7_SB_DQ19
DDR7_SB_DQ20
DDR7_SB_DQ21
DDR7_SB_DQ22
DDR7_SB_DQ23
DDR7_SB_DQ24
DDR7_SB_DQ25
DDR7_SB_DQ26
DDR7_SB_DQ27
DDR7_SB_DQ28
DDR7_SB_DQ29
DDR7_SB_DQ30
DDR7_SB_DQ31
DDR7_SB_CS_N0
DDR7_SB_CS_N1
DDR7_SB_CS_N2
DDR7_SB_CS_N3
DDR7_SB_CA0
DDR7_SB_CA1
DDR7_SB_CA2
DDR7_SB_CA3
DDR7_SB_CA4
DDR7_SB_CA5
DDR7_SB_CA6
DDR7_SA_PAR
DDR7_SA_ECC0
DDR7_SA_ECC1
DDR7_SA_ECC2
DDR7_SA_ECC3
DDR7_SA_ECC4
DDR7_SA_ECC5
DDR7_SA_ECC6
DDR7_SA_ECC7
DDR7_SA_DQS_DP0
DDR7_SA_DQS_DP1
DDR7_SA_DQS_DP2
DDR7_SA_DQS_DP3
DDR7_SA_DQS_DP4
DDR7_SA_DQS_DP5
DDR7_SA_DQS_DP6
DDR7_SA_DQS_DP7
DDR7_SA_DQS_DP8
DDR7_SA_DQS_DP9
DDR7_SA_DQS_DN0
DDR7_SA_DQS_DN1
DDR7_SA_DQS_DN2
DDR7_SA_DQS_DN3
DDR7_SA_DQS_DN4
DDR7_SA_DQS_DN5
DDR7_SA_DQS_DN6
DDR7_SA_DQS_DN7
DDR7_SA_DQS_DN8
DDR7_SA_DQS_DN9
DDR7_SA_DQ0
DDR7_SA_DQ1
DDR7_SA_DQ2
DDR7_SA_DQ3
DDR7_SA_DQ4
DDR7_SA_DQ5
DDR7_SA_DQ6
DDR7_SA_DQ7
DDR7_SA_DQ8
DDR7_SA_DQ9
DDR7_SA_DQ10
DDR7_SA_DQ11
DDR7_SA_DQ12
DDR7_SA_DQ13
DDR7_SA_DQ14
DDR7_SA_DQ15
DDR7_SA_DQ16
DDR7_SA_DQ17
DDR7_SA_DQ18
DDR7_SA_DQ19
DDR7_SA_DQ20
DDR7_SA_DQ21
DDR7_SA_DQ22
DDR7_SA_DQ23
DDR7_SA_DQ24
DDR7_SA_DQ25
DDR7_SA_DQ26
DDR7_SA_DQ27
DDR7_SA_DQ28
DDR7_SA_DQ29
DDR7_SA_DQ30
DDR7_SA_DQ31
DDR7_SA_CS_N0
DDR7_SA_CS_N1
DDR7_SA_CS_N2
DDR7_SA_CS_N3
DDR7_SA_CA0
DDR7_SA_CA1
DDR7_SA_CA2
DDR7_SA_CA3
DDR7_SA_CA4
DDR7_SA_CA5
DDR7_SA_CA6
DDR7_CLK_DP0
DDR7_CLK_DP1
DDR7_CLK_DN0
DDR7_CLK_DN1
DDR7_B_RSP0
DDR7_B_RSP1
DDR7_A_RSP0
DDR7_A_RSP1
DDR7_ALERT_N
SHEETDATE
DEPARTMENT
SIZE
PROJECT DOCUMENT NUMBER REV
REVIEWER
DESIGNER
123
7 3 2 1 6 5 4
E
A
B
C
E
D
C
B
A
7 6 5 4
D
BI
BI
BI
BI
OUT
BI
BI
BI
BI
BI
OUT
BI
OUT
OUT
OUT
ININ
ININ
IN
OUT
C



Fri Aug 25 14:00:41 2023N/AN/AN/AN/AV0559 OF 312SPR CPU1 - DMI (16 OF 30)
SMLFIOSOCKET4677_AZIF0045-P001C01CSTP_DMI_CPU1_PCH_RX_C_DN<7:0>TP_DMI_CPU1_PCH_RX_C_DP<7:0>TP_DMI_CPU1_PCH_TX_DN<7:0>TP_DMI_CPU1_PCH_TX_DP<7:0>
CM18
CL19
CH18
CG19
CD18
CC19
BY18
CA19
CN17
CK18
CJ17
CF18
CE17
CB18
CA17
BW19
BT18
BR19
BM18
BL19
BH18
BG19
BD18
BC19
BU17
BP18
BN17
BK18
BJ17
BF18
BE17
BB18
7
4
3
0
1
2
7
4
5
6
2
3
0
1
6
7
5
4
3
1
2
0
5
4
6
7
1
0
2
3
5
6
U1
16/42
DMI_TX_DP0
DMI_TX_DP1
DMI_TX_DP2
DMI_TX_DP3
DMI_TX_DP4
DMI_TX_DP5
DMI_TX_DP6
DMI_TX_DP7
DMI_TX_DN0
DMI_TX_DN1
DMI_TX_DN2
DMI_TX_DN3
DMI_TX_DN4
DMI_TX_DN5
DMI_TX_DN6
DMI_TX_DN7
DMI_RX_DP0
DMI_RX_DP1
DMI_RX_DP2
DMI_RX_DP3
DMI_RX_DP4
DMI_RX_DP5
DMI_RX_DP6
DMI_RX_DP7
DMI_RX_DN0
DMI_RX_DN1
DMI_RX_DN2
DMI_RX_DN3
DMI_RX_DN4
DMI_RX_DN5
DMI_RX_DN6
DMI_RX_DN7
SHEETDATE
DEPARTMENT
SIZE
PROJECT DOCUMENT NUMBER REV
REVIEWER
DESIGNER
123
7 3 2 1 6 5 4
E
A
B
C
E
D
C
B
A
7 6 5 4
D
C



20210818 MODIFY FOR GT
Fri Aug 25 14:00:42 2023N/AN/AN/AN/AV0560 OF 312SPR CPU1 - PCIE PE0/PE1 (17 OF 30)159176176175175159142143142143SMLFIOSOCKET4677_AZIF0045-P001C01CSSMLFIOSOCKET4677_AZIF0045-P001C01CSP5E_CPU1_PE1_RX_DN<15:0>P5E_CPU1_PE0_TX_DN<15:0>P5E_CPU1_PE0_TX_DP<15:0>P5E_CPU1_PE1_TX_DP<15:0>P5E_CPU1_PE1_TX_DN<15:0>P5E_CPU1_PE1_RX_DP<15:0>P5E_CPU1_PE0_RX_DP<15:0>P5E_CPU1_PE0_RX_DN<15:0>
BC15
AY14
AW15
AT14
AR15
AM14
AL15
AH14
AG15
AD14
AC15
Y14
W15
T14
R15
M14
BB14
BA13
AV14
AU13
AP14
AN13
AK14
AJ13
AF14
AE13
AB14
AA13
V14
U13
P14
N13
AY10
AW11
AT10
AR11
AN9
AL11
AH10
AG11
AD10
AC11
Y10
W11
U9
R11
N9
L11
BA9
AV10
AU9
AP10
AM10
AK10
AJ9
AF10
AE9
AB10
AA9
V10
T10
P10
M10
K10
BD14
BG15
BH14
BL15
BM14
BR15
BT14
BW15
BY14
CC15
CD14
CG15
CH14
CL15
CM14
CR15
BE13
BF14
BJ13
BK14
BN13
BP14
BU13
BV14
CA13
CB14
CE13
CF14
CJ13
CK14
CN13
CP14
BD10
BE9
BH10
BJ9
BM10
BN9
BT10
BU9
BY10
CA9
CD10
CE9
CH10
CJ9
CM10
CN9
BC11
BF10
BG11
BK10
BL11
BP10
BR11
BV10
BW11
CB10
CC11
CF10
CG11
CK10
CL11
CP10
4
15
1
0
2
3
4
6
5
8
7
9
10
11
12
15
13
14
1
0
2
3
7
5
6
9
8
14
13
10
12
11
0
1
2
3
5
6
4
9
8
7
11
10
14
13
12
15
2
1
0
3
4
7
5
6
8
9
11
12
10
14
15
13
15
14
13
12
11
10
9
8
6
7
4
5
3
1
2
0
15
14
13
10
11
12
9
8
5
7
6
4
3
1
2
0
1
11
10
9
15
14
13
12
11
10
9
8
6
7
4
5
3
2
0
15
14
13
12
8
5
7
6
4
3
1
2
0
U1
U1
17/42
PE0_TX_DP0
PE0_TX_DP1
PE0_TX_DP2
PE0_TX_DP3
PE0_TX_DP4
PE0_TX_DP5
PE0_TX_DP6
PE0_TX_DP7
PE0_TX_DP8
PE0_TX_DP9
PE0_TX_DP10
PE0_TX_DP11
PE0_TX_DP12
PE0_TX_DP13
PE0_TX_DP14
PE0_TX_DP15
PE0_TX_DN0
PE0_TX_DN1
PE0_TX_DN2
PE0_TX_DN3
PE0_TX_DN4
PE0_TX_DN5
PE0_TX_DN6
PE0_TX_DN7
PE0_TX_DN8
PE0_TX_DN9
PE0_TX_DN10
PE0_TX_DN11
PE0_TX_DN12
PE0_TX_DN13
PE0_TX_DN14
PE0_TX_DN15
PE0_RX_DP0
PE0_RX_DP1
PE0_RX_DP2
PE0_RX_DP3
PE0_RX_DP4
PE0_RX_DP5
PE0_RX_DP6
PE0_RX_DP7
PE0_RX_DP8
PE0_RX_DP9
PE0_RX_DP10
PE0_RX_DP11
PE0_RX_DP12
PE0_RX_DP13
PE0_RX_DP14
PE0_RX_DP15
PE0_RX_DN0
PE0_RX_DN1
PE0_RX_DN2
PE0_RX_DN3
PE0_RX_DN4
PE0_RX_DN5
PE0_RX_DN6
PE0_RX_DN7
PE0_RX_DN8
PE0_RX_DN9
PE0_RX_DN10
PE0_RX_DN11
PE0_RX_DN12
PE0_RX_DN13
PE0_RX_DN14
PE0_RX_DN15
18/42
PE1_TX_DP0
PE1_TX_DP1
PE1_TX_DP2
PE1_TX_DP3
PE1_TX_DP4
PE1_TX_DP5
PE1_TX_DP6
PE1_TX_DP7
PE1_TX_DP8
PE1_TX_DP9
PE1_TX_DP10
PE1_TX_DP11
PE1_TX_DP12
PE1_TX_DP13
PE1_TX_DP14
PE1_TX_DP15
PE1_TX_DN0
PE1_TX_DN1
PE1_TX_DN2
PE1_TX_DN3
PE1_TX_DN4
PE1_TX_DN5
PE1_TX_DN6
PE1_TX_DN7
PE1_TX_DN8
PE1_TX_DN9
PE1_TX_DN10
PE1_TX_DN11
PE1_TX_DN12
PE1_TX_DN13
PE1_TX_DN14
PE1_TX_DN15
PE1_RX_DP0
PE1_RX_DP1
PE1_RX_DP2
PE1_RX_DP3
PE1_RX_DP4
PE1_RX_DP5
PE1_RX_DP6
PE1_RX_DP7
PE1_RX_DP8
PE1_RX_DP9
PE1_RX_DP10
PE1_RX_DP11
PE1_RX_DP12
PE1_RX_DP13
PE1_RX_DP14
PE1_RX_DP15
PE1_RX_DN0
PE1_RX_DN1
PE1_RX_DN2
PE1_RX_DN3
PE1_RX_DN4
PE1_RX_DN5
PE1_RX_DN6
PE1_RX_DN7
PE1_RX_DN8
PE1_RX_DN9
PE1_RX_DN10
PE1_RX_DN11
PE1_RX_DN12
PE1_RX_DN13
PE1_RX_DN14
PE1_RX_DN15
SHEETDATE
DEPARTMENT
SIZE
PROJECT DOCUMENT NUMBER REV
REVIEWER
DESIGNER
123
7 3 2 1 6 5 4
E
A
B
C
E
D
C
B
A
7 6 5 4
D OUT
OUT
OUT
OUTIN
IN
IN
IN
C



20210818 MODIFY FOR GT
Fri Aug 25 14:00:43 2023N/AN/AN/AN/AV0561 OF 312SPR CPU1 - PCIE PE2/PE3 (18 OF 30)140141177177176176140141140141
140141SMLFIOSOCKET4677_AZIF0045-P001C01CSSMLFIOSOCKET4677_AZIF0045-P001C01CSP5E_CPU1_PE3_RX_DP<15:0>P5E_CPU1_PE3_TX_DN<15:0>P5E_CPU1_PE3_TX_DP<15:0>P5E_CPU1_PE2_TX_DN<15:0>P5E_CPU1_PE2_TX_DP<15:0>P5E_CPU1_PE2_RX_DN<15:0>P5E_CPU1_PE3_RX_DN<15:0>
P5E_CPU1_PE2_RX_DP<15:0>
EG15
ED14
EC15
DY14
DW15
DT14
DR15
DM14
DL15
DH14
DG15
DD14
DC15
CY14
CW15
CT14
EF14
EE13
EB14
EA13
DV14
DU13
DP14
DN13
DK14
DJ13
DF14
DE13
DB14
DA13
CV14
CU13
EG11
EF10
EC11
EB10
DW11
DV10
DR11
DP10
DL11
DK10
DG11
DF10
DC11
DB10
CW11
CV10
EH10
EE9
ED10
EA9
DY10
DU9
DT10
DN9
DM10
DJ9
DH10
DE9
DD10
DA9
CY10
CU9
CR86
CU86
CW86
DA86
DC86
DE86
DG86
DJ86
DL86
DN86
DR86
DU86
DW86
EA86
EC86
ED87
CP85
CT87
CV85
CY87
DB85
DD87
DF85
DH87
DK85
DM87
DP85
DT87
DV85
DY87
EB85
EE86
CT91
CW90
CY91
DC90
DE90
DF89
DJ90
DK89
DM91
DR90
DT91
DW90
EA90
EB89
EE90
EJ90
CU90
CV89
DA90
DB89
DD91
DG90
DH91
DL90
DN90
DP89
DU90
DV89
DY91
EC90
ED91
EH89
10
13
15
12
12
13
14
15
0
1
2
3
4
6
11
0
1
2
4
3
6
5
7
8
9
10
5
8
7
9
12
13
15
14
11
15
13
10
2
3
8
7
0
1
2
3
4
5
6
15
0
1
4
5
6
7
8
9
11
10
12
14
0
1
2
3
4
5
6
7
8
9
11
12
14
15
13
11
10
9
8
7
6
5
2
4
9
3
1
0
15
14
13
11
9
10
7
8
7
6
5
4
3
2
1
0
6
4
5
3
14
13
12
11
10
2
9
1
14
13
12
11
8
15
12
14
10
0
U1
U1
19/42
PE2_TX_DP0
PE2_TX_DP1
PE2_TX_DP2
PE2_TX_DP3
PE2_TX_DP4
PE2_TX_DP5
PE2_TX_DP6
PE2_TX_DP7
PE2_TX_DP8
PE2_TX_DP9
PE2_TX_DP10
PE2_TX_DP11
PE2_TX_DP12
PE2_TX_DP13
PE2_TX_DP14
PE2_TX_DP15
PE2_TX_DN0
PE2_TX_DN1
PE2_TX_DN2
PE2_TX_DN3
PE2_TX_DN4
PE2_TX_DN5
PE2_TX_DN6
PE2_TX_DN7
PE2_TX_DN8
PE2_TX_DN9
PE2_TX_DN10
PE2_TX_DN11
PE2_TX_DN12
PE2_TX_DN13
PE2_TX_DN14
PE2_TX_DN15
PE2_RX_DP0
PE2_RX_DP1
PE2_RX_DP2
PE2_RX_DP3
PE2_RX_DP4
PE2_RX_DP5
PE2_RX_DP6
PE2_RX_DP7
PE2_RX_DP8
PE2_RX_DP9
PE2_RX_DP10
PE2_RX_DP11
PE2_RX_DP12
PE2_RX_DP13
PE2_RX_DP14
PE2_RX_DP15
PE2_RX_DN0
PE2_RX_DN1
PE2_RX_DN2
PE2_RX_DN3
PE2_RX_DN4
PE2_RX_DN5
PE2_RX_DN6
PE2_RX_DN7
PE2_RX_DN8
PE2_RX_DN9
PE2_RX_DN10
PE2_RX_DN11
PE2_RX_DN12
PE2_RX_DN13
PE2_RX_DN14
PE2_RX_DN15
20/42
PE3_TX_DP0
PE3_TX_DP1
PE3_TX_DP2
PE3_TX_DP3
PE3_TX_DP4
PE3_TX_DP5
PE3_TX_DP6
PE3_TX_DP7
PE3_TX_DP8
PE3_TX_DP9
PE3_TX_DP10
PE3_TX_DP11
PE3_TX_DP12
PE3_TX_DP13
PE3_TX_DP14
PE3_TX_DP15
PE3_TX_DN0
PE3_TX_DN1
PE3_TX_DN2
PE3_TX_DN3
PE3_TX_DN4
PE3_TX_DN5
PE3_TX_DN6
PE3_TX_DN7
PE3_TX_DN8
PE3_TX_DN9
PE3_TX_DN10
PE3_TX_DN11
PE3_TX_DN12
PE3_TX_DN13
PE3_TX_DN14
PE3_TX_DN15
PE3_RX_DP0
PE3_RX_DP1
PE3_RX_DP2
PE3_RX_DP3
PE3_RX_DP4
PE3_RX_DP5
PE3_RX_DP6
PE3_RX_DP7
PE3_RX_DP8
PE3_RX_DP9
PE3_RX_DP10
PE3_RX_DP11
PE3_RX_DP12
PE3_RX_DP13
PE3_RX_DP14
PE3_RX_DP15
PE3_RX_DN0
PE3_RX_DN1
PE3_RX_DN2
PE3_RX_DN3
PE3_RX_DN4
PE3_RX_DN5
PE3_RX_DN6
PE3_RX_DN7
PE3_RX_DN8
PE3_RX_DN9
PE3_RX_DN10
PE3_RX_DN11
PE3_RX_DN12
PE3_RX_DN13
PE3_RX_DN14
PE3_RX_DN15
SHEETDATE
DEPARTMENT
SIZE
PROJECT DOCUMENT NUMBER REV
REVIEWER
DESIGNER
123
7 3 2 1 6 5 4
E
A
B
C
E
D
C
B
A
7 6 5 4
D
OUT
OUT
IN
IN
IN
IN
OUT
OUT
C



20210818 MODIFY FOR GT
Fri Aug 25 14:00:44 2023N/AN/AN/AN/AV0562 OF 312SPR CPU1 - PCIE PE4 (19 OF 30)
177177142143142143SMLFIOSOCKET4677_AZIF0045-P001C01CSP5E_CPU1_PE4_TX_DN<15:0>P5E_CPU1_PE4_TX_DP<15:0>P5E_CPU1_PE4_RX_DN<15:0>P5E_CPU1_PE4_RX_DP<15:0>
BB85
AY87
AV85
AT87
AN86
AM87
AK85
AH87
AF85
AD87
AB85
Y87
V85
T87
N86
M87
BA86
AW86
AU86
AR86
AP85
AL86
AJ86
AG86
AE86
AC86
AA86
W86
U86
R86
P85
L86
BA90
AW90
AU90
AR90
AN90
AL90
AJ90
AG90
AE90
AC90
AA90
W90
U90
R90
N90
K89
BB89
AY91
AV89
AT91
AP89
AM91
AK89
AH91
AF89
AD91
AB89
Y91
V89
T91
P89
J90
5
0
1
6
2
3
4
10
12
11
7
8
0
13
15
14
5
4
1
2
8
10
9
6
7
13
11
12
14
15
3
9
0
1
2
3
4
5
6
7
10
11
12
13
15
14
1
0
2
3
4
5
6
7
8
9
10
11
12
13
14
15
8
9
U1
21/42
PE4_TX_DP0
PE4_TX_DP1
PE4_TX_DP2
PE4_TX_DP3
PE4_TX_DP4
PE4_TX_DP5
PE4_TX_DP6
PE4_TX_DP7
PE4_TX_DP8
PE4_TX_DP9
PE4_TX_DP10
PE4_TX_DP11
PE4_TX_DP12
PE4_TX_DP13
PE4_TX_DP14
PE4_TX_DP15
PE4_TX_DN0
PE4_TX_DN1
PE4_TX_DN2
PE4_TX_DN3
PE4_TX_DN4
PE4_TX_DN5
PE4_TX_DN6
PE4_TX_DN7
PE4_TX_DN8
PE4_TX_DN9
PE4_TX_DN10
PE4_TX_DN11
PE4_TX_DN12
PE4_TX_DN13
PE4_TX_DN14
PE4_TX_DN15
PE4_RX_DP0
PE4_RX_DP1
PE4_RX_DP2
PE4_RX_DP3
PE4_RX_DP4
PE4_RX_DP5
PE4_RX_DP6
PE4_RX_DP7
PE4_RX_DP8
PE4_RX_DP9
PE4_RX_DP10
PE4_RX_DP11
PE4_RX_DP12
PE4_RX_DP13
PE4_RX_DP14
PE4_RX_DP15
PE4_RX_DN0
PE4_RX_DN1
PE4_RX_DN2
PE4_RX_DN3
PE4_RX_DN4
PE4_RX_DN5
PE4_RX_DN6
PE4_RX_DN7
PE4_RX_DN8
PE4_RX_DN9
PE4_RX_DN10
PE4_RX_DN11
PE4_RX_DN12
PE4_RX_DN13
PE4_RX_DN14
PE4_RX_DN15
SHEETDATE
DEPARTMENT
SIZE
PROJECT DOCUMENT NUMBER REV
REVIEWER
DESIGNER
123
7 3 2 1 6 5 4
E
A
B
C
E
D
C
B
A
7 6 5 4
D
IN
IN
OUT
OUT
C



Fri Aug 25 14:00:45 2023N/AN/AN/AN/AV0563 OF 312SPR CPU1 - UPI0 (20 OF 30)
3333 3333SMLFIOSOCKET4677_AZIF0045-P001C01CSUPI_CPU0_CPU1_P1P0_DN<23:0>UPI_CPU0_CPU1_P1P0_DP<23:0>UPI_CPU1_CPU0_P0P1_DN<23:0>UPI_CPU1_CPU0_P0P1_DP<23:0>
BU3
BN3
BL3
BJ1
BG3
BE1
BC3
BA1
AW3
AV2
AR3
AN1
AL3
AJ1
AG3
AE1
AC3
AB2
W3
V2
R3
P2
L3
J3
BT2
BR3
BM2
BK2
BH2
BF2
BD2
BB2
AY2
AU1
AT2
AP2
AM2
AK2
AH2
AF2
AD2
AA1
Y2
U1
T2
N1
M2
K4
BT6
BP6
BM6
BL7
BH6
BG7
BD6
BC7
AY6
AW7
AT6
AR7
AM6
AL7
AJ5
AG7
AD6
AC7
Y6
W7
T6
R7
M6
L7
BU5
BR7
BN5
BK6
BJ5
BF6
BE5
BB6
BA5
AV6
AU5
AP6
AN5
AK6
AH6
AF6
AE5
AB6
AA5
V6
U5
P6
N5
K6
22
23
17
18
21
19
20
14
16
15
8
13
12
11
6
7
8
10
9
4
3
6
5
1
2
22
0
21
23
20
19
18
7
16
17
14
13
15
11
12
9
8
10
5
7
6
3
4
5
2
1
0
23
4
22
21
19
20
17
18
16
15
14
13
3
12
11
9
10
8
7
6
4
5
3
2
1
2
0
23
22
21
19
20
18
17
1
16
15
13
14
11
12
10
9
0
U1
22/42
UPI0_TX_DP0
UPI0_TX_DP1
UPI0_TX_DP2
UPI0_TX_DP3
UPI0_TX_DP4
UPI0_TX_DP5
UPI0_TX_DP6
UPI0_TX_DP7
UPI0_TX_DP8
UPI0_TX_DP9
UPI0_TX_DP10
UPI0_TX_DP11
UPI0_TX_DP12
UPI0_TX_DP13
UPI0_TX_DP14
UPI0_TX_DP15
UPI0_TX_DP16
UPI0_TX_DP17
UPI0_TX_DP18
UPI0_TX_DP19
UPI0_TX_DP20
UPI0_TX_DP21
UPI0_TX_DP22
UPI0_TX_DP23
UPI0_TX_DN0
UPI0_TX_DN1
UPI0_TX_DN2
UPI0_TX_DN3
UPI0_TX_DN4
UPI0_TX_DN5
UPI0_TX_DN6
UPI0_TX_DN7
UPI0_TX_DN8
UPI0_TX_DN9
UPI0_TX_DN10
UPI0_TX_DN11
UPI0_TX_DN12
UPI0_TX_DN13
UPI0_TX_DN14
UPI0_TX_DN15
UPI0_TX_DN16
UPI0_TX_DN17
UPI0_TX_DN18
UPI0_TX_DN19
UPI0_TX_DN20
UPI0_TX_DN21
UPI0_TX_DN22
UPI0_TX_DN23
UPI0_RX_DP0
UPI0_RX_DP1
UPI0_RX_DP2
UPI0_RX_DP3
UPI0_RX_DP4
UPI0_RX_DP5
UPI0_RX_DP6
UPI0_RX_DP7
UPI0_RX_DP8
UPI0_RX_DP9
UPI0_RX_DP10
UPI0_RX_DP11
UPI0_RX_DP12
UPI0_RX_DP13
UPI0_RX_DP14
UPI0_RX_DP15
UPI0_RX_DP16
UPI0_RX_DP17
UPI0_RX_DP18
UPI0_RX_DP19
UPI0_RX_DP20
UPI0_RX_DP21
UPI0_RX_DP22
UPI0_RX_DP23
UPI0_RX_DN0
UPI0_RX_DN1
UPI0_RX_DN2
UPI0_RX_DN3
UPI0_RX_DN4
UPI0_RX_DN5
UPI0_RX_DN6
UPI0_RX_DN7
UPI0_RX_DN8
UPI0_RX_DN9
UPI0_RX_DN10
UPI0_RX_DN11
UPI0_RX_DN12
UPI0_RX_DN13
UPI0_RX_DN14
UPI0_RX_DN15
UPI0_RX_DN16
UPI0_RX_DN17
UPI0_RX_DN18
UPI0_RX_DN19
UPI0_RX_DN20
UPI0_RX_DN21
UPI0_RX_DN22
UPI0_RX_DN23
SHEETDATE
DEPARTMENT
SIZE
PROJECT DOCUMENT NUMBER REV
REVIEWER
DESIGNER
123
7 3 2 1 6 5 4
E
A
B
C
E
D
C
B
A
7 6 5 4
D
IN
IN
OUT
OUT
C



Fri Aug 25 14:00:45 2023N/AN/AN/AN/AV0564 OF 312SPR CPU1 - UPI1 (21 OF 30)
3232 3232SMLFIOSOCKET4677_AZIF0045-P001C01CSUPI_CPU0_CPU1_P0P1_DN<23:0>UPI_CPU0_CPU1_P0P1_DP<23:0>UPI_CPU1_CPU0_P1P0_DN<23:0>UPI_CPU1_CPU0_P1P0_DP<23:0>
BW7
CB6
CC7
CF6
CG7
CK6
CL7
CP6
CR7
CV6
CW7
DB6
DC7
DF6
DG7
DJ5
DM6
DN5
DR7
DU5
DW7
EA5
ED6
EE5
BY6
CA5
CD6
CE5
CH6
CJ5
CM6
CN5
CT6
CU5
CY6
DA5
DD6
DE5
DH6
DK6
DL7
DP6
DT6
DV6
DY6
EB6
EC7
EF6
BY2
CC3
CE1
CG3
CK2
CM2
CP2
CT2
CU1
CW3
DA1
DC3
DF2
DH2
DK2
DM2
DP2
DR3
DV2
DW3
EB2
EC3
EG3
EJ3
CB2
CD2
CF2
CH2
CJ1
CL3
CN1
CR3
CV2
CY2
DB2
DD2
DE1
DG3
DJ1
DL3
DN1
DT2
DU1
DY2
EA1
ED2
EE3
EH2
20
19
21
22
23
18
17
16
14
15
13
9
10
8
12
11
5
3
4
6
7
23
1
2
0
18
19
20
22
21
15
13
16
17
14
10
8
11
12
9
5
4
7
6
3
2
1
0
23
19
18
17
16
14
11
10
9
8
7
6
4
5
3
2
1
0
22
21
20
15
13
12
23
0
1
2
3
4
5
6
7
8
9
10
11
14
16
17
18
19
12
13
15
20
21
22
U1
23/42
UPI1_TX_DP0
UPI1_TX_DP1
UPI1_TX_DP2
UPI1_TX_DP3
UPI1_TX_DP4
UPI1_TX_DP5
UPI1_TX_DP6
UPI1_TX_DP7
UPI1_TX_DP8
UPI1_TX_DP9
UPI1_TX_DP10
UPI1_TX_DP11
UPI1_TX_DP12
UPI1_TX_DP13
UPI1_TX_DP14
UPI1_TX_DP15
UPI1_TX_DP16
UPI1_TX_DP17
UPI1_TX_DP18
UPI1_TX_DP19
UPI1_TX_DP20
UPI1_TX_DP21
UPI1_TX_DP22
UPI1_TX_DP23
UPI1_TX_DN0
UPI1_TX_DN1
UPI1_TX_DN2
UPI1_TX_DN3
UPI1_TX_DN4
UPI1_TX_DN5
UPI1_TX_DN6
UPI1_TX_DN7
UPI1_TX_DN8
UPI1_TX_DN9
UPI1_TX_DN10
UPI1_TX_DN11
UPI1_TX_DN12
UPI1_TX_DN13
UPI1_TX_DN14
UPI1_TX_DN15
UPI1_TX_DN16
UPI1_TX_DN17
UPI1_TX_DN18
UPI1_TX_DN19
UPI1_TX_DN20
UPI1_TX_DN21
UPI1_TX_DN22
UPI1_TX_DN23
UPI1_RX_DP0
UPI1_RX_DP1
UPI1_RX_DP2
UPI1_RX_DP3
UPI1_RX_DP4
UPI1_RX_DP5
UPI1_RX_DP6
UPI1_RX_DP7
UPI1_RX_DP8
UPI1_RX_DP9
UPI1_RX_DP10
UPI1_RX_DP11
UPI1_RX_DP12
UPI1_RX_DP13
UPI1_RX_DP14
UPI1_RX_DP15
UPI1_RX_DP16
UPI1_RX_DP17
UPI1_RX_DP18
UPI1_RX_DP19
UPI1_RX_DP20
UPI1_RX_DP21
UPI1_RX_DP22
UPI1_RX_DP23
UPI1_RX_DN0
UPI1_RX_DN1
UPI1_RX_DN2
UPI1_RX_DN3
UPI1_RX_DN4
UPI1_RX_DN5
UPI1_RX_DN6
UPI1_RX_DN7
UPI1_RX_DN8
UPI1_RX_DN9
UPI1_RX_DN10
UPI1_RX_DN11
UPI1_RX_DN12
UPI1_RX_DN13
UPI1_RX_DN14
UPI1_RX_DN15
UPI1_RX_DN16
UPI1_RX_DN17
UPI1_RX_DN18
UPI1_RX_DN19
UPI1_RX_DN20
UPI1_RX_DN21
UPI1_RX_DN22
UPI1_RX_DN23
SHEETDATE
DEPARTMENT
SIZE
PROJECT DOCUMENT NUMBER REV
REVIEWER
DESIGNER
123
7 3 2 1 6 5 4
E
A
B
C
E
D
C
B
A
7 6 5 4
D
IN
OUT
OUT
IN
C



Fri Aug 25 14:00:46 2023N/AN/AN/AN/AV0565 OF 312SPR CPU1 - UPI2 (22 OF 30)
3434 3434SMLFIOSOCKET4677_AZIF0045-P001C01CSUPI_CPU0_CPU1_P2P2_DN<23:0>UPI_CPU0_CPU1_P2P2_DP<23:0>UPI_CPU1_CPU0_P2P2_DN<23:0>UPI_CPU1_CPU0_P2P2_DP<23:0>
BN72
BE80
BG82
BC80
BD83
BA82
BB81
AU82
AV83
AT81
AM83
AP81
AV79
BA78
W82
Y83
V81
P83
T81
G86
H87
E88
F85
D85
BM71
BG80
BF81
BD79
BE82
BC82
BA80
AV81
AT83
AR80
AN82
AM81
AU78
AW78
Y81
V83
U80
R82
P81
H85
F87
D87
E84
B85
BC74
BL74
BM75
BJ74
BN76
BK77
BG76
AV75
BD75
BA76
AY73
BB73
AJ82
AH81
AF83
AG80
AC82
AE80
K81
L82
M79
H83
E82
G80
BD73
BK73
BN74
BG74
BL76
BJ76
BH75
AW74
BB75
AY75
AV73
BA72
AG82
AJ80
AE82
AF79
AD81
AC80
L80
J82
K79
G82
F81
E80
23
22
21
20
19
17
18
16
14
15
7
12
13
11
9
10
7
6
8
5
4
5
0
1
3
2
19
20
21
22
23
18
4
16
17
14
15
13
11
12
8
9
10
3
6
7
3
5
4
0
1
2
23
22
1
21
20
19
18
17
16
15
14
13
12
2
11
10
9
8
6
7
5
4
3
2
0
1
0
23
21
22
20
19
18
17
16
15
14
13
12
11
10
9
8
6
U1
24/42
UPI2_TX_DP0
UPI2_TX_DP1
UPI2_TX_DP2
UPI2_TX_DP3
UPI2_TX_DP4
UPI2_TX_DP5
UPI2_TX_DP6
UPI2_TX_DP7
UPI2_TX_DP8
UPI2_TX_DP9
UPI2_TX_DP10
UPI2_TX_DP11
UPI2_TX_DP12
UPI2_TX_DP13
UPI2_TX_DP14
UPI2_TX_DP15
UPI2_TX_DP16
UPI2_TX_DP17
UPI2_TX_DP18
UPI2_TX_DP19
UPI2_TX_DP20
UPI2_TX_DP21
UPI2_TX_DP22
UPI2_TX_DP23
UPI2_TX_DN0
UPI2_TX_DN1
UPI2_TX_DN2
UPI2_TX_DN3
UPI2_TX_DN4
UPI2_TX_DN5
UPI2_TX_DN6
UPI2_TX_DN7
UPI2_TX_DN8
UPI2_TX_DN9
UPI2_TX_DN10
UPI2_TX_DN11
UPI2_TX_DN12
UPI2_TX_DN13
UPI2_TX_DN14
UPI2_TX_DN15
UPI2_TX_DN16
UPI2_TX_DN17
UPI2_TX_DN18
UPI2_TX_DN19
UPI2_TX_DN20
UPI2_TX_DN21
UPI2_TX_DN22
UPI2_TX_DN23
UPI2_RX_DP0
UPI2_RX_DP1
UPI2_RX_DP2
UPI2_RX_DP3
UPI2_RX_DP4
UPI2_RX_DP5
UPI2_RX_DP6
UPI2_RX_DP7
UPI2_RX_DP8
UPI2_RX_DP9
UPI2_RX_DP10
UPI2_RX_DP11
UPI2_RX_DP12
UPI2_RX_DP13
UPI2_RX_DP14
UPI2_RX_DP15
UPI2_RX_DP16
UPI2_RX_DP17
UPI2_RX_DP18
UPI2_RX_DP19
UPI2_RX_DP20
UPI2_RX_DP21
UPI2_RX_DP22
UPI2_RX_DP23
UPI2_RX_DN0
UPI2_RX_DN1
UPI2_RX_DN2
UPI2_RX_DN3
UPI2_RX_DN4
UPI2_RX_DN5
UPI2_RX_DN6
UPI2_RX_DN7
UPI2_RX_DN8
UPI2_RX_DN9
UPI2_RX_DN10
UPI2_RX_DN11
UPI2_RX_DN12
UPI2_RX_DN13
UPI2_RX_DN14
UPI2_RX_DN15
UPI2_RX_DN16
UPI2_RX_DN17
UPI2_RX_DN18
UPI2_RX_DN19
UPI2_RX_DN20
UPI2_RX_DN21
UPI2_RX_DN22
UPI2_RX_DN23
SHEETDATE
DEPARTMENT
SIZE
PROJECT DOCUMENT NUMBER REV
REVIEWER
DESIGNER
123
7 3 2 1 6 5 4
E
A
B
C
E
D
C
B
A
7 6 5 4
D
IN OUT
OUTIN
C



20211122 MODIFY FOR GT
20211129 CHANGE TX FLOATINGFri Aug 25 14:00:47 2023N/AN/AN/AN/AV0566 OF 312SPR CPU1 - UPI3 (23 OF 30)
SOCKET4677_AZIF0045-P001C01CSIOSMLF
CD73
CW74
CK75
CH75
CF77
CL76
CJ78
CM77
CU74
CR76
CV77
DA76
DN80
DL82
DP83
DR80
DU82
DT81
EL88
EH87
EP87
EN86
EM85
EK85
CF73
CV73
CJ74
CF75
CG76
CM75
CH77
CK77
CR74
CT75
CU76
CW76
DL80
DM81
DN82
DP79
DR82
DU80
EK87
EJ86
EM87
EP85
EL84
EH85
DB79
CU80
CR80
CN82
CV81
CT83
CW82
DE78
DD81
DB83
DF81
DH83
DG82
DH79
DL78
EB81
DY83
ED81
EF83
EE82
EJ82
EN82
ER82
EL80
DA78
CT79
CN80
CP81
CW80
CR82
CU82
DF77
DB81
DC82
DE80
DF83
DH81
DG78
DJ78
DY81
EA82
EC80
ED83
EF81
EK81
EL82
EP81
EJ80
U1
25/42
UPI3_TX_DP0
UPI3_TX_DP1
UPI3_TX_DP2
UPI3_TX_DP3
UPI3_TX_DP4
UPI3_TX_DP5
UPI3_TX_DP6
UPI3_TX_DP7
UPI3_TX_DP8
UPI3_TX_DP9
UPI3_TX_DP10
UPI3_TX_DP11
UPI3_TX_DP12
UPI3_TX_DP13
UPI3_TX_DP14
UPI3_TX_DP15
UPI3_TX_DP16
UPI3_TX_DP17
UPI3_TX_DP18
UPI3_TX_DP19
UPI3_TX_DP20
UPI3_TX_DP21
UPI3_TX_DP22
UPI3_TX_DP23
UPI3_TX_DN0
UPI3_TX_DN1
UPI3_TX_DN2
UPI3_TX_DN3
UPI3_TX_DN4
UPI3_TX_DN5
UPI3_TX_DN6
UPI3_TX_DN7
UPI3_TX_DN8
UPI3_TX_DN9
UPI3_TX_DN10
UPI3_TX_DN11
UPI3_TX_DN12
UPI3_TX_DN13
UPI3_TX_DN14
UPI3_TX_DN15
UPI3_TX_DN16
UPI3_TX_DN17
UPI3_TX_DN18
UPI3_TX_DN19
UPI3_TX_DN20
UPI3_TX_DN21
UPI3_TX_DN22
UPI3_TX_DN23
UPI3_RX_DP0
UPI3_RX_DP1
UPI3_RX_DP2
UPI3_RX_DP3
UPI3_RX_DP4
UPI3_RX_DP5
UPI3_RX_DP6
UPI3_RX_DP7
UPI3_RX_DP8
UPI3_RX_DP9
UPI3_RX_DP10
UPI3_RX_DP11
UPI3_RX_DP12
UPI3_RX_DP13
UPI3_RX_DP14
UPI3_RX_DP15
UPI3_RX_DP16
UPI3_RX_DP17
UPI3_RX_DP18
UPI3_RX_DP19
UPI3_RX_DP20
UPI3_RX_DP21
UPI3_RX_DP22
UPI3_RX_DP23
UPI3_RX_DN0
UPI3_RX_DN1
UPI3_RX_DN2
UPI3_RX_DN3
UPI3_RX_DN4
UPI3_RX_DN5
UPI3_RX_DN6
UPI3_RX_DN7
UPI3_RX_DN8
UPI3_RX_DN9
UPI3_RX_DN10
UPI3_RX_DN11
UPI3_RX_DN12
UPI3_RX_DN13
UPI3_RX_DN14
UPI3_RX_DN15
UPI3_RX_DN16
UPI3_RX_DN17
UPI3_RX_DN18
UPI3_RX_DN19
UPI3_RX_DN20
UPI3_RX_DN21
UPI3_RX_DN22
UPI3_RX_DN23
SHEETDATE
DEPARTMENT
SIZE
PROJECT DOCUMENT NUMBER REV
REVIEWER
DESIGNER
123
7 3 2 1 6 5 4
E
A
B
C
E
D
C
B
A
7 6 5 4
D
C



67 OF 312N/AFri Aug 25 14:00:48 2023N/AV05N/AN/A
PVCCIN_CPU1 PVCCIN_CPU1PVCCIN_CPU1PVCCIN_CPU1
SPR CPU1 POWER - VCCIN (24 OF 30)
SMLFIOSOCKET4677_AZIF0045-P001C01CSSMLFIOSOCKET4677_AZIF0045-P001C01CS
BW78
BW76
BW74
BW72
BW70
BW68
BW66
BW64
BW62
BW60
BW58
BW56
BW54
BW52
BW50
BW48
BW45
BW43
BW41
BW39
BW37
BW35
BW33
BV89
BV87
BV85
BV83
BV81
BV79
BV77
BV75
BV73
BV71
BV69
BV67
BV65
BV63
BV61
BV59
BV57
BV55
BV53
BV51
BV49
BV47
BV44
BV42
BV40
BV38
BV36
BV34
BV32
BU90
BU88
BU86
BU84
BU82
BU80
BU78
BU76
BU74
BU72
BU70
BU68
BU66
BU64
BU62
BU60
BU58
BU56
BU54
BU52
BU50
BU48
BU45
BU43
BU41
BU39
BU37
BU35
BU33
BT89
BT87
BT85
BT83
BT81
BT79
BT77
BT75
BT73
BT71
BT69
BT67
BT65
BT63
BT61
BT59
BT57
BT55
BT53
BT51
BT49
BT47
BT44
BT42
BT40
BT38
BT36
BT34
BT32
BR78
BR62
BR60
BP89
BP87
BP85
BP83
BP81
BP79
BP61
BP59
BP57
BP55
BP53
BP51
BP49
BP47
BP44
BP42
BP40
BP38
BP36
BP34
BP32
BN90
BN88
BN86
BN84
BN82
BN80
BN78
BN60
BN58
BN56
BN54
BN52
BN50
BN48
BN45
BN43
CM89
CP89
CN90
CN88
CM91
CM87
CL90
CL88
CL86
CL84
CK91
CK89
CK87
CK85
CK83
CJ90
CJ88
CJ86
CJ84
CJ82
CH91
CH81
CG90
CG88
CG86
CG84
CG82
CG80
CF91
CF89
CF87
CF85
CF83
CF81
CF79
CE90
CE88
CE86
CE84
CE82
CE80
CD89
CD87
CD85
CD83
CD81
CD79
CD59
CD57
CD55
CD53
CD51
CD49
CD47
CD44
CD42
CD40
CD38
CD36
CD34
CD32
CC90
CC88
CC86
CC84
CC82
CC80
CC78
CC76
CC60
CC58
CC56
CC54
CC52
CC50
CC48
CC45
CC43
CC41
CC39
CC37
CC35
CC33
CB77
CB75
CB61
CA90
CA88
CA86
CA84
CA82
CA80
CA78
CA76
CA74
CA72
CA70
CA68
CA66
CA64
CA62
CA60
CA58
CA56
CA54
CA52
CA50
CA48
CA45
CA43
CA41
CA39
CA37
CA35
CA33
BY89
BY87
BY85
BY83
BY81
BY79
BY77
BY75
BY73
BY71
BY69
BY67
BY65
BY63
BY61
BY59
BY57
BY55
BY53
BY51
BY49
BY47
BY44
BY42
BY40
BY38
BY36
BY34
BY32
BW90
BW88
BW86
BW84
BW82
BW80
U1U1
27/42
VCCIN40
VCCIN41
VCCIN42
VCCIN43
VCCIN44
VCCIN45
VCCIN46
VCCIN47
VCCIN48
VCCIN49
VCCIN50
VCCIN51
VCCIN52
VCCIN53
VCCIN54
VCCIN55
VCCIN56
VCCIN57
VCCIN58
VCCIN59
VCCIN60
VCCIN61
VCCIN62
VCCIN63
VCCIN64
VCCIN65
VCCIN66
VCCIN67
VCCIN68
VCCIN69
VCCIN70
VCCIN71
VCCIN72
VCCIN73
VCCIN74
VCCIN75
VCCIN76
VCCIN77
VCCIN78
VCCIN79
VCCIN80
VCCIN81
VCCIN82
VCCIN83
VCCIN84
VCCIN85
VCCIN86
VCCIN87
VCCIN88
VCCIN89
VCCIN90
VCCIN91
VCCIN92
VCCIN93
VCCIN94
VCCIN95
VCCIN96
VCCIN97
VCCIN98
VCCIN99
VCCIN100
VCCIN101
VCCIN102
VCCIN103
VCCIN104
VCCIN105
VCCIN106
VCCIN107
VCCIN108
VCCIN109
VCCIN110
VCCIN111
VCCIN112
VCCIN113
VCCIN114
VCCIN115
VCCIN116
VCCIN117
VCCIN118
VCCIN119
VCCIN120
VCCIN121
VCCIN122
VCCIN123
VCCIN124
VCCIN125
VCCIN126
VCCIN127
VCCIN128
VCCIN129
VCCIN130
VCCIN131
VCCIN132
VCCIN133
VCCIN134
VCCIN135
VCCIN136
VCCIN137
VCCIN138
VCCIN139
VCCIN140
VCCIN141
VCCIN142
VCCIN143
VCCIN144
VCCIN145
VCCIN146
VCCIN147
VCCIN148
VCCIN149
VCCIN150
VCCIN151
VCCIN152
VCCIN153
VCCIN154
VCCIN155
VCCIN156
VCCIN157
VCCIN158
VCCIN159
VCCIN160
VCCIN161
VCCIN162
VCCIN163
VCCIN164
VCCIN165
VCCIN166
VCCIN167
VCCIN168
VCCIN169
VCCIN170
VCCIN171
VCCIN172
VCCIN173
VCCIN174
VCCIN175
VCCIN176
VCCIN177
VCCIN178
VCCIN179
VCCIN180
VCCIN181
VCCIN182
VCCIN183
VCCIN184
VCCIN185
VCCIN186
VCCIN187
VCCIN188
VCCIN189
26/42
VCCIN190
VCCIN191
VCCIN192
VCCIN193
VCCIN194
VCCIN195
VCCIN196
VCCIN197
VCCIN198
VCCIN199
VCCIN200
VCCIN201
VCCIN202
VCCIN203
VCCIN204
VCCIN205
VCCIN206
VCCIN207
VCCIN208
VCCIN209
VCCIN210
VCCIN211
VCCIN212
VCCIN213
VCCIN214
VCCIN215
VCCIN216
VCCIN217
VCCIN218
VCCIN219
VCCIN220
VCCIN221
VCCIN222
VCCIN223
VCCIN224
VCCIN225
VCCIN226
VCCIN227
VCCIN228
VCCIN229
VCCIN230
VCCIN231
VCCIN232
VCCIN233
VCCIN234
VCCIN235
VCCIN236
VCCIN237
VCCIN238
VCCIN239
VCCIN240
VCCIN241
VCCIN242
VCCIN243
VCCIN244
VCCIN245
VCCIN246
VCCIN247
VCCIN248
VCCIN249
VCCIN250
VCCIN251
VCCIN252
VCCIN253
VCCIN254
VCCIN255
VCCIN256
VCCIN257
VCCIN258
VCCIN259
VCCIN260
VCCIN261
VCCIN262
VCCIN263
VCCIN264
VCCIN265
VCCIN266
VCCIN267
VCCIN268
VCCIN269
VCCIN270
VCCIN271
VCCIN272
VCCIN273
VCCIN274
VCCIN275
VCCIN276
VCCIN277
VCCIN278
VCCIN279
VCCIN280
VCCIN281
VCCIN282
VCCIN283
VCCIN284
VCCIN285
VCCIN286
VCCIN287
VCCIN288
VCCIN289
VCCIN290
VCCIN291
VCCIN292
VCCIN293
VCCIN294
VCCIN295
VCCIN296
VCCIN297
VCCIN298
VCCIN299
VCCIN300
VCCIN301
VCCIN302
VCCIN303
VCCIN304
VCCIN305
VCCIN306
VCCIN307
VCCIN308
VCCIN309
VCCIN310
VCCIN311
VCCIN312
VCCIN313
VCCIN314
VCCIN315
VCCIN316
VCCIN317
VCCIN318
VCCIN319
VCCIN320
VCCIN321
VCCIN322
VCCIN323
VCCIN324
VCCIN325
VCCIN326
VCCIN327
VCCIN328
VCCIN329
VCCIN330
VCCIN331
VCCIN332
VCCIN333
VCCIN334
VCCIN335
VCCIN336
VCCIN337
VCCIN338
VCCIN339
SHEETDATE
DEPARTMENT
SIZE
PROJECT DOCUMENT NUMBER REV
REVIEWER
DESIGNER
123
7 3 2 1 6 5 4
E
A
B
C
E
D
C
B
A
7 6 5 4
D
C



N/AFri Aug 25 14:00:49 202368 OF 312N/AV05N/AN/A
PVCCIN_CPU1 PVCCINFAON_CPU1 PVCCD_HV_CPU1PVNN_MAIN_CPU1PVPP_HBM_CPU1P3V3_AUXPVCCINFAON_CPU1PVNN_MAIN_CPU1PVCCFA_EHV_CPU1SPR CPU1 POWER - VCCIN/VCCINFAON (25)
SOCKET4677_AZIF0045-P001C01CSIOSMLFSOCKET4677_AZIF0045-P001C01CSIOSMLF
C04026.3VX6S10UF20%
CG68
BA21
BC21
CC68
CD67
CE68
CF67
BN19
BJ19
BE19
BA19
DJ11
DE7
DA7
DA3
CW64
CR66
DJ7
DJ3
DJ15
DE3
DE15
DE11
DA64
DA15
DA11
CY67
CY65
CW66
CV67
CV65
CU7
CU64
CU3
CU15
CU11
CT67
CT65
CP67
CP65
CN7
CN66
CN64
CN3
CN15
CN11
CJ7
CJ3
CJ15
CE15
U3
N3
AW60
AV61
AU60
AT61
AN3
AJ3
AE3
AA3
CY53
CY36
CY34
CW56
CW54
CW52
CW37
CW35
CE7
CA7
BN7
BJ7
BJ3
BJ11
BE7
BE3
BE11
BA7
BA3
AV55
AV53
AV36
AV34
AU7
AU54
AU35
AU3
AT55
AT36
DA21
CW62
CV63
CV61
CT63
CP63
CN19
CJ19
CJ11
CE19
CA15
BN15
BK61
BJ60
BJ15
BG60
BE60
BE15
BC60
BA15
AY18
BN41
BN39
BN37
BN35
BN33
BM91
BM89
BM87
BM85
BM83
BM81
BM79
BL90
BL88
BL86
BL84
BL82
BL80
BK91
BK89
BK87
BK85
BK83
BK81
BH91
BH89
BH87
BH85
BG90
BG88
BG86
BG84
BF91
BF89
BF87
BF85
BE90
BE88
BE86
BD91
U1
U1 29/42
VPP_HBM4
VPP_HBM3
VPP_HBM2
VPP_HBM1
VPP_HBM
VCCVNN0
VCCVNN1
VCCVNN2
VCCVNN3
VCCINFAON0
VCCINFAON1
VCCINFAON2
VCCINFAON3
VCCINFAON4
VCCINFAON5
VCCINFAON6
VCCINFAON7
VCCINFAON8
VCCINFAON9
VCCINFAON10
VCCINFAON11
VCCINFAON12
VCCINFAON13
VCCINFAON14
VCCINFAON15
VCCINFAON16
VCCINFAON17
VCCINFAON18
VCCINFAON19
VCCINFAON20
VCCINFAON21
VCCINFAON22
VCCINFAON23
VCCINFAON24
VCCINFAON25
VCCINFAON26
VCCINFAON27
VCCINFAON28
VCCINFAON29
VCCINFAON30
VCCINFAON31
VCCINFAON32
VCCINFAON54
VCCINFAON55
VCCINFAON56
VCCINFAON57
VCCINFAON58
VCCINFAON59
VCCFA_EHV0
VCCFA_EHV1
VCCFA_EHV2
VCCFA_EHV3
VCCFA_EHV4
VCCFA_EHV5
VCCFA_EHV6
VCCFA_EHV7
VCCFA_EHV9
VCCFA_EHV8
VCCD_HV0
VCCD_HV1
VCCD_HV2
VCCD_HV3
VCCD_HV4
VCCD_HV5
VCCD_HV6
VCCD_HV7
VCCD_HV8
VCCD_HV9
VCCD_HV10
VCCD_HV11
VCCD_HV12
VCCD_HV13
VCCD_HV14
VCCD_HV15
VCCD_HV16
VCCD_HV17
VCCD_HV18
VCCD_HV19
VCCD_HV20
VCCD_HV21
VCCD_HV22
VCCD_HV23
VCCD_HV25
VCCD_HV26
VCCD_HV24
VCCD_HV27
VCCD_HV28
VCC_3P3_AUX1
VCC_3P3_AUX0
28/42
VCCINFAON33
VCCINFAON34
VCCINFAON35
VCCINFAON36
VCCINFAON37
VCCINFAON38
VCCINFAON39
VCCINFAON40
VCCINFAON41
VCCINFAON42
VCCINFAON43
VCCINFAON44
VCCINFAON45
VCCINFAON46
VCCINFAON47
VCCINFAON48
VCCINFAON49
VCCINFAON50
VCCINFAON51
VCCINFAON52
VCCINFAON53
VCCIN0
VCCIN1
VCCIN2
VCCIN3
VCCIN4
VCCIN5
VCCIN6
VCCIN7
VCCIN8
VCCIN9
VCCIN10
VCCIN11
VCCIN12
VCCIN13
VCCIN14
VCCIN15
VCCIN16
VCCIN17
VCCIN18
VCCIN19
VCCIN20
VCCIN21
VCCIN22
VCCIN23
VCCIN24
VCCIN25
VCCIN26
VCCIN27
VCCIN28
VCCIN29
VCCIN30
VCCIN31
VCCIN32
VCCIN33
VCCIN34
VCCIN35
VCCIN36
VCCIN37
VCCIN38
VCCIN39
SHEETDATE
DEPARTMENT
SIZE
PROJECT DOCUMENT NUMBER REV
REVIEWER
DESIGNER
123
7 3 2 1 6 5 4
E
A
B
C
E
D
C
B
A
7 6 5 4
D
C71
C



N/AFri Aug 25 14:00:50 202369 OF 312V05N/AN/AN/A
PVCCFA_EHV_FIVRA_CPU1PVCCFA_EHV_FIVRA_CPU1
SPR CPU1 POWER - VCCFA EHV FIVRA (26)
IOSOCKET4677_AZIF0045-P001C01CSSMLF
Y89
Y85
Y79
W80
U7
U15
U11
T89
T85
R80
P79
N7
N11
M89
M85
L84
K87
J80
J7
J11
H89
EN84
EJ84
EJ15
EG80
EF79
EE84
EE7
EE15
EE11
ED89
ED85
ED79
EC78
EA7
EA3
EA15
EA11
DY89
DY85
DU7
DU3
DU15
DU11
DT89
DT85
DT79
DN7
DN3
DN15
DN11
DM89
DM85
DM83
DH89
DD89
DD85
DD83
DD77
CY89
CY85
CY79
CY75
CT85
CT77
CP73
CN78
CM73
CK79
CK73
CE74
C88
C84
BJ78
BJ72
BH79
BF77
BE72
AY89
AW76
AU15
AT89
AT73
AN80
AN7
AN15
AN11
AM89
AM85
AM79
AJ7
AJ15
AJ11
AH89
AH85
AG78
AF77
AE7
AE15
AE11
AD89
AD85
AA7
AA15
AA11
U1
30/42
VCCFA_EHV_FIVRA0
VCCFA_EHV_FIVRA1
VCCFA_EHV_FIVRA2
VCCFA_EHV_FIVRA3
VCCFA_EHV_FIVRA4
VCCFA_EHV_FIVRA5
VCCFA_EHV_FIVRA6
VCCFA_EHV_FIVRA7
VCCFA_EHV_FIVRA8
VCCFA_EHV_FIVRA9
VCCFA_EHV_FIVRA10
VCCFA_EHV_FIVRA11
VCCFA_EHV_FIVRA12
VCCFA_EHV_FIVRA13
VCCFA_EHV_FIVRA14
VCCFA_EHV_FIVRA15
VCCFA_EHV_FIVRA16
VCCFA_EHV_FIVRA17
VCCFA_EHV_FIVRA18
VCCFA_EHV_FIVRA19
VCCFA_EHV_FIVRA20
VCCFA_EHV_FIVRA21
VCCFA_EHV_FIVRA22
VCCFA_EHV_FIVRA23
VCCFA_EHV_FIVRA24
VCCFA_EHV_FIVRA25
VCCFA_EHV_FIVRA26
VCCFA_EHV_FIVRA27
VCCFA_EHV_FIVRA28
VCCFA_EHV_FIVRA29
VCCFA_EHV_FIVRA30
VCCFA_EHV_FIVRA31
VCCFA_EHV_FIVRA32
VCCFA_EHV_FIVRA33
VCCFA_EHV_FIVRA34
VCCFA_EHV_FIVRA35
VCCFA_EHV_FIVRA36
VCCFA_EHV_FIVRA37
VCCFA_EHV_FIVRA38
VCCFA_EHV_FIVRA39
VCCFA_EHV_FIVRA40
VCCFA_EHV_FIVRA41
VCCFA_EHV_FIVRA42
VCCFA_EHV_FIVRA43
VCCFA_EHV_FIVRA44
VCCFA_EHV_FIVRA45
VCCFA_EHV_FIVRA46
VCCFA_EHV_FIVRA47
VCCFA_EHV_FIVRA48
VCCFA_EHV_FIVRA49
VCCFA_EHV_FIVRA50
VCCFA_EHV_FIVRA51
VCCFA_EHV_FIVRA52
VCCFA_EHV_FIVRA53
VCCFA_EHV_FIVRA54
VCCFA_EHV_FIVRA55
VCCFA_EHV_FIVRA56
VCCFA_EHV_FIVRA57
VCCFA_EHV_FIVRA58
VCCFA_EHV_FIVRA59
VCCFA_EHV_FIVRA60
VCCFA_EHV_FIVRA61
VCCFA_EHV_FIVRA62
VCCFA_EHV_FIVRA63
VCCFA_EHV_FIVRA64
VCCFA_EHV_FIVRA65
VCCFA_EHV_FIVRA66
VCCFA_EHV_FIVRA67
VCCFA_EHV_FIVRA68
VCCFA_EHV_FIVRA69
VCCFA_EHV_FIVRA70
VCCFA_EHV_FIVRA71
VCCFA_EHV_FIVRA72
VCCFA_EHV_FIVRA73
VCCFA_EHV_FIVRA74
VCCFA_EHV_FIVRA75
VCCFA_EHV_FIVRA76
VCCFA_EHV_FIVRA77
VCCFA_EHV_FIVRA78
VCCFA_EHV_FIVRA79
VCCFA_EHV_FIVRA80
VCCFA_EHV_FIVRA81
VCCFA_EHV_FIVRA82
VCCFA_EHV_FIVRA83
VCCFA_EHV_FIVRA84
VCCFA_EHV_FIVRA85
VCCFA_EHV_FIVRA86
VCCFA_EHV_FIVRA87
VCCFA_EHV_FIVRA88
VCCFA_EHV_FIVRA89
VCCFA_EHV_FIVRA90
VCCFA_EHV_FIVRA91
VCCFA_EHV_FIVRA92
VCCFA_EHV_FIVRA93
VCCFA_EHV_FIVRA94
VCCFA_EHV_FIVRA95
VCCFA_EHV_FIVRA96
VCCFA_EHV_FIVRA97
VCCFA_EHV_FIVRA98
VCCFA_EHV_FIVRA99
VCCFA_EHV_FIVRA100
VCCFA_EHV_FIVRA101
VCCFA_EHV_FIVRA102
VCCFA_EHV_FIVRA103
VCCFA_EHV_FIVRA104
SHEETDATE
DEPARTMENT
SIZE
PROJECT DOCUMENT NUMBER REV
REVIEWER
DESIGNER
123
7 3 2 1 6 5 4
E
A
B
C
E
D
C
B
A
7 6 5 4
D
C



70 OF 312V05Fri Aug 25 14:00:51 2023N/AN/AN/AN/ASPR CPU1 POWER - GND (27 OF 30)
SOCKET4677_AZIF0045-P001C01CSIOSMLFSOCKET4677_AZIF0045-P001C01CSIOSMLFSOCKET4677_AZIF0045-P001C01CSIOSMLF
DW9
DW64
DW62
DW58
DW56
DW54
DW52
DW50
DW5
DW48
DW45
DW43
DW41
DW39
DW37
DW35
DW33
DW31
DW29
DW27
DW25
DW23
DW19
DW17
DW13
DW1
DV91
DV87
DV83
DV81
DV8
DV79
DV77
DU88
DU84
DU78
DU76
DU33
DU27
DU21
DT8
DT75
DT71
DT69
DT65
DT57
DT47
DT40
DT38
DT34
DT32
DT28
DT22
DT12
DR9
DR88
DR84
DR78
DR74
DR66
DR56
DR50
DR48
DR43
DR41
DR37
DR31
DR29
DR23
DR19
DR13
DR1
DP87
DP81
DP8
DP73
DP49
DP4
DP36
DP30
DP16
DN88
DN84
DN78
DM8
DM79
DM77
DM75
DM71
DM69
DM67
DM65
DM63
DM61
DM59
DM57
DM55
DM53
DM49
DM47
DM44
DM42
DM40
DM4
DM38
DM36
DM34
DM32
DM30
DM28
DM26
DM24
DM22
DM20
DM18
DM16
DM12
DW60
DW21
DV42
DV4
DV16
DV12
DU70
DU64
DU58
DU52
DU45
DU39
DT83
DT63
DT59
DT53
DT51
DT44
DT4
DT26
DT20
DT16
DR72
DR68
DR62
DR60
DR54
DR5
DR35
DR25
DP91
DP67
DP61
DP55
DP42
DP24
DP18
DP12
DN52
DN39
DN17
DM73
DM51
EH4
EH30
EH24
EH16
EG90
EG9
EG88
EG86
EG84
EG82
EG39
EF87
EF85
EF8
EF77
EF71
EF69
EF67
EF65
EF63
EF61
EF59
EF57
EF55
EF53
EF49
EF47
EF44
EF42
EF40
EF4
EF38
EF36
EF34
EF32
EF30
EF28
EF26
EF24
EF22
EF20
EF2
EF18
EF16
EF12
EE88
EE80
EE78
ED8
ED49
ED4
ED36
ED30
ED24
ED16
EC9
EC88
EC84
EC82
EC74
EC72
EC66
EC56
EC50
EC48
EC43
EC41
EH6
EC37
EC31
EC29
EC23
EC19
EC13
EC1
EB87
EB83
EB8
EH18
EB79
EH14
EH12
EB75
EB71
EB69
EB65
EB57
EB47
EB40
EG7
EB38
EB32
EG52
EG5
EB28
EB22
EB12
EA88
EA84
EG13
EF89
EA80
EA78
EA76
EA70
EA33
EF75
EF73
EA27
EA21
DY8
DY77
DW88
DW84
EF51
DW82
DW80
DW76
DW74
DW72
DW70
DW68
DW66
EE52
EE39
EE17
ED73
ED67
ED61
ED55
ED42
ED18
ED12
EC68
EC62
EC60
EC54
EC5
EC35
EC25
EB91
EB63
EB59
EB53
EB51
EB44
EB4
EB34
EB26
EB20
EB16
EA64
EA58
EA52
EA45
EA39
DY42
DY4
DY16
DY12
ER50
ER48
ER43
ER41
ET57
ET38
ET34
ET28
ET22
ET16
ET10
ER86
ER84
ER80
ER78
ER74
ER70
ER7
ER5
ER33
ER27
EP83
EP67
EN80
EN78
EN64
EN56
EN54
EN52
EN50
EN48
EN45
EN43
EN41
EN37
EN35
EN33
EN31
EN29
EN27
EN25
EN23
EN21
EN19
EN17
EN15
EN13
EN11
EM83
EM81
EM8
EM73
ET59
EM42
ET53
EL76
EL64
EL5
EL45
ET32
EL39
ET26
EL33
ET20
EL3ET14
EL27
ER9
EL21
EK75
EK69
EK65
EK57
EK47
EK40
ER64
ER58
EK4
EK38
ER52
EK34
ER39
EK32
EK28
EK22
EK2
ER21
ER15
EK14
EP77
EP71
EP69
EK10
EJ9
EJ88
EJ78
EJ74
EN9
EN88
EJ7
EJ66
EJ60
EN72
EN66
EJ56
EN62
EN60
EN58
EJ50
EJ48
EJ43
EJ41
EJ37
EJ31
EJ29
EJ23
EN39
EJ19
EJ13
EH83
EH81
EH73
EH49
EH36
EM79
EM49
EL9
EL86
EL72
EL70
EL7
EL58
EL52
EL15
EK89
EK83
EK79
EK77
EK71
EK63
EK59
EK53
EK51
EK44
EK26
EK20
EK16
EJ72
EJ68
EJ62
EJ54
EJ35
EJ25
EJ17
EJ11
EH79
EH67
EH61
EH55
EH42
U1U1U1
33/42
VSS934
VSS945
VSS955
VSS957
VSS959
VSS966
VSS968
VSS969
VSS973
VSS976
VSS979
VSS980
VSS985
VSS990
VSS993
VSS998
VSS1000
VSS1002
VSS1003
VSS1005
VSS1006
VSS1013
VSS1014
VSS1016
VSS1021
VSS1023
VSS1025
VSS1026
VSS1028
VSS1029
VSS1036
VSS1047
VSS1048
VSS1050
VSS1051
VSS1052
VSS1054
VSS1059
VSS1060
VSS1063
VSS1064
VSS1077
VSS1097
VSS1100
VSS1101
VSS1102
VSS1103
VSS1104
VSS1105
VSS1106
VSS1107
VSS1108
VSS1109
VSS1110
VSS1113
VSS1114
VSS1117
VSS1118
VSS1119
VSS1120
VSS1121
VSS1122
VSS1123
VSS1124
VSS1127
VSS1128
VSS1130
VSS1132
VSS1133
VSS1134
VSS1135
VSS1136
VSS1137
VSS1138
VSS1139
VSS1140
VSS1143
VSS1147
VSS1148
VSS1149
VSS1150
VSS1151
VSS1152
VSS1153
VSS1154
VSS1157
VSS1159
VSS1160
VSS1162
VSS1164
VSS1166
VSS1169
VSS1172
VSS1173
VSS1174
VSS1175
VSS1176
VSS1177
VSS1178
VSS1179
VSS1181
VSS1182
VSS1183
VSS1184
VSS1186
VSS1187
VSS1189
VSS1190
VSS1191
VSS1192
VSS1194
VSS1196
VSS1199
VSS1201
VSS1202
VSS1203
VSS1204
VSS1205
VSS1206
VSS1207
VSS1209
VSS1211
VSS1212
VSS1213
VSS1214
VSS1215
VSS1216
VSS1218
VSS1219
VSS1221
VSS1222
VSS1226
VSS1227
VSS1228
VSS1229
VSS1230
VSS1231
VSS1233
VSS1234
VSS1236
VSS1238
VSS1239
VSS1240
VSS1241
VSS1242
VSS1243
VSS1244
VSS1245
VSS1246
VSS1247
VSS1248
VSS1249
VSS1250
VSS1251
VSS1252
VSS1253
VSS1254
VSS1255
VSS1256
VSS1268
32/42
VSS1111
VSS1112
VSS1115
VSS1116
VSS1141
VSS1142
VSS1144
VSS1145
VSS1146
VSS1155
VSS1156
VSS1158
VSS1161
VSS1163
VSS1165
VSS1167
VSS1168
VSS1170
VSS1171
VSS1180
VSS1185
VSS1188
VSS1193
VSS1195
VSS1197
VSS1198
VSS1200
VSS1208
VSS1210
VSS1217
VSS1220
VSS1223
VSS1224
VSS1225
VSS1232
VSS1235
VSS1237
VSS1257
VSS1258
VSS1259
VSS1260
VSS1261
VSS1262
VSS1263
VSS1264
VSS1265
VSS1266
VSS1267
VSS1269
VSS1270
VSS1274
VSS1275
VSS1276
VSS1277
VSS1278
VSS1279
VSS1280
VSS1281
VSS1282
VSS1283
VSS1284
VSS1285
VSS1286
VSS1287
VSS1288
VSS1289
VSS1290
VSS1291
VSS1292
VSS1293
VSS1294
VSS1295
VSS1296
VSS1297
VSS1298
VSS1299
VSS1300
VSS1301
VSS1302
VSS1303
VSS1304
VSS1305
VSS1306
VSS1307
VSS1308
VSS1309
VSS1310
VSS1311
VSS1313
VSS1314
VSS1316
VSS1317
VSS1318
VSS1321
VSS1323
VSS1324
VSS1326
VSS1327
VSS1329
VSS1330
VSS1332
VSS1333
VSS1335
VSS1336
VSS1337
VSS1338
VSS1339
VSS1341
VSS1342
VSS1344
VSS1346
VSS1348
VSS1349
VSS1350
VSS1351
VSS1352
VSS1353
VSS1354
VSS1356
VSS1358
VSS1360
VSS1361
VSS1362
VSS1363
VSS1364
VSS1365
VSS1367
VSS1370
VSS1373
VSS1374
VSS1376
VSS1382
VSS1383
VSS1384
VSS1385
VSS1386
VSS1387
VSS1388
VSS1389
VSS1390
VSS1392
VSS1393
VSS1395
VSS1399
VSS1402
VSS1403
VSS1404
VSS1406
VSS1407
VSS1408
VSS1410
VSS1411
VSS1412
VSS1413
VSS1414
VSS1415
VSS1416
VSS1417
VSS1418
VSS1420
31/42
VSS1312
VSS1315
VSS1319
VSS1320
VSS1322
VSS1325
VSS1328
VSS1331
VSS1334
VSS1340
VSS1343
VSS1345
VSS1347
VSS1355
VSS1357
VSS1359
VSS1366
VSS1368
VSS1369
VSS1371
VSS1372
VSS1375
VSS1377
VSS1378
VSS1379
VSS1380
VSS1381
VSS1391
VSS1394
VSS1396
VSS1397
VSS1398
VSS1400
VSS1401
VSS1405
VSS1409
VSS1419
VSS1421
VSS1422
VSS1423
VSS1424
VSS1425
VSS1426
VSS1427
VSS1428
VSS1429
VSS1430
VSS1431
VSS1432
VSS1433
VSS1434
VSS1435
VSS1436
VSS1437
VSS1438
VSS1439
VSS1440
VSS1441
VSS1442
VSS1443
VSS1444
VSS1445
VSS1446
VSS1447
VSS1448
VSS1449
VSS1450
VSS1451
VSS1452
VSS1453
VSS1454
VSS1455
VSS1456
VSS1457
VSS1458
VSS1459
VSS1460
VSS1461
VSS1462
VSS1463
VSS1464
VSS1465
VSS1466
VSS1467
VSS1468
VSS1469
VSS1470
VSS1471
VSS1472
VSS1473
VSS1474
VSS1475
VSS1476
VSS1477
VSS1478 VSS1479
VSS1480
VSS1481
VSS1482
VSS1483
VSS1484
VSS1485
VSS1486
VSS1488
VSS1489
VSS1491
VSS1492
VSS1493
VSS1496
VSS1497
VSS1498
VSS1499
VSS1500
VSS1501
VSS1503
VSS1505
VSS1506
VSS1512
VSS1513
VSS1515
VSS1517
VSS1518
VSS1520
VSS1522
VSS1524
VSS1525
VSS1526
VSS1528
VSS1529
VSS1530
VSS1531
VSS1533
VSS1537
VSS1539
VSS1540
VSS1541
VSS1542
VSS1543
VSS1545
VSS1547
VSS1548
VSS1549
VSS1550
VSS1551
VSS1552
VSS1553
VSS1554
VSS1555
VSS1556
VSS1557
VSS1559
VSS1561
VSS1562
VSS1563
VSS1565
VSS1569
VSS1837
VSS1836
VSS1835
VSS1834
SHEETDATE
DEPARTMENT
SIZE
PROJECT DOCUMENT NUMBER REV
REVIEWER
DESIGNER
123
7 3 2 1 6 5 4
E
A
B
C
E
D
C
B
A
7 6 5 4
D
C



Fri Aug 25 14:00:52 2023N/AN/AN/AN/AV0571 OF 312SPR CPU1 POWER - GND (28 OF 30)
SOCKET4677_AZIF0045-P001C01CSIOSMLFSOCKET4677_AZIF0045-P001C01CSIOSMLFSOCKET4677_AZIF0045-P001C01CSIOSMLF
CK8
CK26
CK20
CK16
CK12
CJ80
CJ60
CH89
CH87
CH85
CH83
CH8
CH79
CH73
CH67
CH4
CH20
CH16
CH12
CG9
CG78
CG74
CG72
CG70
CG64
CG62
CG5
CG25
CG23
CG21
CG17
CG13
CG1
CF8
CF71
CF69
CF4
CF20
CF16
CF12
CE78
CE76
CE72
CE66
CE60
CE3
CD8
CD77
CD75
CD61
CD4
CD20
CD16
CD12
CC9
CC74
CC72
CC70
CC62
CC5
CC31
CC17
CC13
CB89
CB87
CB85
CB83
CB81
CB8
CB79
CB73
CB71
CB69
CB67
CB65
CB63
CB59
CB57
CB55
CB53
CB51
CB49
CB47
CB44
CB42
CB40
CB4
CB38
CB36
CB34
CB32
CB28
CB26
CB24
CB22
CB20
CB16
CB12
CA31
CA3
BY8
BY4
BY20
BY16
BY12
BW9
BW5
BW31
BW3
BW29
BW27
BW17
BW13
BV8
BV6
BV4
BV20
BV2
BV18
BV16
BV12
BU7
BU31
BU25
BU23
BU21
BU19
BU15
BT8
BT4
BT20
BT16
BT12
BR90
BR88
BR86
BR84
BR82
BR80
BR76
BR74
BR72
BR70
BR68
BR66
BR64
BR58
BR56
BR54
BR52
BR50
BR48
BR45
BR43
BR41
BR39
BR37
BR35
CK4
CJ76
DB87
DB8
DB77
DB71
DB65
DB57
DB47
DB40
DB4
DB38
DB32
DB28
DB22
DB12
DA88
DA84
DA82
DA80
DA74
DA72
DA66
DA62
DA60
DA58
DA56
DA54
DA50
DA48
DA41
DA37
DA35
DA33
DA31
DA29
DA25
DA23
DA19
CY83
CY81
CY8
CY77
CY73
CY63
CY30
CY26
CY18
CY16
CY12
CW9
CW88
CW84
CW78
CW72
CW5
CW17
CW13
CW1
CV91
CV87
CV83
CV8
CV75
CV4
CV12
CU88
CU84
CU68
CU66
CU60
CU23
CU21
CU19
CT81
CT73
CT69
CT12
CT10
CR90
CR9
CR88
CR84
CR64
CR62
CR5
CR17
CR13
CR11
CR1
CP91
CP87
CP83
CP8
CP77
CP75
CP4
CP18
CP12
CN86
CN84
CN74
CN72
CN70
CN68
CM85
CM83
CM81
CM8
CM79
CM67
CM65
CM61
CM4
CM24
CM20
CM12
CL9
CL82
CL80
CL78
CL74
CL62
CL5
CL17
CL13
CL1
CK81
CK69
CK63
DB75
DB69
DB63
DB59
DB53
DB51
DB44
DB34
DB26
DB20
DB16
DA68
DA43
CY4
CW70
CW33
CV79
CV26
CV16
CU78
CU72
CU25
CT89
CT8
CT4
CT16
CR78
CP79
CP16
CN76
CM22
CM16
DL9
DL88
DL84
DL39
DK91
DK87
DK83
DK81
DK8
DK79
DK77
DK73
DK49
DK4
DK36
DK30
DK16
DJ88
DJ84
DJ82
DJ80
DJ74
DJ72
DJ66
DJ60
DJ56
DJ50
DJ48
DJ43
DJ41
DJ37
DJ31
DJ29
DJ23
DJ19
DH85
DH8
DH77
DH71
DH65
DH57
DH47
DH40
DH4
DH38
DH32
DH28
DH22
DH12
DG9
DG88
DG84
DG80
DG76
DG70
DG5
DG45
DG39
DG33
DG27
DF87
DF8
DF79
DF4
DE88
DE84
DE82
DE76
DE74
DE72
DE68
DE66
DE64
DE62
DE60
DE58
DE56
DE54
DE52
DE50
DE48
DE45
DE43
DE41
DE37
DE35
DE33
DE31
DE29
DE27
DE25
DE23
DE21
DE19
DE17
DD8
DD79
DD4
DC9
DC88
DC84
DC80
DC78
DC76
DC70
DC5
DC45
DC39
DC33
DC27
DL52
DL5
DL17
DL13
DL1
DK67
DK61
DK55
DK42
DK24
DK18
DK12
DJ68
DJ62
DJ54
DJ35
DJ25
DH75
DH69
DH63
DH59
DH53
DH51
DH44
DH34
DH26
DH20
DH16
DG64
DG58
DG52
DG21
DG13
DG1
DF91
DF49
DF16
DF12
DE70
DE39
DD49
DD16
DD12
DC64
DC58
DC52
DC21
DC13
DC1
DB91
U1U1U1
36/42
VSS383
VSS396
VSS542
VSS543
VSS545
VSS546
VSS547
VSS548
VSS549
VSS550
VSS551
VSS552
VSS555
VSS556
VSS557
VSS559
VSS560
VSS561
VSS563
VSS564
VSS565
VSS566
VSS567
VSS568
VSS569
VSS570
VSS573
VSS574
VSS575
VSS576
VSS577
VSS578
VSS579
VSS580
VSS581
VSS582
VSS584
VSS585
VSS586
VSS587
VSS588
VSS589
VSS590
VSS591
VSS592
VSS593
VSS594
VSS596
VSS597
VSS598
VSS599
VSS600
VSS601
VSS602
VSS603
VSS604
VSS605
VSS606
VSS607
VSS608
VSS620
VSS621
VSS622
VSS623
VSS624
VSS625
VSS626
VSS627
VSS628
VSS629
VSS630
VSS631
VSS632
VSS633
VSS634
VSS635
VSS636
VSS637
VSS638
VSS639
VSS640
VSS641
VSS642
VSS643
VSS644
VSS645
VSS646
VSS647
VSS648
VSS649
VSS650
VSS651
VSS652
VSS653
VSS654
VSS655
VSS656
VSS660
VSS661
VSS664
VSS665
VSS666
VSS667
VSS668
VSS669
VSS670
VSS671
VSS672
VSS673
VSS674
VSS675
VSS676
VSS677
VSS678
VSS680
VSS681
VSS682
VSS683
VSS684
VSS685
VSS686
VSS687
VSS688
VSS689
VSS691
VSS692
VSS693
VSS694
VSS695
VSS696
VSS697
VSS698
VSS701
VSS703
VSS704
VSS706
VSS707
VSS708
VSS710
VSS713
VSS716
VSS718
VSS720
VSS721
VSS722
VSS727
VSS728
VSS729
VSS730
VSS731
VSS732
VSS733
VSS734
VSS736
VSS737
VSS740
VSS741
VSS742
VSS743
VSS746
35/42
VSS436
VSS438
VSS471
VSS478
VSS493
VSS514
VSS521
VSS526
VSS534
VSS537
VSS544
VSS553
VSS554
VSS558
VSS562
VSS571
VSS583
VSS595
VSS611
VSS679
VSS690
VSS699
VSS700
VSS702
VSS705
VSS709
VSS711
VSS712
VSS714
VSS715
VSS717
VSS719
VSS744
VSS745
VSS749
VSS750
VSS751
VSS752
VSS754
VSS755
VSS756
VSS757
VSS758
VSS759
VSS760
VSS761
VSS762
VSS763
VSS764
VSS765
VSS766
VSS767
VSS768
VSS769
VSS770
VSS771
VSS772
VSS773
VSS774
VSS775
VSS777
VSS778
VSS779
VSS780
VSS781
VSS782
VSS783
VSS784
VSS785
VSS786
VSS787
VSS788
VSS789
VSS790
VSS792
VSS793
VSS794
VSS795
VSS796
VSS797
VSS800
VSS801
VSS803
VSS804
VSS805
VSS810
VSS811
VSS812
VSS813
VSS814
VSS815
VSS816
VSS818
VSS819
VSS822
VSS823
VSS824
VSS825
VSS826
VSS827
VSS828
VSS831
VSS833
VSS834
VSS836
VSS837
VSS838
VSS840
VSS843
VSS846
VSS848
VSS850
VSS851
VSS852
VSS853
VSS854
VSS855
VSS856
VSS858
VSS859
VSS860
VSS862
VSS863
VSS910
VSS911
VSS912
VSS913
VSS914
VSS915
VSS916
VSS917
VSS918
VSS919
VSS920
VSS921
VSS922
VSS923
VSS924
VSS925
VSS926
VSS927
VSS928
VSS929
VSS930
VSS931
VSS932
VSS933
VSS935
VSS936
VSS937
VSS938
VSS939
VSS940
VSS941
VSS942
VSS943
VSS944
VSS946
VSS947
VSS948
34/42
VSS723
VSS724
VSS725
VSS726
VSS735
VSS738
VSS739
VSS747
VSS748
VSS753
VSS776
VSS791
VSS798
VSS799
VSS802
VSS806
VSS807
VSS808
VSS809
VSS817
VSS820
VSS821
VSS829
VSS830
VSS832
VSS835
VSS839
VSS841
VSS842
VSS844
VSS845
VSS847
VSS849
VSS857
VSS861
VSS867
VSS870
VSS872
VSS880
VSS882
VSS883
VSS887
VSS890
VSS893
VSS894
VSS903
VSS904
VSS905
VSS908
VSS909
VSS949
VSS950
VSS951
VSS952
VSS953
VSS954
VSS956
VSS958
VSS960
VSS961
VSS962
VSS963
VSS964
VSS965
VSS967
VSS970
VSS971
VSS972
VSS974
VSS975
VSS977
VSS978
VSS981
VSS982
VSS983
VSS984
VSS986
VSS987
VSS988
VSS989
VSS991
VSS992
VSS994
VSS995
VSS996
VSS997
VSS999
VSS1001
VSS1004
VSS1007
VSS1008
VSS1009
VSS1010
VSS1011
VSS1012
VSS1015
VSS1017
VSS1018
VSS1019
VSS1020
VSS1022
VSS1024
VSS1027
VSS1030
VSS1031
VSS1032
VSS1033
VSS1034
VSS1035
VSS1037
VSS1038
VSS1039
VSS1040
VSS1041
VSS1042
VSS1043
VSS1044
VSS1045
VSS1046
VSS1049
VSS1053
VSS1055
VSS1056
VSS1057
VSS1058
VSS1061
VSS1062
VSS1065
VSS1066
VSS1067
VSS1068
VSS1069
VSS1070
VSS1071
VSS1072
VSS1073
VSS1074
VSS1075
VSS1076
VSS1078
VSS1079
VSS1080
VSS1081
VSS1082
VSS1083
VSS1084
VSS1085
VSS1086
VSS1087
VSS1088
VSS1089
VSS1090
VSS1091
VSS1092
VSS1093
VSS1094
VSS1095
VSS1096
VSS1098
VSS1099
SHEETDATE
DEPARTMENT
SIZE
PROJECT DOCUMENT NUMBER REV
REVIEWER
DESIGNER
123
7 3 2 1 6 5 4
E
A
B
C
E
D
C
B
A
7 6 5 4
D
C



Fri Aug 25 14:00:53 2023N/AN/AN/AN/AV0572 OF 312SPR CPU1 POWER - GND (29 OF 30)
SMLFSOCKET4677_AZIF0045-P001C01CSSOCKET4677_AZIF0045-P001C01CSIOSMLFIOSOCKET4677_AZIF0045-P001C01CSIOSMLF
AJ88
AJ84
AJ78
AJ74
AJ72
AJ68
AJ66
AJ62
AJ60
AJ56
AJ54
AJ50
AJ48
AJ43
AJ41
AJ37
AJ35
AJ31
AJ29
AJ25
AJ23
AJ19
AH83
AH8
AH79
AH77
AH75
AH71
AH69
AH65
AH63
AH59
AH57
AH53
AH51
AH47
AH44
AH40
AH4
AH38
AH34
AH32
AH28
AH26
AH22
AH20
AH16
AH12
AG9
AG88
AG84
AG76
AG70
AG64
AG58
AG52
AG5
AG45
AG39
AG33
AG27
AG21
AG13
AG1
AF91
AF87
AF81
AF8
AF42
AF4
AF16
AF12
AE88
AE84
AE78
AE76
AE74
AE72
AE70
AE68
AE66
AE64
AE62
AE60
AE58
AE56
AE54
AE52
AE50
AE48
AE45
AE43
AE41
AE39
AE37
AE35
AE33
AE31
AE29
AE27
AE25
AE23
AE21
AE19
AE17
AD83
AD8
AD79
AD42
AD4
AD16
AD12
AC9
AC88
AC84
AC76
AC70
AC64
AC58
AC52
AC5
AC45
AC39
AC33
AC27
AC21
AC13
AC1
AB91
AB87
AB83
AB81
AB8
AB79
AB77
AB75
AB71
AB69
AB65
AB63
AB59
AB57
AB53
AB51
AB47
AB44
AB40
AB4
AB38
AB34
AB32
AB28
AB26
AB22
AB20
AB16
AB12
AA88
AA84
AA82
AW9
AW5
AW13
AW1
AV91
AV87
AV8
AV77
AV4
AV16
AV12
AU88
AU84
AU80
AU76
AU74
AU72
AU70
AU48
AU45
AU41
AU39
AU37
AU31
AU27
AT8
AT79
AT77
AT75
AT71
AT69
AT65
AT63
AT59
AT57
AT53
AT51
AT44
AT40
AT4
AT38
AT34
AT32
AT28
AT26
AT22
AT20
AT16
AT12
AR9
AR88
AR84
AR82
AR78
AR74
AR72
AR68
AR66
AR62
AR60
AR56
AR54
AR50
AR5
AR48
AR43
AR41
AR37
AR35
AR31
AR29
AR25
AR23
AR19
AR13
AR1
AP91
AP87
AP83
AP8
AP79
AP73
AP67
AP61
AP55
AP49
AP42
AP4
AP36
AP30
AP24
AP18
AP16
AP12
AN88
AN84
AN52
AM8
AM77
AM75
AM73
AM71
AM69
AM67
AM65
AM63
AM61
AM59
AM57
AM55
AM53
AM51
AM49
AM47
AM44
AM42
AM40
AM4
AM38
AM36
AM34
AM32
AM30
AM28
AM26
AM24
AM22
AM20
AM18
AM16
AM12
AL9
AL88
AL84
AL82
AL80
AL52
AL5
AL17
AL13
AL1
AK91
AK87
AK83
AK81
AK8
AK79
AK73
AK67
AK61
AK55
AK49
AK42
AK4
AK36
AK30
AK24
AK18
AK16
AK12
BR9
BR33
BR31
BR29
BR27
BR17
BR13
BP8
BP77
BP75
BP73
BP71
BP63
BP4
BP20
BP2
BP16
BP12
BN70
BN62
BN31
BM8
BM77
BM73
BM61
BM4
BM26
BM24
BM22
BM20
BM16
BM12
BL9
BL78
BL72
BL70
BL68
BL5
BL17
BL13
BL1
BK8
BK79
BK75
BK71
BK65
BK4
BK20
BK16
BK12
BJ90
BJ88
BJ86
BJ84
BJ82
BJ80
BJ68
BJ62
BH83
BH81
BH8
BH77
BH73
BH67
BH4
BH20
BH16
BH12
BG9
BG70
BG5
BG25
BG23
BG21
BG17
BG13
BG1
BF83
BF8
BF79
BF75
BF73
BF63
BF61
BF4
BF20
BF16
BF12
BE84
BE78
BE76
BE74
BE68
BE66
BE64
BD89
BD85
BD81
BD8
BD4
BD20
BD16
BD12
BC9
BC88
BC86
BC84
BC78
BC76
BC72
BC66
BC62
BC5
BC17
BC13
BC1
BB91
BB87
BB83
BB8
BB79
BB77
BB71
BB69
BB63
BB4
BB26
BB24
BB22
BB20
BB16
BB12
BB10
BA88
BA84
BA74
BA64
BA60
BA17
AY83
AY81
AY8
AY79
AY77
AY71
AY4
AY16
AY12
AW88
AW84
AW82
AW80
AW72
AW68
AW66
AW62
AW25
AW23
AW21
BR5
U1U1U1
39/42
VSS38
VSS39
VSS40
VSS41
VSS42
VSS43
VSS44
VSS45
VSS46
VSS47
VSS48
VSS49
VSS50
VSS51
VSS52
VSS53
VSS54
VSS55
VSS56
VSS57
VSS58
VSS59
VSS60
VSS61
VSS62
VSS63
VSS64
VSS65
VSS66
VSS67
VSS68
VSS69
VSS70
VSS71
VSS72
VSS73
VSS74
VSS75
VSS76
VSS77
VSS78
VSS79
VSS80
VSS81
VSS82
VSS83
VSS84
VSS85
VSS86
VSS87
VSS88
VSS89
VSS90
VSS91
VSS92
VSS93
VSS94
VSS95
VSS96
VSS97
VSS98
VSS99
VSS100
VSS101
VSS102
VSS103
VSS104
VSS105
VSS106
VSS107
VSS108
VSS109
VSS110
VSS111
VSS112
VSS113
VSS114
VSS115
VSS116
VSS117
VSS118
VSS119
VSS120
VSS121
VSS122
VSS123
VSS124
VSS125
VSS126
VSS127
VSS128
VSS129
VSS130
VSS131
VSS132
VSS133
VSS134
VSS135
VSS136
VSS137
VSS138
VSS139
VSS140
VSS141
VSS142
VSS143
VSS144
VSS145
VSS146
VSS147
VSS148
VSS149
VSS150
VSS151
VSS152
VSS153
VSS154
VSS155
VSS156
VSS157
VSS158
VSS159
VSS160
VSS161
VSS162
VSS163
VSS164
VSS165
VSS166
VSS167
VSS168
VSS169
VSS170
VSS171
VSS172
VSS173
VSS174
VSS175
VSS176
VSS177
VSS178
VSS179
VSS180
VSS181
VSS182
VSS183
VSS184
VSS185
VSS186
VSS187
VSS188
VSS189
VSS190
VSS191
VSS192
VSS193
VSS194
VSS195
VSS196
VSS197
38/42
VSS198
VSS199
VSS200
VSS201
VSS202
VSS203
VSS204
VSS205
VSS206
VSS207
VSS208
VSS209
VSS210
VSS211
VSS212
VSS213
VSS214
VSS215
VSS216
VSS217
VSS218
VSS219
VSS220
VSS221
VSS222
VSS223
VSS224
VSS225
VSS226
VSS227
VSS228
VSS229
VSS230
VSS231
VSS232
VSS233
VSS234
VSS235
VSS236
VSS237
VSS238
VSS239
VSS240
VSS241
VSS242
VSS243
VSS244
VSS245
VSS246
VSS247
VSS248
VSS249
VSS250
VSS251
VSS252
VSS253
VSS254
VSS255
VSS256
VSS257
VSS258
VSS259
VSS260
VSS261
VSS262
VSS263
VSS264
VSS265
VSS266
VSS267
VSS268
VSS269
VSS270
VSS271
VSS272
VSS273
VSS274
VSS275
VSS276
VSS277
VSS278
VSS279
VSS280
VSS281
VSS282
VSS283
VSS284
VSS285
VSS286
VSS287
VSS288
VSS289
VSS290
VSS291
VSS292
VSS293
VSS294
VSS295
VSS296
VSS297
VSS298
VSS299
VSS300
VSS301
VSS302
VSS303
VSS304
VSS305
VSS306
VSS307
VSS308
VSS309
VSS310
VSS311
VSS312
VSS313
VSS314
VSS315
VSS316
VSS317
VSS318
VSS319
VSS320
VSS321
VSS322
VSS323
VSS324
VSS325
VSS326
VSS327
VSS328
VSS329
VSS330
VSS331
VSS332
VSS333
VSS334
VSS335
VSS336
VSS337
VSS338
VSS339
VSS340
VSS341
VSS342
VSS343
VSS344
VSS345
VSS346
VSS347
VSS348
VSS349
VSS350
VSS351
VSS352
VSS353
VSS354
VSS355
VSS359
VSS368
37/42
VSS0
VSS356
VSS357
VSS358
VSS360
VSS361
VSS362
VSS363
VSS364
VSS365
VSS366
VSS367
VSS369
VSS370
VSS371
VSS372
VSS373
VSS374
VSS375
VSS376
VSS377
VSS393
VSS394
VSS395
VSS397
VSS398
VSS399
VSS400
VSS401
VSS402
VSS403
VSS404
VSS405
VSS406
VSS407
VSS408
VSS409
VSS410
VSS411
VSS412
VSS413
VSS414
VSS415
VSS416
VSS417
VSS418
VSS419
VSS420
VSS421
VSS422
VSS423
VSS424
VSS425
VSS426
VSS427
VSS428
VSS429
VSS430
VSS431
VSS432
VSS433
VSS434
VSS435
VSS437
VSS439
VSS440
VSS441
VSS442
VSS443
VSS444
VSS445
VSS446
VSS447
VSS448
VSS449
VSS450
VSS451
VSS452
VSS453
VSS454
VSS455
VSS456
VSS457
VSS458
VSS459
VSS460
VSS461
VSS462
VSS463
VSS464
VSS465
VSS466
VSS467
VSS468
VSS469
VSS470
VSS472
VSS473
VSS474
VSS475
VSS476
VSS477
VSS479
VSS480
VSS481
VSS482
VSS483
VSS484
VSS485
VSS486
VSS487
VSS488
VSS489
VSS490
VSS491
VSS492
VSS494
VSS495
VSS496
VSS497
VSS498
VSS499
VSS500
VSS501
VSS502
VSS503
VSS504
VSS505
VSS506
VSS507
VSS508
VSS509
VSS510
VSS511
VSS512
VSS513
VSS515
VSS516
VSS517
VSS518
VSS519
VSS520
VSS522
VSS523
VSS524
VSS525
VSS527
VSS528
VSS529
VSS530
VSS531
VSS532
VSS533
VSS535
VSS536
VSS538
VSS539
VSS540
VSS541
VSS572
SHEETDATE
DEPARTMENT
SIZE
PROJECT DOCUMENT NUMBER REV
REVIEWER
DESIGNER
123
7 3 2 1 6 5 4
E
A
B
C
E
D
C
B
A
7 6 5 4
D
C



Fri Aug 25 14:00:53 2023N/AN/AN/AN/AV0573 OF 312SPR CPU1 POWER - GND (30 OF 30)
IOSOCKET4677_AZIF0045-P001C01CSIOSMLFSOCKET4677_AZIF0045-P001C01CSSMLFSOCKET4677_AZIF0045-P001C01CSIOSMLF
E39
E5
D83
D81
D71
D69
D61
D6
D59
D57
D55
D53
D51
D49
D47
D44
D42
D40
D38
D36
D34
D32
D30
D28
D26
D24
D22
D20
D18
D16
D14
D12
D10
D8
D79
D67
D65
D63
C86
C82
C80
C78
C74
C72
C52
C5
C45
C39
B87
B83
B75
B67
B61
B6
B55
B49
B42
B36
B30
B24
B18
B12
A62
A60
A56
A54
A50
A41
A37
A35
A31
A29
A25
A23
A19
A17
A13
A11
N70
N58
N52
N45
N33
N27
N15
M83
M81
L78
L76
L74
L72
L68
L66
L64
L62
L60
L56
N64
L54
L52
L50
L5
L48
N39
L45
L43
L41
L39
N21
L37
L35
L33
L31
L29
L27
M8
L25
L23
M49
M42
M4
L21
L17
M12
L90
L9
L88
L15
L13
K85
K83
K8
L70
K77
J86
J84
J78
J76
L58
J58
J52
J45
J33
J27
J15
H81
H8
H79
H71
H69
H63
H6
H59
H53
H47
H44
H40
H4
L19
H38
H34
H32
H28
H26
H22
H20
H16
H10
G90
K49
K42
G88
G84
K2
K14
K12
J9
J88
G72
G62
G56
G54
G50
J70
G43
J64
G41
G37
G31
G29
J5
G23
J39
G19
G13
F89
F83
J21
F49
F4
F36
F30
F24
H75
H65
H57
H51
H2
H14
G74
G7
G68
G66
G60
G48
G35
G3
G25
G17
G11
F79
F73
F67
F61
F6
F55
F42
F18
F12
E86
E76
E78
E74
E52
Y73
Y8
Y55
Y49
Y67
Y61
Y42
Y4
Y36
Y30
Y24
Y18
Y16
Y12
W9
W88
W84
W39
W52
W5
V87
V8
V79
V77
W13
W1
V91
V75
V69
V67
V65
V63
V73
V71
V61
V59
V57
V55
V53
V51
V47
V44
V42
V40
V49
V4
V38
V36
V34
V32
V30
V28
V26
V24
V22
V20
V18
V16
V12
U88
U84
U82
U39
T83
T8
T79
T73
U52
T67
T61
T42
T4
T30
T24
R9
R88
R84
R78
R74
R72
R68
R62
R56
T55
T49
R54
R50
T36
R5
R43
R41
R37
T18
T16
T12
R35
R31
R29
R25
R17
R13
P91
P87
R66
P8
R60
P77
P75
P69
P65
R48
P63
P59
P53
P47
P44
P40
P4
R23
R19
P38
P34
R1
P28
P26
P22
P20
P16
P12
P71
N88
N84
N82
N80
P57
N78
P51
N76
P32
AA80
AA78
AA74
AA72
AA68
AA66
AA62
AA60
AA56
AA54
AA50
AA48
AA43
AA41
AA37
AA35
AA31
AA29
AA25
AA23
AA19
U1U1U1
42/42
VSS1
VSS2
VSS3
VSS4
VSS5
VSS6
VSS7
VSS8
VSS9
VSS10
VSS11
VSS12
VSS13
VSS14
VSS15
VSS16
VSS378
VSS379
VSS380
VSS381
VSS382
VSS384
VSS385
VSS386
VSS387
VSS388
VSS389
VSS390
VSS391
VSS392
VSS609
VSS610
VSS612
VSS613
VSS614
VSS615
VSS616
VSS617
VSS618
VSS619
VSS657
VSS658
VSS659
VSS662
VSS663
VSS864
VSS865
VSS866
VSS868
VSS869
VSS871
VSS873
VSS874
VSS875
VSS876
VSS877
VSS878
VSS879
VSS881
VSS884
VSS885
VSS886
VSS888
VSS889
VSS891
VSS892
VSS895
VSS896
VSS897
VSS898
VSS899
VSS900
VSS901
VSS902
VSS906
VSS907
VSS1125
VSS1271
41/42
VSS1126
VSS1129
VSS1131
VSS1272
VSS1273
VSS1494
VSS1495
VSS1502
VSS1504
VSS1507
VSS1508
VSS1509
VSS1510
VSS1511
VSS1514
VSS1516
VSS1519
VSS1521
VSS1523
VSS1527
VSS1532
VSS1534
VSS1535
VSS1536
VSS1538
VSS1544
VSS1546
VSS1558
VSS1560
VSS1564
VSS1567
VSS1570
VSS1571
VSS1572
VSS1573
VSS1574
VSS1575
VSS1576
VSS1577
VSS1578
VSS1579
VSS1580
VSS1581
VSS1582
VSS1583
VSS1584
VSS1585
VSS1586
VSS1587
VSS1588
VSS1589
VSS1590
VSS1591
VSS1592
VSS1593
VSS1594
VSS1595
VSS1596
VSS1597
VSS1598
VSS1599
VSS1600
VSS1601
VSS1602
VSS1603
VSS1604
VSS1605
VSS1606
VSS1607
VSS1608
VSS1609
VSS1610
VSS1611
VSS1612
VSS1613
VSS1614
VSS1615
VSS1616
VSS1617
VSS1618
VSS1619
VSS1620
VSS1621
VSS1622
VSS1623
VSS1624
VSS1625
VSS1626
VSS1627
VSS1628
VSS1629
VSS1630
VSS1631
VSS1632
VSS1633
VSS1634
VSS1635
VSS1636
VSS1637
VSS1638
VSS1639
VSS1640
VSS1641
VSS1642
VSS1643
VSS1644
VSS1645
VSS1646
VSS1647
VSS1648
VSS1649
VSS1650
VSS1651
VSS1652
VSS1653
VSS1654
VSS1655
VSS1656
VSS1657
VSS1658
VSS1659
VSS1660
VSS1661
VSS1662
VSS1663
VSS1664
VSS1665
VSS1666
VSS1667
VSS1668
VSS1669
VSS1670
VSS1671
VSS1672
VSS1673
VSS1674
VSS1675
VSS1676
VSS1677
VSS1678
VSS1679
VSS1680
VSS1681
VSS1682
VSS1683
VSS1684
VSS1685
VSS1686
VSS1687
VSS1688
VSS1689
VSS1691
VSS1692
VSS1693
VSS1694
VSS1695
40/42
VSS17
VSS18
VSS19
VSS20
VSS21
VSS22
VSS23
VSS24
VSS25
VSS26
VSS27
VSS28
VSS29
VSS30
VSS31
VSS32
VSS33
VSS34
VSS35
VSS36
VSS37
VSS1690
VSS1696
VSS1697
VSS1698
VSS1699
VSS1700
VSS1701
VSS1702
VSS1703
VSS1704
VSS1705
VSS1706
VSS1707
VSS1708
VSS1709
VSS1710
VSS1711
VSS1712
VSS1713
VSS1714
VSS1715
VSS1716
VSS1717
VSS1718
VSS1719
VSS1720
VSS1721
VSS1722
VSS1723
VSS1724
VSS1725
VSS1726
VSS1727
VSS1728
VSS1729
VSS1730
VSS1731
VSS1732
VSS1733
VSS1734
VSS1735
VSS1736
VSS1737
VSS1738
VSS1739
VSS1740
VSS1741
VSS1742
VSS1743
VSS1744
VSS1745
VSS1746
VSS1747
VSS1748
VSS1749
VSS1750
VSS1751
VSS1752
VSS1753
VSS1754
VSS1755
VSS1756
VSS1757
VSS1758
VSS1759
VSS1760
VSS1761
VSS1762
VSS1763
VSS1764
VSS1765
VSS1766
VSS1767
VSS1768
VSS1769
VSS1770
VSS1771
VSS1772
VSS1773
VSS1774
VSS1775
VSS1776
VSS1777
VSS1778
VSS1779
VSS1780
VSS1781
VSS1782
VSS1783
VSS1784
VSS1785
VSS1786
VSS1787
VSS1788
VSS1789
VSS1790
VSS1791
VSS1792
VSS1793
VSS1794
VSS1795
VSS1796
VSS1797
VSS1798
VSS1799
VSS1800
VSS1801
VSS1802
VSS1803
VSS1804
VSS1805
VSS1806
VSS1807
VSS1808
VSS1809
VSS1810
VSS1811
VSS1812
VSS1813
VSS1814
VSS1815
VSS1816
VSS1817
VSS1818
VSS1819
VSS1820
VSS1821
VSS1822
VSS1823
VSS1824
VSS1825
VSS1826
VSS1827
VSS1828
VSS1829
VSS1830
VSS1831
VSS1832
VSS1833
SHEETDATE
DEPARTMENT
SIZE
PROJECT DOCUMENT NUMBER REV
REVIEWER
DESIGNER
123
7 3 2 1 6 5 4
E
A
B
C
E
D
C
B
A
7 6 5 4
D
C



PVCCIN: 10 0805 100UF MLCC CAPS ON TOP
PVCCIN: 79 0402 22UF CAPS ON TOP
74 OF 312V05Fri Aug 25 14:00:54 2023N/AN/AN/AN/AX6SPVCCFA_EHV_CPU0PVCCIN_CPU0PVCCIN_CPU0
PVNN_MAIN_CPU0PVCCIN_CPU0PVCCIN_CPU0PVCCIN_CPU0PVCCINFAON_CPU0
PVCCIN_CPU0PVCCIN_CPU0PVCCIN_CPU0PVCCD_HV_CPU0
PVCCIN_CPU0
PVCCFA_EHV_FIVRA_CPU0SPR CPU0 TOP DECOUPLING CAPS22UF6.3V20%22UF4VC0402X6S
4V20%C0402X6S22UF20%22UF4VX6SC04024V22UF20%X6SC04024V20%22UFC0402X6S20%4V22UFC0402X6S20%4V22UFX6SC040220%22UF4VC0402X6S4V22UF20%C0402X6S20%X6S22UF4VC040220%X6S4V22UFC04024V22UFX6S20%C04024V20%22UFX6SC040220%4VX6SC040222UF4V22UF20%C0402X6S22UF4V20%C0402X6S20%4VX6SC040222UF4V20%22UFC0402X6S4V22UF20%C0402X6S4V22UF20%C0402X6S20%22UF4VX6SC040222UF20%4VX6SC040220%4VX6S22UFC040220%22UF4VX6SC040220%4VX6S22UFC040220%4V22UFX6SC040220%22UF4VC0402X6SX6S4V22UF20%C040222UF4VX6S20%C0402X6S20%22UF4VC040222UF4V20%X6SC04024V22UF20%X6SC040220%22UFX6S4VC040222UF4V20%X6SC040222UF20%X6S4VC04024V20%C0402X6S22UF4V20%X6SC0402
4V22UF20%C0402X6S4V20%22UFC0402X6S4V22UF20%C0402X6S4V20%C040222UFX6S20%22UF4VX6S22UF20%4VC0402X6S6.3V10UF20%X6SC04026.3V10UF20%X6S6.3V10UF20%X6SC04026.3V10UF20%C04026.3V20%X6S10UFC040210UF20%20%X6S4V22UFC040222UF4V20%X6SC040220%X6SC040210UF6.3V20%X6SC040210UF6.3V47UF20%4VC0805X6SC040222UF20%4VX6S47UF20%4VC0805X6S20%4V22UFX6SC04024V20%22UFC0402X6S20%4VX6SC040222UF20%4VX6SC040222UF
6.3V10UFX6S20%C04026.3V10UF20%C0402X6S6.3V10UFX6S20%C0402X6S20%6.3V10UFC04026.3V10UFX6S20%C04026.3V10UF20%C0402X6S6.3VX6S10UF20%C04026.3V20%X6SC0402X6S6.3V10UF20%C04026.3V10UFX6S20%C04026.3V10UF20%X6SC04026.3V10UFX6S20%C04026.3V10UF20%X6SC0402X6S6.3V10UF20%C0402X6S6.3V10UF20%C0402C0402X6S20%10UF6.3V20%X6SC040210UF6.3V20%X6SC040210UF47UF20%4VC0805X6S47UF20%4VC080522UF20%4VX6SC040222UF4V20%X6SC0402C080547UF20%4VX6SX6SC040220%10UF6.3VX6S20%C040210UF6.3V47UF4V20%C0805X6S47UF20%4VC0805X6S20%X6S22UF4VC0402
6.3V10UF20%X6SC04026.3V10UF20%X6SC04026.3V10UF20%X6SC04026.3V10UF20%X6SC0402C04026.3V10UF20%X6S6.3V10UF20%C0402X6S6.3V10UF20%X6SC04026.3V10UF20%X6SC0402C04026.3V10UF20%X6S20%6.3VX6SC040210UF20%6.3VX6SC040210UF47UF20%4VC0805X6SC040220%X6S4V22UF47UF20%4VC0805X6S20%X6S22UF4VC040220%6.3VX6SC040210UF47UF20%4VC0805X6S22UFX6S4VC04024V20%22UFC0402X6S22UF4V20%C0402X6S22UF20%4VX6SC040220%4VX6S22UFC040220%4VX6SC040222UF20%4VX6S22UFC04024V20%22UFX6SC04024V20%22UFC0402X6S
C0402X6S6.3VC0402X6SC040210UF20%
C1045C1041C1037
C1030
C1031
C1026C1022
C1027C1023
C1032C1028C1024
C1018
C1033C1029C1025C1021
C1004
C994
C987
C992
C989
C970
C972
C966
C967 C1043
C1044
C1038
C1039
C1034
C1035
C1040C1036
C1019
C1014
C1015
C1020C1016
C1017
C1010
C1011
C1006
C1007
C1012C1008
C1002
C1003
C998
C999
C1000
C1013C1009C1005C1001
C995
C990
C991
C986
C996C988
C982
C983
C978
C979
C984C980
C997C993C985C981
C974
C975C971
C976C968
C977C973C969
C217 C220 C219C218C216C215C214C213C212C101
2
1
2
1
2
1
2
1
2
1
2
1
2
1
2
1
2
1
2
1
2
1
2
1
2
1
2
1
2
1
2
1
2
1
2
1
2
1
2
1
2
1
2
1
2
1
2
1
2
1
2
1
2
1
2
1
2
1
2
1
2
1
2
1
2
1
2
1
2
1
2
1
2
1
2
1
2
1
2
1
2
1
2
1
2
1
2
1
2
1
2
1
2
1
2
1
2
1
2
1
2
1
2
1
2
1
2
1
2
1
2
1
2
1
2
1
2
1
2
1
2
1
2
1
2
1
2
1
2
1
2
1
2
1
2
1
2
1
2
1
2
1
2
1
2
1
2
1
2
1
2
1
2
1
2
1
2
1
2
1
2
1
2
1
2
1
2
1
2
1
2
1
2
1
2
1
2
1
2
1
2
1
2
1
2
1
2
1
2
1
2
1
2
1
2
1
2
1
2
1
2
1
2
1
2
1
2
1
2
1
2
1
2
1
2
1
2
1
2
1
2
1
2
1
2
1
2
1
SHEETDATE
DEPARTMENT
SIZE
PROJECT DOCUMENT NUMBER REV
REVIEWER
DESIGNER
123
7 3 2 1 6 5 4
E
A
B
C
E
D
C
B
A
7 6 5 4
D
C422C420C405C399
C406C404C402C400
C408 C421
C590
C419C416C414
C418C417C415
C412C410C403C401
C413C411C409C407
C



PVCCD_HV: 2 100UF CAP & 1 47UF CAP ARE PLACED AT CAVITY(LEFT)PVCCD_HV: 2 100UF CAPS ARE PLACED AT CAVITY(RIGHT)
PVCCIN: 13 0805 100UF CAPS PLACED AT CAVITY(LEFT)PVCCFA_EHV: 2 100UF CAPS PLACED AT CAVITY(LEFT)PVCCD_HV: 1 100UF CAP & 1 47UF CAP ARE PLACED AT CAVITY(RIGHT)PVCCD_HV: 1 100UF CAP & 1 47UF CAP ARE PLACED AT CAVITY(LEFT)PVCCIN: 12 0805 100UF CAPS PLACED AT CAVITY(RIGHT)PVNN_MAIN: 4 CAPS PLACED AT CAVITY(LEFT)PVNN_MAIN: 4 CAPS PLACED AT CAVITY(RIGHT)PVCCIN: 1 0805 47UF CAPS PLACED AT CAVITY(RIGHT)PVCCIN: 1 0805 47UF CAPS PLACED AT CAVITY(LEFT)
N/AFri Aug 25 14:00:55 202375 OF 312V05N/AN/AN/APVCCINFAON_CPU0PVCCFA_EHV_CPU0PVCCFA_EHV_FIVRA_CPU0PVCCD_HV_CPU0PVCCIN_CPU0PVCCIN_CPU0
PVPP_HBM_CPU0PVNN_MAIN_CPU0PVCCIN_CPU0
SPR CPU0 BOTTOM DECOUPLING CAPSC0805X6SC020110%C0805X6S20%20%47UFX6S47UFC080520%4VX6S47UFC080520%4V47UF4VX6S47UFC080520%4VX6S20%47UF2.5VC060347UF4VX6S20%C080520%X6S4V47UFC0805X6SC080520%4V47UFC0603X6S2.5V20%X6S4V47UFC080547UFC0603X6S2.5V20%X6SC080520%4V47UFX6SC080520%4V47UFX6SC080520%4V47UFX6SC080520%4V47UFX6SC080520%4V47UFX6SC080520%4V47UFX6SC080520%4V47UFX6SC080520%4V47UF
C040222UF4VX6S20%X6SC080547UF4V20%X6SC080520%4V47UFX6SC080520%4V47UFX6SC080520%4V47UFX6SC080520%4V47UFX6SC080520%4V47UFX6SC080520%4V47UFX6S20%4V47UFC0805X6SC080520%4V47UFX6SC080520%4V47UFX6SC080520%4V47UF
X6S4V47UFC080520%X6SC080520%4V47UF20%X6S4V47UFC0805X6SC060320%2.5V47UFX6SC080520%4V47UFX6SC08054V47UF20%X6SC080520%4V47UFX6SC080520%4V47UFX6SC080520%4V47UFX6SC080547UF20%4VX6SC080520%4V47UFX6SC080520%4V47UF
20%4V47UF6.3VX6S0.22UFX6SC060320%2.5V47UFX6SC060320%47UF2.5VX6SC080520%4V47UFX6S47UFC08054V20%47UFX6SC08054V20%
C527C363
C357C397
C381C387C385C382
C389
C395
C376C373C370
C371
C367C364
C365
C355
C356 C393
C379
C391C368
C361C358
C362C359
2
1
2
1
2
1
2
1
2
1
2
1
2
1
2
1
2
1
2
1
2
1
2
1
2
1
2
1
2
1
2
1
2
1
2
1
2
1
2
1
2
1
2
1
2
1
2
1
2
1
2
1
2
1
2
1
2
1
2
1
2
1
2
1
2
1
2
1
2
1
2
1C360
2
1
2
1
2
1
2
1
2
1
2
1
2
1
2
1
2
1
2
1
2
1
2
1
2
1
2
1
SHEETDATE
DEPARTMENT
SIZE
PROJECT DOCUMENT NUMBER REV
REVIEWER
DESIGNER
123
7 3 2 1 6 5 4
E
A
B
C
E
D
C
B
A
7 6 5 4
D
C1407C1406
C1436C1398
C1405
C518
C534
C515C495
C533
C496
C491
C492
C522
C509C505
C1397C1396C532
C501C497C493
C



PVCCD_HV: 4 MLCC CAPS PLACED AT CPU(UP>PVCCIN: 14 0805 100UF MLCC CAPS PLACED AT CPU(DOWN>
PVCCINFAON: 4 MLCC CAPS PLACED AT CPU(UP>PVCCFA_EHV: 6 0805 100UF MLCC CAPS PLACED AT CPU(LEFT>PVCCFA_EHV: 6 0805 100UF MLCC CAPS PLACED AT CPU(RIGHT>PVCCFA_EHV: 6 MLCC CAPS PLACED AT CPU(UP>
N/AFri Aug 25 14:00:56 2023N/AV05N/AN/A76 OF 312
PVCCFA_EHV_CPU0PVCCFA_EHV_FIVRA_CPU0PVCCINFAON_CPU0PVNN_MAIN_CPU0PVCCD_HV_CPU0PVCCIN_CPU0
SPR CPU0 BOTTOM DECOUPLING CAPS CONTI.
47UF20%47UFX6S47UFC08054V20%X6S47UFC08054V20%X6S47UFC08054V20%47UFC08054V20%X6S X6S47UFC08054V20%X6S4VC0805X6SC08054V20%47UFX6SC08054V20%47UFX6SC08054V20%X6S47UFC08054V20%X6S47UFC08054V20%22UFC04024VX6S20%X6SC08054V20%47UFX6SC08054V20%47UFX6SC08054V20%47UFX6S47UFC08054V20%X6S47UFC08054V20%X6S47UFC08054V20%
X6S47UFC08054V20%X6S47UFC08054V20%X6S47UFC08054V20%X6S47UFC08054V20%47UFC08054V20%X6SX6SC08054V20%47UF 47UF2.5VC0603X6S20%47UFC0603X6S2.5V20%X6S47UFC08054V20%X6S47UFC08054V20%X6S47UFC08054V20%X6S47UFC08054V20%X6S47UFC08054V20%
X6SC08054V20%47UFX6S47UFC08054V20%X6S47UFC08054V20%X6S47UFC08054V20%X6S47UFC08054V20%X6S47UFC08054V20%X6S47UFC08054V20%X6S47UFC08054V20%X6S47UFC08054V20%X6S47UFC08054V20%X6S47UFC08054V20%X6S47UFC08054V20%
C383C380C377C374C372C369C366C394C392C390C388C386 C398 C396
2
1
2
1
2
1
2
1
2
1
2
1
2
1
2
1
2
1
2
1
2
1
2
1
2
1
2
1
2
1
2
1
2
1
2
1
2
1
2
1
2
1
2
1
2
1C1362
2
1
2
1
2
1
2
1
2
1
2
1
2
1
2
1
2
1
2
1
2
1
2
1
2
1
2
1
2
1
2
1
2
1
2
1
2
1
2
1
SHEETDATE
DEPARTMENT
SIZE
PROJECT DOCUMENT NUMBER REV
REVIEWER
DESIGNER
123
7 3 2 1 6 5 4
E
A
B
C
E
D
C
B
A
7 6 5 4
D
C511
C526C523C521C520
C519C516C512
C506
C507
C1400
C508C504C500
C525
C502C498 C529
C531
C517C514C510
C503C499
C1399
C530C528
C494
C



PVCCIN: 10 0805 100UF MLCC CAPS ON TOPFri Aug 25 14:00:57 202377 OF 312N/A V05N/AN/AN/AX6SPVCCFA_EHV_FIVRA_CPU1PVCCD_HV_CPU1PVCCIN_CPU1PVCCIN_CPU1PVCCIN_CPU1PVCCIN_CPU1PVCCIN_CPU1
PVCCINFAON_CPU1PVCCFA_EHV_CPU1PVNN_MAIN_CPU1PVCCIN_CPU1PVCCIN_CPU1PVCCIN_CPU1PVCCIN_CPU1
SPR CPU1 TOP DECOUPLING CAPSC0402X6S4V22UFC0402C04026.3V10UF20%C0402X6S22UF20%4VX6SC040222UF20%4VC040222UFX6S4V20%22UFC0402X6S4V20%22UFX6SC04024V20%22UFX6SC04024VX6S47UFC080520%4VX6S47UFC08054V20%20%X6SC040210UF6.3VC0402X6S20%10UF6.3VX6SC040222UF20%4VX6S47UFC080520%4VX6S22UFC040220%4V47UFX6SC080520%4VC0402X6S20%10UF6.3V20%X6SC04026.3V10UFX6SC040220%6.3VX6SC040210UF20%X6SC040220%10UF6.3VX6SC040220%10UF6.3VX6SC040210UF20%6.3VX6SC040210UF20%6.3VC0402X6S20%6.3V10UF 10UFX6S6.3V20%C0402X6SC040220%10UF6.3VX6SC040210UF20%6.3VC0402X6S6.3V10UF20%10UFX6SC04026.3V20%
X6S22UFC040220%4VX6SC040222UF4V20%C0402X6S22UF20%4VX6SC040222UF20%4V47UFX6SC08054V20%C0402X6S4V22UF20%47UFX6SC08054V20%X6S20%C04026.3V10UF20%X6SC04026.3V10UFC0402X6S4V22UF20%47UFC08054V20%X6SC040220%22UF4VX6S47UFC080520%4VC040220%X6S6.3V10UFC0402X6S20%10UF6.3VX6S22UF20%4VC0402X6S22UFC04024V20%22UFC0402X6S20%4VC0402X6S22UF4V20%X6S47UFC080520%4VC04024V22UF20%X6S47UFX6SC080520%4V20%X6S10UF6.3VC040220%X6S10UF6.3V22UFX6SC040220%4VX6SC040220%4V22UF20%X6S22UF4VC040222UFX6S4V20%C040222UFX6S4V20%10UFC0402X6S6.3V20%10UFC0402X6S6.3V20%C0402X6S6.3V10UF20%10UFC0402X6S6.3V20%X6SC04026.3V10UF20%10UFC0402X6S6.3V20%10UFC0402X6S6.3V20%X6SC040210UF20%6.3VX6SC04026.3V10UF20%10UFC0402X6S6.3V20%C0402X6S20%10UF6.3VX6SC040210UF20%6.3VX6SC040210UF20%6.3VX6SC040210UF20%6.3V20%22UFX6SC04024VX6SC040220%10UF6.3VX6SC040220%10UF6.3VX6SC040210UF20%6.3VX6SC040210UF20%6.3VX6SC040222UF4V20%22UFX6SC040220%4V22UFC0402X6S20%4VC040222UF20%X6S4VX6SC040222UF4V20%22UFX6SC040220%4VC0402X6S20%22UF4VC040222UFX6S20%4V
X6SC040220%4V22UF20%22UFX6SC040220%4VC040222UFX6S4V20%C0402X6S20%4V22UFX6SC040222UF20%4VC040222UFX6S4V20%C040222UFX6S4V20%C040222UFX6S4V20%20%22UFX6SC04024V20%22UFX6SC04024VC0402X6S4V22UF20%22UFX6SC040220%4VC0402X6S22UF4V20%22UFX6SC04024V20%22UF20%X6SC04024V22UF20%X6SC04024VX6SC040220%22UF4VX6S22UFC04024V20%C0402X6S20%22UF4V22UFX6SC040220%4V22UFX6SC040220%4VX6SC040220%22UF4V22UF20%X6SC04024V22UF20%X6SC04024V22UFC0402X6S20%4VX6SC040220%4V22UF22UFX6SC040220%4VX6SC040222UF4V20%22UFX6SC040220%4V
C307C303C291
C292
C287C266
C267
C273
C256
C252
C253
C241
C243
C310
C269
C227
C235
C229
C308C304
C309C305C301
C300
C299C295
C296
C297C293
C288
C283
C284
C289C285
C306C302C298C294C290C286
C279
C280
C275
C276
C281C277
C271
C272
C261
C262
C268C263
C257
C251
C258
C246
C247C242
C248
C282C278C274C264
C270C265
C259C254
C260C255
C249C244
C250C245
C236
C237
C231
C232
C238C233
C226C221
C222
C228C223
C239C234
C240
C224
C230C225
2
1
2
1
2
1
2
1
2
1
2
1
2
1
2
1
2
1
2
1
2
1
2
1
2
1
2
1
2
1
2
1
2
1
2
1
2
1
2
1
2
1
2
1
2
1
2
1
2
1
2
1
2
1
2
1
2
1
2
1
2
1
2
1
2
1
2
1
2
1
2
1
2
1
2
1
2
1
2
1
2
1
2
1
2
1
2
1
2
1
2
1
2
1
2
1
2
1
2
1
2
1
2
1
2
1
2
1
2
1
2
1
2
1
2
1
2
1
2
1
2
1
2
1
2
1
2
1
2
1
2
1
2
1
2
1
2
1
2
1
2
1
2
1
2
1
2
1
2
1
2
1
2
1
2
1
2
1
2
1
2
1
2
1
2
1
2
1
2
1
2
1
2
1
2
1
2
1
2
1
2
1
2
1
2
1
2
1
2
1
2
1
2
1
2
1
2
1
2
1
2
1
2
1
2
1
2
1
2
1
2
1
2
1
2
1
2
1
2
1
2
1
2
1
2
1
2
1
SHEETDATE
DEPARTMENT
SIZE
PROJECT DOCUMENT NUMBER REV
REVIEWER
DESIGNER
123
7 3 2 1 6 5 4
E
A
B
C
E
D
C
B
A
7 6 5 4
D
C443
C437C426
C446C445C444C440C438
C442C441C439
C436C434C432
C435C433C431
C429C427C425C423
C430C428C424
C



PVNNINFAON: 4 CAPS PLACED AT CAVITY(LEFT)PVCCIN: 12 0805 100UF CAPS PLACED AT CAVITY(RIGHT)PVCCD_HV: 1 100UF CAP & 1 47UF CAP ARE PLACED AT CAVITY(LEFT)PVCCD_HV: 1 100UF CAP & 1 47UF CAP ARE PLACED AT CAVITY(RIGHT)PVCCIN: 13 0805 100UF CAPS PLACED AT CAVITY(LEFT)PVNN_MAIN: 4 CAPS PLACED AT CAVITY(RIGHT)PVCCIN: 1 0805 47UF CAPS PLACED AT CAVITY(RIGHT)PVCCIN: 1 0805 47UF CAPS PLACED AT CAVITY(LEFT)
PVCCFA_EHV_FIVRA: 2 100UF CAP & 1 47UF CAP ARE PLACED AT CAVITY(LEFT)PVCCFA_EHV_FIVRA: 2 100UF CAPS ARE PLACED AT CAVITY(RIGHT)PVCCFA_EHV: 2 100UF CAPS PLACED AT CAVITY(LEFT)
N/AFri Aug 25 14:00:58 2023N/AN/AN/AV0578 OF 312
PVCCFA_EHV_CPU1PVCCFA_EHV_FIVRA_CPU1PVCCINFAON_CPU1PVCCD_HV_CPU1PVCCIN_CPU1PVCCIN_CPU1
PVPP_HBM_CPU1PVNN_MAIN_CPU1PVCCIN_CPU1
SPR CPU1 BOTTOM DECOUPLING CAPSC080520%C080520%4VC0805X6S47UFC08054V20%X6S47UFC08054V20%X6S47UFC08054V20%X6S47UF 47UFC06032.5VX6S20%4VX6S20%47UFC0805X6S47UFC08054V20%X6S47UF4V20%X6SC08054V20%47UFX6S47UFC08054V20%
47UFC0603X6S2.5V20%47UFC0603X6S2.5V20%X6S47UFC08054V20%C04024VX6S20%22UFX6S47UFC08054V20%X6S47UFC08054V20%X6SC08054V20%47UFX6SC08054V20%47UFX6S47UFC08054V20%X6SC08054V20%47UFX6SC08054V20%47UFX6SC08054V20%47UFX6SC08054V20%47UFX6SC08054V47UF20%X6SC08054V20%47UFX6SC08054V20%47UFX6S47UFC08054V20%X6S47UFC08054V20%X6S47UFC08054V20%X6S47UFC08054V20%X6S47UFC08054V20%X6S47UFC08054V20%X6S47UFC08054V20%X6S47UFC08054V20%X6S47UFC08054V20%
4VX6S47UFC08054VX6S20%47UF4VX6S20%47UFC080547UF2.5VC0603X6S20%C06032.5V47UFX6S20%4VX6S20%47UFC08056.3V10%C02010.22UFX6SC06032.5V47UFX6S20%X6SC080520%47UF4VX6SC08054V47UF20%X6S47UFC08054V20%X6S47UFC08054V20%X6S47UFC08054V20%X6S20%C08054V47UF20%X6SC080547UF4V
C351C349C338C335C332C329C317
C339C333C330C324C321C315
C311
C312
C353
C316C313
C326C323C320C314
C336C327C318
2
1
2
1
2
1
2
1
2
1
2
1
2
1
2
1
2
1
2
1
2
1
2
1
2
1
2
1
2
1
2
1
2
1
2
1
2
1
2
1
2
1
2
1
2
1
2
1
2
1
2
1
2
1
2
1
2
1
2
1
2
1
2
1C483
2
1C337
2
1
2
1
2
1
2
1
2
1
2
1
2
1
2
1
2
1
2
1
2
1
2
1
2
1
2
1
2
1
2
1
2
1
SHEETDATE
DEPARTMENT
SIZE
PROJECT DOCUMENT NUMBER REV
REVIEWER
DESIGNER
123
7 3 2 1 6 5 4
E
A
B
C
E
D
C
B
A
7 6 5 4
D
C1393
C1437C1392
C1389C1387
C1390C1388
C471
C452
C489C488
C447
C448
C478
C457C449
C1391
C474C451
C490
C465C461C453
C



PVCCINFAON: 4 MLCC CAPS PLACED AT CPU(UP>PVCCD_HV: 4 MLCC CAPS PLACED AT CPU(UP>PVCCIN: 14 0805 100UF MLCC CAPS PLACED AT CPU(DOWN>
PVCCFA_EHV: 6 0805 100UF MLCC CAPS PLACED AT CPU(RIGHT>PVCCFA_EHV: 6 0805 100UF MLCC CAPS PLACED AT CPU(LEFT>PVCCFA_EHV: 6 MLCC CAPS PLACED AT CPU(UP>
N/AFri Aug 25 14:00:59 2023N/AN/AN/AV0579 OF 312PVCCFA_EHV_FIVRA_CPU1PVCCINFAON_CPU1PVCCFA_EHV_CPU1PVCCD_HV_CPU1PVCCIN_CPU1PVNN_MAIN_CPU1
SPR CPU1 BOTTOM DECOUPLING CAPS CONTI.X6SX6S47UFX6SC080520%4V47UFX6SC080520%4VX6S47UFC080520%4V47UFX6SC080520%4V47UFX6SC080520%4V47UFX6SC080520%4V47UFX6SC080520%4V47UFX6SC080520%4V47UFC080520%4V47UFX6SC08054V20%47UFX6SC080520%4V47UFX6SC08054V20%47UFC080520%4V47UFX6SC080520%4V47UFX6SC080520%4V47UFX6SC080520%4V47UFX6SC080520%4V47UFX6SC080520%4V47UFX6SC080520%4V47UFX6SC080520%4V47UF20%X6S4VC0805X6SC060320%2.5V47UFX6SC060320%47UF2.5V47UFX6SC080520%4V47UFX6SC080520%4V47UFX6SC080520%4V47UFX6SC080520%4V47UFX6SC080520%4V
47UFX6SC080520%4V47UFX6SC080520%4V47UFX6SC080520%4V47UFX6SC080520%4V47UFX6SC080520%4V
C080547UF20%X6S4VC080547UF20%X6S4V47UFX6SC080520%4V47UFX6SC080520%4V20%X6S4V22UFC040247UFX6SC080520%4V47UFX6SC080520%4V47UFX6SC080520%4V47UFX6SC080520%4V47UFX6SC080520%4V
C347C345C343C341C328C325C322C354C352C350C348C346C344C342
2
1
2
1
2
1
2
1
2
1
2
1C1353
2
1
2
1
2
1
2
1
2
1
2
1
2
1
2
1
2
1
2
1
2
1
2
1
2
1
2
1
2
1
2
1
2
1
2
1
2
1
2
1
2
1
2
1
2
1
2
1
2
1
2
1
2
1
2
1
2
1
2
1
2
1
2
1
2
1
2
1
2
1
2
1
2
1
SHEETDATE
DEPARTMENT
SIZE
PROJECT DOCUMENT NUMBER REV
REVIEWER
DESIGNER
123
7 3 2 1 6 5 4
E
A
B
C
E
D
C
B
A
7 6 5 4
D
C1404C1403
C485C482C479C477C476
C467
C475C472C468
C463C459C455
C464C460C456
C481 C484 C486 C487
C473C470C466C462C458C454C450
C



80 OF 312V05N/AN/AN/AN/AFri Aug 25 14:00:59 2023P3V3_AUXPVNN_MAIN_CPU0PVNN_MAIN_CPU0PVCCINFAON_CPU0P3V3_AUXPVNN_MAIN_CPU1PVNN_TERM_CPU0 PVNN_MAIN_CPU1PVCCINFAON_CPU1PVNN_TERM_CPU1
SPR CPU0 & 1 - PVNN_TERM & MISC1515151521346213464646FM_S3M_CPU0_CPLD_CONFIG_NPU_S3M_CPU0_CPLD_CONFDPU_S3M_CPU0_CPLD_STATUSFM_S3M_CPU0_CPLD_CRC_ERROR FM_S3M_CPU1_CPLD_CRC_ERRORFM_S3M_CPU1_CPLD_CONFIG_NPU_S3M_CPU1_CPLD_CONFDPU_S3M_CPU1_CPLD_STATUS1/16WCHIP1.5K1%0402LFCHIP10K1%C040222UFX6S20%4VCHIP10K1%CHIP1/16W0402LF10K1%X6S22UF20%C04024V1/2W0CHIP1206LFEMPTY1/2W01206LF20%X6S22UFC04024V1.5K1%1/16WCHIP0402LFCHIP1%10K10KCHIP1%CHIP1/16W0402LF10K1%22UFC040220%X6S4V1206LF1/2WCHIP0EMPTY1/2W01206LF
21R329
21R330
21R325
21R326
21R327
21R1217
21R323
21R324
21R320
2
1C1363
21R321
21R1216
2
1C1366
2
1C1365
2
1C1364
21R319
SHEETDATE
DEPARTMENT
SIZE
PROJECT DOCUMENT NUMBER REV
REVIEWER
DESIGNER
123
7 3 2 1 6 5 4
E
A
B
C
E
D
C
B
A
7 6 5 4
D
OUT
OUT
OUT
OUT
OUT
OUT
OUT
OUT
C



THIS PAGE WAS INTENTIONALLY LEFT BLANK
Thu Aug 24 16:13:00 2023N/AN/AN/AN/AV0581 OF 312BLANK
SHEETDATE
DEPARTMENT
SIZE
PROJECT DOCUMENT NUMBER REV
REVIEWER
DESIGNER
123
7 3 2 1 6 5 4
E
A
B
C
E
D
C
B
A
7 6 5 4
D
C



20210728 MODIFY FOR GT
Fri Aug 25 14:01:00 202382 OF 312V05N/AN/AN/AN/A
P12V_S3_AUX_CPU0_NVDIMM
P12V_S3_AUX_CPU0_NVDIMMP3V3_AUXP3V3_AUX
DDR5 - CPU0 CHA DIMM1(YELLOW)
1298384852083822298384858687888922983848586878889114822020202020202083208320832083208320 8320 8320 8320 8320 8320 8320202083RST_M_AB_CPU0_FPGA_NM_A_CPU0_ALERT_NPD_CHA_CPU0_DIMM1_SAAI3C_SPD_DDRABCD_CPU0_LVC1_SDAI3C_SPD_DDRABCD_CPU0_LVC1_SCL_R1I3C_SPD_DDRABCD_CPU0_LVC1_SCLPWRGD_CHA_CPU0_DIMM1
SCONN288_ADR50017-P130CCIOSMLFSMLFSCONN288_ADR50017-P130CCSMLF
BOM NOTE: 2ND SOURCE IS DFHST8FS385 (@BLUE)PLACE THE BYPASS CAPS CLOSE TO DIMM1%CHIP49.90402LF10K1%CHIP1/16W
IOSCONN288_ADR50017-P130CC
20%2.2UFC04026.3VX6S16V10UF10%C0805X6S
IO
10%10UF16VC0805X6SPD_CHA_CPU0_DIMM1_SAATP_CHA_CPU0_DIMM1_FRU_0TP_CHA_CPU0_DIMM1_FRU_1TP_CHA_CPU0_DIMM1_FRU_2TP_CHA_CPU0_DIMM1_FRU_3TP_CHA_CPU0_DIMM1_FRU_4TP_CHA_CPU0_DIMM1_FRU_5TP_CHA_CPU0_DIMM1_FRU_6M_A_CPU0_SB_RSP<0>M_A_CPU0_SA_RSP<0>M_A_CPU0_CLK_DN<0>M_A_CPU0_SA_CS_N<0>M_A_CPU0_SB_CS_N<0>M_A_CPU0_SA_CS_N<1>M_A_CPU0_SB_PARM_A_CPU0_SA_PARM_A_CPU0_SA_CB<7:0>M_A_CPU0_SB_CA<6:0>M_A_CPU0_SA_CA<6:0>M_A_CPU0_SB_DQ<31:0>M_A_CPU0_SB_DQS_DN<9:0>M_A_CPU0_SB_DQS_DP<9:0>M_A_CPU0_SA_DQ<31:0>M_A_CPU0_SA_DQS_DN<9:0>M_A_CPU0_SA_DQS_DP<9:0>M_A_CPU0_CLK_DP<0>M_A_CPU0_SB_CS_N<1>M_A_CPU0_SB_CB<7:0>
DQS7_A_c||TDQS7_A_c
DQS6_A_t||TDQS6_A_t
DQS8_B_t||TDQS8_B_t
DQS8_B_c||TDQS8_B_c
DQS7_B_t||TDQS7_B_t
DQS0_A_c
DQS0_A_t
DQS0_B_c
DQS0_B_t
DQS1_A_c
DQS1_A_t
DQS1_B_c
DQS1_B_t
DQS2_A_c
DQS2_A_t
DQS2_B_c
DQS2_B_t
DQS3_A_c
DQS3_A_t
DQS3_B_c
DQS3_B_t
DQS4_A_c
DQS4_A_t
DQS4_B_c
DQS4_B_t
DQS5_A_c||TDQS5_A_c||DQS5_A_t||TDQS5_A_t
DQS5_A_t||TDQS5_A_t
DQS5_B_c||TDQS5_B_c
DQS5_B_t||TDQS5_B_t
DQS6_A_c||TDQS6_A_c||DQS6_A_t||TDQS6_A_t
DQS6_B_c||TDQS6_B_c
DQS6_B_t||TDQS6_B_t
DQS7_A_t||TDQS7_A_t
DQS7_B_c||TDQS7_B_c
DQS8_A_c||TDQS8_A_c
DQS8_A_t||TDQS8_A_t
DQS9_A_c||TDQS9_A_c
DQS9_A_t||TDQS9_A_t
DQS9_B_c||TDQS9_B_c
DQS9_B_t||TDQS9_B_t||DBI4_B_n
R3875
102
288
286
284
281
279
277
275
273
270
268
266
264
262
259
257
255
253
251
248
246
244
242
240
237
235
233
230
228
226
224
222
219
216
214
212
210
208
206
204
202
199
197
195
193
191
188
186
184
182
180
177
175
173
171
169
166
164
162
160
158
155
153
151
143
141
139
136
134
132
130
128
125
123
121
119
117
114
112
110
108
106
103
101
99
97
95
92
90
88
85
83
81
79
77
75
73
71
69
67
65
63
61
59
57
54
52
50
48
46
43
41
39
37
35
32
30
28
26
24
21
19
17
15
13
10
8
6
146
145
1
G3
G2
G1
93
94
201
200
283
282
190
189
272
271
179
178
261
260
168
167
250
249
157
156
239
238
55
56
137
138
44
45
126
127
33
34
115
116
22
23
104
105
11
12
3
232
231
220
150
149
144
2
207
147
227
74
87
86
5
4
148
287
194
285
192
142
49
140
47
280
187
278
185
135
42
133
40
276
183
274
181
131
38
129
36
269
176
267
174
124
31
122
29
265
172
263
170
120
27
118
25
258
165
256
163
113
20
111
18
254
161
252
159
109
16
107
14
247
154
245
152
9
100
7
229
209
84
64
217
218
236
205
234
203
91
60
89
58
243
198
241
196
98
53
96
51
82
72
225
215
80
70
223
213
78
68
221
211
76
66
62
1
0
2
3
4
6
5
7
0
1
2
3
4
5
7
6
2
1
0
4
3
6
5
1
0
0
1
3
2
6
5
4
7
8
9
10
11
12
13
14
15
16
17
18
19
21
20
23
24
22
25
26
27
28
29
31
30
0
1
2
3
4
5
6
8
7
9
11
10
13
14
12
16
15
19
18
17
20
21
22
23
24
25
26
2
3
4
6
5
29
27
28
30
31
0
0
1
2
1
2
3
4
3
4
5
5
6
7
7
6
8
9
8
9
0
1
0
1
2
3
2
4
3
4
5
6
6
5
7
7
8
9
8
9
J1J1
J1
3/3
G3
G2
G1
VSS62
VSS61
VSS60
VSS58
VSS104
VSS102
VSS100
VIN_BULK2
VIN_BULK1
VIN_BULK0
VSS126
VSS125
VSS124
VSS123
VSS122
VSS121
VSS120
VSS119
VSS118
VSS117
VSS116
VSS115
VSS114
VSS113
VSS112
VSS111
VSS110
VSS109
VSS108
VSS107
VSS106
VSS105
VSS103
VSS101
VSS99
VSS98
VSS97
VSS96
VSS95
VSS94
VSS93
VSS92
VSS91
VSS90
VSS89
VSS88
VSS87
VSS86
VSS85
VSS84
VSS83
VSS82
VSS81
VSS80
VSS79
VSS78
VSS77
VSS76
VSS75
VSS74
VSS73
VSS72
VSS71
VSS70
VSS69
VSS68
VSS67
VSS66
VSS65
VSS64
VSS63
VSS59
VSS57
VSS56
VSS55
VSS54
VSS53
VSS52
VSS51
VSS50
VSS49
VSS48
VSS47
VSS46
VSS45
VSS44
VSS43
VSS42
VSS41
VSS40
VSS39
VSS38
VSS37
VSS36
VSS35
VSS34
VSS33
VSS32
VSS31
VSS30
VSS29
VSS28
VSS27
VSS26
VSS25
VSS24
VSS23
VSS22
VSS21
VSS20
VSS19
VSS18
VSS17
VSS16
VSS15
VSS14
VSS13
VSS12
VSS11
VSS10
VSS9
VSS8
VSS7
VSS6
VSS5
VSS4
VSS3
VSS2
VSS1
VSS0
2/31/3
DQ31_A
CB7_A
CB4_A
CB1_A
CB7_B
ALERT_n
CA0_A
CA0_B
CA1_A
CA1_B
CA2_A
CA2_B
CA3_A
CA3_B
CA4_A
CA4_B
CA5_A
CA5_B
CA6_A
CA6_B
CB6_A
CB5_A
CB3_A
CB2_A
CB0_A
CB6_B
CB5_B
CB4_B
CB3_B
CB2_B
CB1_B
CB0_B
CK_c
CK_t
CS0_A_n
CS0_B_n
CS1_A_n
CS1_B_n
DQ30_A
DQ29_A
DQ28_A
DQ27_A
DQ26_A
DQ25_A
DQ24_A
DQ23_A
DQ22_A
DQ21_A
DQ20_A
DQ19_A
DQ18_A
DQ17_A
DQ16_A
DQ15_A
DQ14_A
DQ13_A
DQ12_A
DQ11_A
DQ10_A
DQ9_A
DQ8_A
DQ7_A
DQ6_A
DQ5_A
DQ4_A
DQ3_A
DQ2_A
DQ1_A
DQ0_A
DQ31_B
DQ30_B
DQ29_B
DQ28_B
DQ27_B
DQ26_B
DQ25_B
DQ24_B
DQ23_B
DQ22_B
DQ21_B
DQ20_B
DQ19_B
DQ18_B
DQ17_B
DQ16_B
DQ15_B
DQ14_B
DQ13_B
DQ12_B
DQ11_B
DQ10_B
DQ9_B
DQ8_B
DQ7_B
DQ6_B
DQ5_B
DQ4_B
DQ3_B
DQ2_B
DQ1_B
DQ0_B
HSA
HSCL
HSDA
LBD||RSP_A_n
LBS||RSP_B_n
PAR_A
PAR_B
PWR_GOOD||FAIL_n
RESET_n
RFU6
RFU5
RFU4
RFU3
RFU2
RFU1
RFU0
VIN_MGMT
21
2
1
2
1
2
1
2
1
BOM NOTE:
CAD NOTE:
SHEETDATE
DEPARTMENT
SIZE
PROJECT DOCUMENT NUMBER REV
REVIEWER
DESIGNER
123
7 3 2 1 6 5 4
E
A
B
C
E
D
C
B
A
7 6 5 4
D
BI
IN
BI
OUT
OUTOUT
ININ
IN
IN
BI
BI
ININ
ININ
ININ
ININ
BI
IN
IN
OUTOUT
OUTOUT
R26
C2 C4 C3
C



20210728 MODIFY FOR GT
Fri Aug 25 14:01:02 2023N/AN/AN/AN/AV0583 OF 312
P3V3_AUXP3V3_AUX P12V_S3_AUX_CPU0_NVDIMM
P12V_S3_AUX_CPU0_NVDIMM
DDR5 - CPU0 CHA DIMM2(BLACK)22982848586878889229828485868788898312982848520821148320202082208220202020202020822082208220 82208220 8220 8220 8220 8220 82
PLACE THE BYPASS CAPS CLOSE TO DIMMI3C_SPD_DDRABCD_CPU0_LVC1_SCLI3C_SPD_DDRABCD_CPU0_LVC1_SCL_R2I3C_SPD_DDRABCD_CPU0_LVC1_SDAPD_CHA_CPU0_DIMM2_SAARST_M_AB_CPU0_FPGA_NM_A_CPU0_ALERT_NPWRGD_CHA_CPU0_DIMM2CHIP49.9TP_CHA_CPU0_DIMM2_FRU_6TP_CHA_CPU0_DIMM2_FRU_5TP_CHA_CPU0_DIMM2_FRU_4TP_CHA_CPU0_DIMM2_FRU_1PD_CHA_CPU0_DIMM2_SAAM_A_CPU0_SB_RSP<1>M_A_CPU0_SA_RSP<1>M_A_CPU0_SB_CB<7:0>M_A_CPU0_SA_CB<7:0>M_A_CPU0_CLK_DP<1>M_A_CPU0_CLK_DN<1>M_A_CPU0_SB_CS_N<2>M_A_CPU0_SB_CS_N<3>M_A_CPU0_SA_CS_N<3>M_A_CPU0_SA_CS_N<2>M_A_CPU0_SB_PARM_A_CPU0_SA_PARM_A_CPU0_SB_CA<6:0>TP_CHA_CPU0_DIMM2_FRU_3TP_CHA_CPU0_DIMM2_FRU_2TP_CHA_CPU0_DIMM2_FRU_0M_A_CPU0_SB_DQ<31:0>M_A_CPU0_SA_CA<6:0> M_A_CPU0_SA_DQ<31:0>M_A_CPU0_SB_DQS_DP<9:0>M_A_CPU0_SB_DQS_DN<9:0>M_A_CPU0_SA_DQS_DP<9:0>M_A_CPU0_SA_DQS_DN<9:0>
1/16W15.4K1%CHIP0402LF
IOSMLFSCONN288_ADR50017-P087CC
20%2.2UFX6S6.3VC0402
SCONN288_ADR50017-P087CCSMLFIO
16VC080510UF10%X6S16VC080510UF10%X6SBOM NOTE: 2ND SOURCE IS DFHST8FS384 (@BLACK)
SCONN288_ADR50017-P087CCSMLFIO
DQS7_A_c||TDQS7_A_c
DQS6_A_t||TDQS6_A_t
DQS8_B_t||TDQS8_B_t
DQS8_B_c||TDQS8_B_c
DQS7_B_t||TDQS7_B_t
DQS0_A_c
DQS0_A_t
DQS0_B_c
DQS0_B_t
DQS1_A_c
DQS1_A_t
DQS1_B_c
DQS1_B_t
DQS2_A_c
DQS2_A_t
DQS2_B_c
DQS2_B_t
DQS3_A_c
DQS3_A_t
DQS3_B_c
DQS3_B_t
DQS4_A_c
DQS4_A_t
DQS4_B_c
DQS4_B_t
DQS5_A_c||TDQS5_A_c||DQS5_A_t||TDQS5_A_t
DQS5_A_t||TDQS5_A_t
DQS5_B_c||TDQS5_B_c
DQS5_B_t||TDQS5_B_t
DQS6_A_c||TDQS6_A_c||DQS6_A_t||TDQS6_A_t
DQS6_B_c||TDQS6_B_c
DQS6_B_t||TDQS6_B_t
DQS7_A_t||TDQS7_A_t
DQS7_B_c||TDQS7_B_c
DQS8_A_c||TDQS8_A_c
DQS8_A_t||TDQS8_A_t
DQS9_A_c||TDQS9_A_c
DQS9_A_t||TDQS9_A_t
DQS9_B_c||TDQS9_B_c
DQS9_B_t||TDQS9_B_t||DBI4_B_n
R3876
93
94
201
200
283
282
190
189
272
271
179
178
261
260
168
167
250
249
157
156
239
238
55
56
137
138
44
45
126
127
33
34
115
116
22
23
104
105
11
12
288
286
284
281
279
277
275
273
270
268
266
264
262
259
257
255
253
251
248
246
244
242
240
237
235
233
230
228
226
224
222
219
216
214
212
210
208
206
204
202
199
197
195
193
191
188
186
184
182
180
177
175
173
171
169
166
164
162
160
158
155
153
151
143
141
139
136
134
132
130
128
125
123
121
119
117
114
112
110
108
106
103
101
99
97
95
92
90
88
85
83
81
79
77
75
73
71
69
67
65
63
61
59
57
54
52
50
48
46
43
41
39
37
35
32
30
28
26
24
21
19
17
15
13
10
8
6
146
145
1
G3
G2
G1
3
232
231
220
150
149
144
2
207
147
227
74
87
86
5
4
148
287
194
285
192
142
49
140
47
280
187
278
185
135
42
133
40
276
183
274
181
131
38
129
36
269
176
267
174
124
31
122
29
265
172
263
170
120
27
118
25
258
165
256
163
113
20
111
18
254
161
252
159
109
16
107
14
247
154
245
152
102
9
100
7
229
209
84
64
217
218
236
205
234
203
91
60
89
58
243
198
241
196
98
53
96
51
82
72
225
215
80
70
223
213
78
68
221
211
76
66
62
3
4
5
6
7
8
0
0
1
3
2
4
5
6
7
8
9
10
11
12
13
15
14
17
16
18
19
20
1
2
3
4
5
6
7
0
1
2
4
3
5
6
7
1
0
2
3
4
5
6
0
1
3
2
22
21
23
24
25
26
28
27
29
31
30
0
2
1
3
5
4
7
6
8
9
10
11
13
12
14
15
16
18
17
19
21
20
23
22
25
24
26
27
28
5
4
6
29
30
31
0
1
0
1
2
3
2
4
5
6
8
7
9
0
9
0
1
2
1
2
3
3
4
5
4
5
6
7
6
7
8
8
9
9
J2
J2J2
2/3 3/3
G3
G2
G1
VSS62
VSS61
VSS60
VSS58
VSS104
VSS102
VSS100
VIN_BULK2
VIN_BULK1
VIN_BULK0
VSS126
VSS125
VSS124
VSS123
VSS122
VSS121
VSS120
VSS119
VSS118
VSS117
VSS116
VSS115
VSS114
VSS113
VSS112
VSS111
VSS110
VSS109
VSS108
VSS107
VSS106
VSS105
VSS103
VSS101
VSS99
VSS98
VSS97
VSS96
VSS95
VSS94
VSS93
VSS92
VSS91
VSS90
VSS89
VSS88
VSS87
VSS86
VSS85
VSS84
VSS83
VSS82
VSS81
VSS80
VSS79
VSS78
VSS77
VSS76
VSS75
VSS74
VSS73
VSS72
VSS71
VSS70
VSS69
VSS68
VSS67
VSS66
VSS65
VSS64
VSS63
VSS59
VSS57
VSS56
VSS55
VSS54
VSS53
VSS52
VSS51
VSS50
VSS49
VSS48
VSS47
VSS46
VSS45
VSS44
VSS43
VSS42
VSS41
VSS40
VSS39
VSS38
VSS37
VSS36
VSS35
VSS34
VSS33
VSS32
VSS31
VSS30
VSS29
VSS28
VSS27
VSS26
VSS25
VSS24
VSS23
VSS22
VSS21
VSS20
VSS19
VSS18
VSS17
VSS16
VSS15
VSS14
VSS13
VSS12
VSS11
VSS10
VSS9
VSS8
VSS7
VSS6
VSS5
VSS4
VSS3
VSS2
VSS1
VSS0
1/3
DQ31_A
CB7_A
CB4_A
CB1_A
CB7_B
ALERT_n
CA0_A
CA0_B
CA1_A
CA1_B
CA2_A
CA2_B
CA3_A
CA3_B
CA4_A
CA4_B
CA5_A
CA5_B
CA6_A
CA6_B
CB6_A
CB5_A
CB3_A
CB2_A
CB0_A
CB6_B
CB5_B
CB4_B
CB3_B
CB2_B
CB1_B
CB0_B
CK_c
CK_t
CS0_A_n
CS0_B_n
CS1_A_n
CS1_B_n
DQ30_A
DQ29_A
DQ28_A
DQ27_A
DQ26_A
DQ25_A
DQ24_A
DQ23_A
DQ22_A
DQ21_A
DQ20_A
DQ19_A
DQ18_A
DQ17_A
DQ16_A
DQ15_A
DQ14_A
DQ13_A
DQ12_A
DQ11_A
DQ10_A
DQ9_A
DQ8_A
DQ7_A
DQ6_A
DQ5_A
DQ4_A
DQ3_A
DQ2_A
DQ1_A
DQ0_A
DQ31_B
DQ30_B
DQ29_B
DQ28_B
DQ27_B
DQ26_B
DQ25_B
DQ24_B
DQ23_B
DQ22_B
DQ21_B
DQ20_B
DQ19_B
DQ18_B
DQ17_B
DQ16_B
DQ15_B
DQ14_B
DQ13_B
DQ12_B
DQ11_B
DQ10_B
DQ9_B
DQ8_B
DQ7_B
DQ6_B
DQ5_B
DQ4_B
DQ3_B
DQ2_B
DQ1_B
DQ0_B
HSA
HSCL
HSDA
LBD||RSP_A_n
LBS||RSP_B_n
PAR_A
PAR_B
PWR_GOOD||FAIL_n
RESET_n
RFU6
RFU5
RFU4
RFU3
RFU2
RFU1
RFU0
VIN_MGMT
21
2
1
2
1
2
1
2
1
BOM NOTE:
CAD NOTE:
SHEETDATE
DEPARTMENT
SIZE
PROJECT DOCUMENT NUMBER REV
REVIEWER
DESIGNER
123
7 3 2 1 6 5 4
E
A
B
C
E
D
C
B
A
7 6 5 4
D
IN
IN
ININ
OUTOUT
IN
ININ
IN
OUT
IN
IN
BI
IN
OUTOUT
IN
BI
OUTOUT
IN
BI
IN
BI
BI
IN
C7C6C5
C
R27



20210728 MODIFY FOR GT
Fri Aug 25 14:01:03 2023N/AN/AN/AN/A V0584 OF 312
P3V3_AUXP12V_S3_AUX_CPU0_NVDIMM
P12V_S3_AUX_CPU0_NVDIMMP3V3_AUXDDR5 - CPU0 CHB DIMM1(YELLOW)
8422982838586878889129828385218522982838586878889114218521852185218521218521212121212121218521852185218584
218521852185
PLACE THE BYPASS CAPS CLOSE TO DIMMC0402I3C_SPD_DDRABCD_CPU0_LVC1_SCL_R3PD_CHB_CPU0_DIMM1_SAAI3C_SPD_DDRABCD_CPU0_LVC1_SDARST_M_AB_CPU0_FPGA_NM_B_CPU0_ALERT_NCHIP49.9I3C_SPD_DDRABCD_CPU0_LVC1_SCLPWRGD_CHB_CPU0_DIMM1M_B_CPU0_SB_DQS_DN<9:0>M_B_CPU0_SB_DQS_DP<9:0>M_B_CPU0_SA_DQS_DP<9:0>M_B_CPU0_SA_DQS_DN<9:0>M_B_CPU0_SB_CS_N<1>M_B_CPU0_SA_CB<7:0>M_B_CPU0_CLK_DN<0>M_B_CPU0_CLK_DP<0>SMLFIOSCONN288_ADR50017-P130CCM_B_CPU0_SA_CS_N<0>M_B_CPU0_SB_CS_N<0>M_B_CPU0_SA_CS_N<1>M_B_CPU0_SA_RSP<0>M_B_CPU0_SB_RSP<0>M_B_CPU0_SA_PARM_B_CPU0_SB_PARTP_CHB_CPU0_DIMM1_FRU_6TP_CHB_CPU0_DIMM1_FRU_5TP_CHB_CPU0_DIMM1_FRU_4TP_CHB_CPU0_DIMM1_FRU_3TP_CHB_CPU0_DIMM1_FRU_2TP_CHB_CPU0_DIMM1_FRU_1TP_CHB_CPU0_DIMM1_FRU_0
SMLFIOSCONN288_ADR50017-P130CCSMLFIOSCONN288_ADR50017-P130CCM_B_CPU0_SB_DQ<31:0>M_B_CPU0_SB_CB<7:0>CHIP1%1/16W0402LF23.2KX6SC080510%16V10UFX6S10UFC080510%16VPD_CHB_CPU0_DIMM1_SAA
M_B_CPU0_SB_CA<6:0>M_B_CPU0_SA_CA<6:0> M_B_CPU0_SA_DQ<31:0>
X6S20%2.2UF6.3V
DQS7_A_c||TDQS7_A_c
DQS6_A_t||TDQS6_A_t
DQS8_B_t||TDQS8_B_t
DQS8_B_c||TDQS8_B_c
DQS7_B_t||TDQS7_B_t
DQS0_A_c
DQS0_A_t
DQS0_B_c
DQS0_B_t
DQS1_A_c
DQS1_A_t
DQS1_B_c
DQS1_B_t
DQS2_A_c
DQS2_A_t
DQS2_B_c
DQS2_B_t
DQS3_A_c
DQS3_A_t
DQS3_B_c
DQS3_B_t
DQS4_A_c
DQS4_A_t
DQS4_B_c
DQS4_B_t
DQS5_A_c||TDQS5_A_c||DQS5_A_t||TDQS5_A_t
DQS5_A_t||TDQS5_A_t
DQS5_B_c||TDQS5_B_c
DQS5_B_t||TDQS5_B_t
DQS6_A_c||TDQS6_A_c||DQS6_A_t||TDQS6_A_t
DQS6_B_c||TDQS6_B_c
DQS6_B_t||TDQS6_B_t
DQS7_A_t||TDQS7_A_t
DQS7_B_c||TDQS7_B_c
DQS8_A_c||TDQS8_A_c
DQS8_A_t||TDQS8_A_t
DQS9_A_c||TDQS9_A_c
DQS9_A_t||TDQS9_A_t
DQS9_B_c||TDQS9_B_c
DQS9_B_t||TDQS9_B_t||DBI4_B_n
R3877
3
232
231
220
150
149
144
2
207
147
227
74
87
86
5
4
148
287
194
285
192
142
49
140
47
280
187
278
185
135
42
133
40
276
183
274
181
131
38
129
36
269
176
267
174
124
31
122
29
265
172
263
170
120
27
118
25
258
165
256
163
113
20
111
18
254
161
252
159
109
16
107
14
247
154
245
152
102
9
100
7
229
209
84
64
217
218
236
205
234
203
91
60
89
58
243
198
241
196
98
53
96
51
82
72
225
215
80
70
223
213
78
68
221
211
76
66
62
93
94
201
200
283
282
190
189
272
271
179
178
261
260
168
167
250
249
157
156
239
238
55
56
137
138
44
45
126
127
33
34
115
116
22
23
104
105
11
12
288
286
284
281
279
277
275
273
270
268
266
264
262
259
257
255
253
251
248
246
244
242
240
237
235
233
230
228
226
224
222
219
216
214
212
210
208
206
204
202
199
197
195
193
191
188
186
184
182
180
177
175
173
171
169
166
164
162
160
158
155
153
151
143
141
139
136
134
132
130
128
125
123
121
119
117
114
112
110
108
106
103
101
99
97
95
92
90
88
85
83
81
79
77
75
73
71
69
67
65
63
61
59
57
54
52
50
48
46
43
41
39
37
35
32
30
28
26
24
21
19
17
15
13
10
8
6
146
145
1
G3
G2
G1
2
3
4
4
7
1
9
0
1
0
2
3
4
5
6
8
9
1
2
5
6
7
8
9
0
2
3
4
5
6
7
8
0
1
3
5
6
7
8
9
3
7
7
10
31
18
19
15
16
12
14
13
10
11
9
8
6
5
4
3
2
1
0
30
29
28
27
26
25
22
24
23
20
21
19
18
17
16
15
14
13
12
11
9
8
7
4
5
6
2
3
1
0
0
1
5
6
3
4
0
1
2
6
7
5
4
3
2
1
0
5
6
4
2
0
1
31
30
28
27
29
5
6
4
3
2
26
25
24
23
22
21
20
17
J3 J3 J3
1/3
DQ31_A
CB7_A
CB4_A
CB1_A
CB7_B
ALERT_n
CA0_A
CA0_B
CA1_A
CA1_B
CA2_A
CA2_B
CA3_A
CA3_B
CA4_A
CA4_B
CA5_A
CA5_B
CA6_A
CA6_B
CB6_A
CB5_A
CB3_A
CB2_A
CB0_A
CB6_B
CB5_B
CB4_B
CB3_B
CB2_B
CB1_B
CB0_B
CK_c
CK_t
CS0_A_n
CS0_B_n
CS1_A_n
CS1_B_n
DQ30_A
DQ29_A
DQ28_A
DQ27_A
DQ26_A
DQ25_A
DQ24_A
DQ23_A
DQ22_A
DQ21_A
DQ20_A
DQ19_A
DQ18_A
DQ17_A
DQ16_A
DQ15_A
DQ14_A
DQ13_A
DQ12_A
DQ11_A
DQ10_A
DQ9_A
DQ8_A
DQ7_A
DQ6_A
DQ5_A
DQ4_A
DQ3_A
DQ2_A
DQ1_A
DQ0_A
DQ31_B
DQ30_B
DQ29_B
DQ28_B
DQ27_B
DQ26_B
DQ25_B
DQ24_B
DQ23_B
DQ22_B
DQ21_B
DQ20_B
DQ19_B
DQ18_B
DQ17_B
DQ16_B
DQ15_B
DQ14_B
DQ13_B
DQ12_B
DQ11_B
DQ10_B
DQ9_B
DQ8_B
DQ7_B
DQ6_B
DQ5_B
DQ4_B
DQ3_B
DQ2_B
DQ1_B
DQ0_B
HSA
HSCL
HSDA
LBD||RSP_A_n
LBS||RSP_B_n
PAR_A
PAR_B
PWR_GOOD||FAIL_n
RESET_n
RFU6
RFU5
RFU4
RFU3
RFU2
RFU1
RFU0
VIN_MGMT
2/3 3/3
G3
G2
G1
VSS62
VSS61
VSS60
VSS58
VSS104
VSS102
VSS100
VIN_BULK2
VIN_BULK1
VIN_BULK0
VSS126
VSS125
VSS124
VSS123
VSS122
VSS121
VSS120
VSS119
VSS118
VSS117
VSS116
VSS115
VSS114
VSS113
VSS112
VSS111
VSS110
VSS109
VSS108
VSS107
VSS106
VSS105
VSS103
VSS101
VSS99
VSS98
VSS97
VSS96
VSS95
VSS94
VSS93
VSS92
VSS91
VSS90
VSS89
VSS88
VSS87
VSS86
VSS85
VSS84
VSS83
VSS82
VSS81
VSS80
VSS79
VSS78
VSS77
VSS76
VSS75
VSS74
VSS73
VSS72
VSS71
VSS70
VSS69
VSS68
VSS67
VSS66
VSS65
VSS64
VSS63
VSS59
VSS57
VSS56
VSS55
VSS54
VSS53
VSS52
VSS51
VSS50
VSS49
VSS48
VSS47
VSS46
VSS45
VSS44
VSS43
VSS42
VSS41
VSS40
VSS39
VSS38
VSS37
VSS36
VSS35
VSS34
VSS33
VSS32
VSS31
VSS30
VSS29
VSS28
VSS27
VSS26
VSS25
VSS24
VSS23
VSS22
VSS21
VSS20
VSS19
VSS18
VSS17
VSS16
VSS15
VSS14
VSS13
VSS12
VSS11
VSS10
VSS9
VSS8
VSS7
VSS6
VSS5
VSS4
VSS3
VSS2
VSS1
VSS0
21
2
1
2
1
2
1
2
1
CAD NOTE:
SHEETDATE
DEPARTMENT
SIZE
PROJECT DOCUMENT NUMBER REV
REVIEWER
DESIGNER
123
7 3 2 1 6 5 4
E
A
B
C
E
D
C
B
A
7 6 5 4
D
IN
IN
ININ
OUTOUT
IN
ININ
IN
OUT
IN
IN
IN
BI
OUTOUT
IN
BI
OUTOUT
ININ
BI
BI
BI
IN
C10C9C8
R28
C



20210728 MODIFY FOR GT
Fri Aug 25 14:01:04 2023N/AN/AN/AN/AV0585 OF 312P3V3_AUXP3V3_AUXP12V_S3_AUX_CPU0_NVDIMM
P12V_S3_AUX_CPU0_NVDIMMDDR5 - CPU0 CHB DIMM2(BLACK)
12982838485229828384868788892184229828384868788891142184 21842184218421842121842121212121212121842184
852184218421842184
PLACE THE BYPASS CAPS CLOSE TO DIMM10%16VRST_M_AB_CPU0_FPGA_NI3C_SPD_DDRABCD_CPU0_LVC1_SCL_R4PD_CHB_CPU0_DIMM2_SAAI3C_SPD_DDRABCD_CPU0_LVC1_SDAM_B_CPU0_ALERT_NI3C_SPD_DDRABCD_CPU0_LVC1_SCLCHIP49.9PWRGD_CHB_CPU0_DIMM2TP_CHB_CPU0_DIMM2_FRU_6TP_CHB_CPU0_DIMM2_FRU_0TP_CHB_CPU0_DIMM2_FRU_1M_B_CPU0_SB_CB<7:0>M_B_CPU0_SB_DQS_DP<9:0>M_B_CPU0_SB_DQS_DN<9:0>M_B_CPU0_SA_DQS_DP<9:0>M_B_CPU0_SA_DQS_DN<9:0>M_B_CPU0_SA_CS_N<3>SCONN288_ADR50017-P087CCSMLFIOSCONN288_ADR50017-P087CCSMLFM_B_CPU0_SA_DQ<31:0>IOM_B_CPU0_CLK_DN<1>M_B_CPU0_CLK_DP<1>M_B_CPU0_SA_CS_N<2>M_B_CPU0_SB_CS_N<2>M_B_CPU0_SB_CS_N<3>M_B_CPU0_SA_RSP<1>M_B_CPU0_SB_RSP<1>M_B_CPU0_SA_PARM_B_CPU0_SB_PARTP_CHB_CPU0_DIMM2_FRU_5TP_CHB_CPU0_DIMM2_FRU_4TP_CHB_CPU0_DIMM2_FRU_3TP_CHB_CPU0_DIMM2_FRU_2
IOSCONN288_ADR50017-P087CCSMLF
CHIP1/16W0402LF1%35.7KX6S16VC080510UF10%X6S10UFC0805PD_CHB_CPU0_DIMM2_SAAM_B_CPU0_SB_DQ<31:0>M_B_CPU0_SB_CA<6:0>M_B_CPU0_SA_CA<6:0>M_B_CPU0_SA_CB<7:0>6.3VX6SC04022.2UF20%
DQS7_A_c||TDQS7_A_c
DQS6_A_t||TDQS6_A_t
DQS8_B_t||TDQS8_B_t
DQS8_B_c||TDQS8_B_c
DQS7_B_t||TDQS7_B_t
DQS0_A_c
DQS0_A_t
DQS0_B_c
DQS0_B_t
DQS1_A_c
DQS1_A_t
DQS1_B_c
DQS1_B_t
DQS2_A_c
DQS2_A_t
DQS2_B_c
DQS2_B_t
DQS3_A_c
DQS3_A_t
DQS3_B_c
DQS3_B_t
DQS4_A_c
DQS4_A_t
DQS4_B_c
DQS4_B_t
DQS5_A_c||TDQS5_A_c||DQS5_A_t||TDQS5_A_t
DQS5_A_t||TDQS5_A_t
DQS5_B_c||TDQS5_B_c
DQS5_B_t||TDQS5_B_t
DQS6_A_c||TDQS6_A_c||DQS6_A_t||TDQS6_A_t
DQS6_B_c||TDQS6_B_c
DQS6_B_t||TDQS6_B_t
DQS7_A_t||TDQS7_A_t
DQS7_B_c||TDQS7_B_c
DQS8_A_c||TDQS8_A_c
DQS8_A_t||TDQS8_A_t
DQS9_A_c||TDQS9_A_c
DQS9_A_t||TDQS9_A_t
DQS9_B_c||TDQS9_B_c
DQS9_B_t||TDQS9_B_t||DBI4_B_n
R3878
93
94
201
200
283
282
190
189
272
271
179
178
261
260
168
167
250
249
157
156
239
238
55
56
137
138
44
45
126
127
33
34
115
116
22
23
104
105
11
12
288
286
284
281
279
277
275
273
270
268
266
264
262
259
257
255
253
251
248
246
244
242
240
237
235
233
230
228
226
224
222
219
216
214
212
210
208
206
204
202
199
197
195
193
191
188
186
184
182
180
177
175
173
171
169
166
164
162
160
158
155
153
151
143
141
139
136
134
132
130
128
125
123
121
119
117
114
112
110
108
106
103
101
99
97
95
92
90
88
85
83
81
79
77
75
73
71
69
67
65
63
61
59
57
54
52
50
48
46
43
41
39
37
35
32
30
28
26
24
21
19
17
15
13
10
8
6
146
145
1
G3
G2
G1
3
232
231
220
150
149
144
2
207
147
227
74
87
86
5
4
148
287
194
285
192
142
49
140
47
280
187
278
185
135
42
133
40
276
183
274
181
131
38
129
36
269
176
267
174
124
31
122
29
265
172
263
170
120
27
118
25
258
165
256
163
113
20
111
18
254
161
252
159
109
16
107
14
247
154
245
152
102
9
100
7
229
209
84
64
217
218
236
205
234
203
91
60
89
58
243
198
241
196
98
53
96
51
82
72
225
215
80
70
223
213
78
68
221
211
76
66
62
15
1
2
3
0
1
2
4
3
5
6
7
8
9
0
1
2
3
4
5
6
7
9
8
1
0
2
3
6
4
5
7
8
0
9
1
2
3
4
5
6
7
8
9
18
23
18
12
11
4
15
16
14
13
9
10
8
7
6
5
3
2
1
0
30
31
29
28
27
25
26
24
22
21
3
2
1
0
5
6
4
2
3
1
0
7
5
6
4
3
2
0
1
7
6
4
5
19
20
17
16
14
13
12
11
9
10
7
8
6
4
5
3
2
1
0
0
31
29
30
6
5
4
27
28
26
25
24
23
22
21
20
19
17
J4
J4J4
1/3
DQ31_A
CB7_A
CB4_A
CB1_A
CB7_B
ALERT_n
CA0_A
CA0_B
CA1_A
CA1_B
CA2_A
CA2_B
CA3_A
CA3_B
CA4_A
CA4_B
CA5_A
CA5_B
CA6_A
CA6_B
CB6_A
CB5_A
CB3_A
CB2_A
CB0_A
CB6_B
CB5_B
CB4_B
CB3_B
CB2_B
CB1_B
CB0_B
CK_c
CK_t
CS0_A_n
CS0_B_n
CS1_A_n
CS1_B_n
DQ30_A
DQ29_A
DQ28_A
DQ27_A
DQ26_A
DQ25_A
DQ24_A
DQ23_A
DQ22_A
DQ21_A
DQ20_A
DQ19_A
DQ18_A
DQ17_A
DQ16_A
DQ15_A
DQ14_A
DQ13_A
DQ12_A
DQ11_A
DQ10_A
DQ9_A
DQ8_A
DQ7_A
DQ6_A
DQ5_A
DQ4_A
DQ3_A
DQ2_A
DQ1_A
DQ0_A
DQ31_B
DQ30_B
DQ29_B
DQ28_B
DQ27_B
DQ26_B
DQ25_B
DQ24_B
DQ23_B
DQ22_B
DQ21_B
DQ20_B
DQ19_B
DQ18_B
DQ17_B
DQ16_B
DQ15_B
DQ14_B
DQ13_B
DQ12_B
DQ11_B
DQ10_B
DQ9_B
DQ8_B
DQ7_B
DQ6_B
DQ5_B
DQ4_B
DQ3_B
DQ2_B
DQ1_B
DQ0_B
HSA
HSCL
HSDA
LBD||RSP_A_n
LBS||RSP_B_n
PAR_A
PAR_B
PWR_GOOD||FAIL_n
RESET_n
RFU6
RFU5
RFU4
RFU3
RFU2
RFU1
RFU0
VIN_MGMT
2/3 3/3
G3
G2
G1
VSS62
VSS61
VSS60
VSS58
VSS104
VSS102
VSS100
VIN_BULK2
VIN_BULK1
VIN_BULK0
VSS126
VSS125
VSS124
VSS123
VSS122
VSS121
VSS120
VSS119
VSS118
VSS117
VSS116
VSS115
VSS114
VSS113
VSS112
VSS111
VSS110
VSS109
VSS108
VSS107
VSS106
VSS105
VSS103
VSS101
VSS99
VSS98
VSS97
VSS96
VSS95
VSS94
VSS93
VSS92
VSS91
VSS90
VSS89
VSS88
VSS87
VSS86
VSS85
VSS84
VSS83
VSS82
VSS81
VSS80
VSS79
VSS78
VSS77
VSS76
VSS75
VSS74
VSS73
VSS72
VSS71
VSS70
VSS69
VSS68
VSS67
VSS66
VSS65
VSS64
VSS63
VSS59
VSS57
VSS56
VSS55
VSS54
VSS53
VSS52
VSS51
VSS50
VSS49
VSS48
VSS47
VSS46
VSS45
VSS44
VSS43
VSS42
VSS41
VSS40
VSS39
VSS38
VSS37
VSS36
VSS35
VSS34
VSS33
VSS32
VSS31
VSS30
VSS29
VSS28
VSS27
VSS26
VSS25
VSS24
VSS23
VSS22
VSS21
VSS20
VSS19
VSS18
VSS17
VSS16
VSS15
VSS14
VSS13
VSS12
VSS11
VSS10
VSS9
VSS8
VSS7
VSS6
VSS5
VSS4
VSS3
VSS2
VSS1
VSS0
21
2
1
2
1
2
1
2
1
CAD NOTE:
SHEETDATE
DEPARTMENT
SIZE
PROJECT DOCUMENT NUMBER REV
REVIEWER
DESIGNER
123
7 3 2 1 6 5 4
E
A
B
C
E
D
C
B
A
7 6 5 4
D
IN
ININ
OUTOUT
OUT
IN
ININ
ININ
IN
BI
OUTOUT
IN
BI
OUTOUT
IN
ININ
BI
BI
BI
IN
IN
C13C12C11
R29
C



20210728 MODIFY FOR GT
Fri Aug 25 14:01:05 2023N/AN/AN/AN/AV0586 OF 312P12V_S3_AUX_CPU0_NVDIMMP3V3_AUXP12V_S3_AUX_CPU0_NVDIMM
P3V3_AUXDDR5 - CPU0 CHC DIMM1(YELLOW)
2287862298283848587888912987888922872298283848587888911422 8722 8722 8722 872222 8722 872222222222222222872287
86
228722872287PLACE THE BYPASS CAPS CLOSE TO DIMMC0805 C0805M_C_CPU0_SA_CB<7:0>I3C_SPD_DDRABCD_CPU0_LVC1_SCL_R5PD_CHC_CPU0_DIMM1_SAAI3C_SPD_DDRABCD_CPU0_LVC1_SDARST_M_CD_CPU0_FPGA_NM_C_CPU0_ALERT_NI3C_SPD_DDRABCD_CPU0_LVC1_SCLPWRGD_CHC_CPU0_DIMM1CHIPM_C_CPU0_SA_DQS_DP<9:0>M_C_CPU0_SA_DQS_DN<9:0>M_C_CPU0_SB_DQS_DP<9:0>M_C_CPU0_SB_DQS_DN<9:0>M_C_CPU0_CLK_DP<0>49.9TP_CHC_CPU0_DIMM1_FRU_6
SMLFSCONN288_ADR50017-P130CCSMLFSCONN288_ADR50017-P130CCSMLFSCONN288_ADR50017-P130CCM_C_CPU0_SA_DQ<31:0>M_C_CPU0_SB_DQ<31:0>IOIOM_C_CPU0_CLK_DN<0>M_C_CPU0_SA_CS_N<0>M_C_CPU0_SB_CS_N<0>M_C_CPU0_SA_CS_N<1>M_C_CPU0_SB_CS_N<1>M_C_CPU0_SA_RSP<0>M_C_CPU0_SB_RSP<0>M_C_CPU0_SA_PARM_C_CPU0_SB_PARTP_CHC_CPU0_DIMM1_FRU_5TP_CHC_CPU0_DIMM1_FRU_4TP_CHC_CPU0_DIMM1_FRU_3TP_CHC_CPU0_DIMM1_FRU_2TP_CHC_CPU0_DIMM1_FRU_1TP_CHC_CPU0_DIMM1_FRU_0
IO
54.9K1%0402LFCHIP1/16WX6S16V10UF10%X6S10%10UF16VPD_CHC_CPU0_DIMM1_SAA
M_C_CPU0_SB_CA<6:0>M_C_CPU0_SA_CA<6:0>M_C_CPU0_SB_CB<7:0>6.3VX6S2.2UF20%C0402
DQS7_A_c||TDQS7_A_c
DQS6_A_t||TDQS6_A_t
DQS8_B_t||TDQS8_B_t
DQS8_B_c||TDQS8_B_c
DQS7_B_t||TDQS7_B_t
DQS0_A_c
DQS0_A_t
DQS0_B_c
DQS0_B_t
DQS1_A_c
DQS1_A_t
DQS1_B_c
DQS1_B_t
DQS2_A_c
DQS2_A_t
DQS2_B_c
DQS2_B_t
DQS3_A_c
DQS3_A_t
DQS3_B_c
DQS3_B_t
DQS4_A_c
DQS4_A_t
DQS4_B_c
DQS4_B_t
DQS5_A_c||TDQS5_A_c||DQS5_A_t||TDQS5_A_t
DQS5_A_t||TDQS5_A_t
DQS5_B_c||TDQS5_B_c
DQS5_B_t||TDQS5_B_t
DQS6_A_c||TDQS6_A_c||DQS6_A_t||TDQS6_A_t
DQS6_B_c||TDQS6_B_c
DQS6_B_t||TDQS6_B_t
DQS7_A_t||TDQS7_A_t
DQS7_B_c||TDQS7_B_c
DQS8_A_c||TDQS8_A_c
DQS8_A_t||TDQS8_A_t
DQS9_A_c||TDQS9_A_c
DQS9_A_t||TDQS9_A_t
DQS9_B_c||TDQS9_B_c
DQS9_B_t||TDQS9_B_t||DBI4_B_n
R3879
93
94
201
200
283
282
190
189
272
271
179
178
261
260
168
167
250
249
157
156
239
238
55
56
137
138
44
45
126
127
33
34
115
116
22
23
104
105
11
12
288
286
284
281
279
277
275
273
270
268
266
264
262
259
257
255
253
251
248
246
244
242
240
237
235
233
230
228
226
224
222
219
216
214
212
210
208
206
204
202
199
197
195
193
191
188
186
184
182
180
177
175
173
171
169
166
164
162
160
158
155
153
151
143
141
139
136
134
132
130
128
125
123
121
119
117
114
112
110
108
106
103
101
99
97
95
92
90
88
85
83
81
79
77
75
73
71
69
67
65
63
61
59
57
54
52
50
48
46
43
41
39
37
35
32
30
28
26
24
21
19
17
15
13
10
8
6
146
145
1
G3
G2
G1
3
232
231
220
150
149
144
2
207
147
227
74
87
86
5
4
148
287
194
285
192
142
49
140
47
280
187
278
185
135
42
133
40
276
183
274
181
131
38
129
36
269
176
267
174
124
31
122
29
265
172
263
170
120
27
118
25
258
165
256
163
113
20
111
18
254
161
252
159
109
16
107
14
247
154
245
152
102
9
100
7
229
209
84
64
217
218
236
205
234
203
91
60
89
58
243
198
241
196
98
53
96
51
82
72
225
215
80
70
223
213
78
68
221
211
76
66
62
5
9
8
7
6
4
5
3
2
1
0
8
9
7
6
5
4
3
2
1
0
9
8
7
6
5
4
3
2
1
0
9
8
7
6
4
3
2
1
0
12
1
1
3
4
13
11
10
8
7
9
6
5
2
3
4
1
0
30
31
29
28
27
6
5
2
3
4
0
1
4
3
6
5
2
0
7
6
3
4
5
7
0
1
2
26
25
22
23
24
20
21
19
17
18
16
15
14
12
13
10
11
8
7
9
6
5
4
2
0
6
5
2
3
1
0
30
31
28
27
29
26
25
24
23
22
20
21
17
18
19
16
15
14
J5
J5J5
1/3
DQ31_A
CB7_A
CB4_A
CB1_A
CB7_B
ALERT_n
CA0_A
CA0_B
CA1_A
CA1_B
CA2_A
CA2_B
CA3_A
CA3_B
CA4_A
CA4_B
CA5_A
CA5_B
CA6_A
CA6_B
CB6_A
CB5_A
CB3_A
CB2_A
CB0_A
CB6_B
CB5_B
CB4_B
CB3_B
CB2_B
CB1_B
CB0_B
CK_c
CK_t
CS0_A_n
CS0_B_n
CS1_A_n
CS1_B_n
DQ30_A
DQ29_A
DQ28_A
DQ27_A
DQ26_A
DQ25_A
DQ24_A
DQ23_A
DQ22_A
DQ21_A
DQ20_A
DQ19_A
DQ18_A
DQ17_A
DQ16_A
DQ15_A
DQ14_A
DQ13_A
DQ12_A
DQ11_A
DQ10_A
DQ9_A
DQ8_A
DQ7_A
DQ6_A
DQ5_A
DQ4_A
DQ3_A
DQ2_A
DQ1_A
DQ0_A
DQ31_B
DQ30_B
DQ29_B
DQ28_B
DQ27_B
DQ26_B
DQ25_B
DQ24_B
DQ23_B
DQ22_B
DQ21_B
DQ20_B
DQ19_B
DQ18_B
DQ17_B
DQ16_B
DQ15_B
DQ14_B
DQ13_B
DQ12_B
DQ11_B
DQ10_B
DQ9_B
DQ8_B
DQ7_B
DQ6_B
DQ5_B
DQ4_B
DQ3_B
DQ2_B
DQ1_B
DQ0_B
HSA
HSCL
HSDA
LBD||RSP_A_n
LBS||RSP_B_n
PAR_A
PAR_B
PWR_GOOD||FAIL_n
RESET_n
RFU6
RFU5
RFU4
RFU3
RFU2
RFU1
RFU0
VIN_MGMT
2/3 3/3
G3
G2
G1
VSS62
VSS61
VSS60
VSS58
VSS104
VSS102
VSS100
VIN_BULK2
VIN_BULK1
VIN_BULK0
VSS126
VSS125
VSS124
VSS123
VSS122
VSS121
VSS120
VSS119
VSS118
VSS117
VSS116
VSS115
VSS114
VSS113
VSS112
VSS111
VSS110
VSS109
VSS108
VSS107
VSS106
VSS105
VSS103
VSS101
VSS99
VSS98
VSS97
VSS96
VSS95
VSS94
VSS93
VSS92
VSS91
VSS90
VSS89
VSS88
VSS87
VSS86
VSS85
VSS84
VSS83
VSS82
VSS81
VSS80
VSS79
VSS78
VSS77
VSS76
VSS75
VSS74
VSS73
VSS72
VSS71
VSS70
VSS69
VSS68
VSS67
VSS66
VSS65
VSS64
VSS63
VSS59
VSS57
VSS56
VSS55
VSS54
VSS53
VSS52
VSS51
VSS50
VSS49
VSS48
VSS47
VSS46
VSS45
VSS44
VSS43
VSS42
VSS41
VSS40
VSS39
VSS38
VSS37
VSS36
VSS35
VSS34
VSS33
VSS32
VSS31
VSS30
VSS29
VSS28
VSS27
VSS26
VSS25
VSS24
VSS23
VSS22
VSS21
VSS20
VSS19
VSS18
VSS17
VSS16
VSS15
VSS14
VSS13
VSS12
VSS11
VSS10
VSS9
VSS8
VSS7
VSS6
VSS5
VSS4
VSS3
VSS2
VSS1
VSS0
21
2
1
2
1
2
1
2
1
CAD NOTE:
SHEETDATE
DEPARTMENT
SIZE
PROJECT DOCUMENT NUMBER REV
REVIEWER
DESIGNER
123
7 3 2 1 6 5 4
E
A
B
C
E
D
C
B
A
7 6 5 4
D
IN
ININ
OUTOUT
IN
IN
ININ
ININ
IN
BI
OUTOUT
OUT
IN OUT
ININ
IN
BI
BI
BI
BI
IN
OUT
C16C15C14
R30
C



20210728 MODIFY FOR GT
Fri Aug 25 14:01:06 2023N/AN/AN/AN/AV0587 OF 312P12V_S3_AUX_CPU0_NVDIMMP3V3_AUXP12V_S3_AUX_CPU0_NVDIMM
P3V3_AUXDDR5 - CPU0 CHC DIMM2(BLACK)
2298283848586888987129868889228622982838485868889114222286 22 8622 8622 8622 862222222222228622 86228622222286
87
22862286 22 86
10%16V10UFPLACE THE BYPASS CAPS CLOSE TO DIMMI3C_SPD_DDRABCD_CPU0_LVC1_SDAPD_CHC_CPU0_DIMM2_SAAI3C_SPD_DDRABCD_CPU0_LVC1_SCL_R6RST_M_CD_CPU0_FPGA_NM_C_CPU0_ALERT_NI3C_SPD_DDRABCD_CPU0_LVC1_SCL49.9CHIPTP_CHC_CPU0_DIMM2_FRU_5TP_CHC_CPU0_DIMM2_FRU_6PWRGD_CHC_CPU0_DIMM2M_C_CPU0_SA_CS_N<3>M_C_CPU0_SB_PARM_C_CPU0_SA_DQS_DN<9:0>M_C_CPU0_SA_DQS_DP<9:0>M_C_CPU0_SB_DQS_DN<9:0>M_C_CPU0_SB_DQS_DP<9:0>TP_CHC_CPU0_DIMM2_FRU_4TP_CHC_CPU0_DIMM2_FRU_3TP_CHC_CPU0_DIMM2_FRU_2TP_CHC_CPU0_DIMM2_FRU_1TP_CHC_CPU0_DIMM2_FRU_0
SCONN288_ADR50017-P087CCSMLFSMLFSCONN288_ADR50017-P087CCSMLFM_C_CPU0_SA_CS_N<2>M_C_CPU0_SB_CS_N<3>M_C_CPU0_SB_CS_N<2>M_C_CPU0_CLK_DP<1>M_C_CPU0_CLK_DN<1>M_C_CPU0_SA_CB<7:0>M_C_CPU0_SB_DQ<31:0>M_C_CPU0_SB_CB<7:0>IO
M_C_CPU0_SA_RSP<1>M_C_CPU0_SB_RSP<1>M_C_CPU0_SA_PARIOSCONN288_ADR50017-P087CCIO
1%1/16WCHIP0402LF84.5KX6S16VC080510UF10%X6SC0805PD_CHC_CPU0_DIMM2_SAA
M_C_CPU0_SB_CA<6:0>M_C_CPU0_SA_CA<6:0> M_C_CPU0_SA_DQ<31:0>
C04022.2UF20%X6S6.3V
DQS7_A_c||TDQS7_A_c
DQS6_A_t||TDQS6_A_t
DQS8_B_t||TDQS8_B_t
DQS8_B_c||TDQS8_B_c
DQS7_B_t||TDQS7_B_t
DQS0_A_c
DQS0_A_t
DQS0_B_c
DQS0_B_t
DQS1_A_c
DQS1_A_t
DQS1_B_c
DQS1_B_t
DQS2_A_c
DQS2_A_t
DQS2_B_c
DQS2_B_t
DQS3_A_c
DQS3_A_t
DQS3_B_c
DQS3_B_t
DQS4_A_c
DQS4_A_t
DQS4_B_c
DQS4_B_t
DQS5_A_c||TDQS5_A_c||DQS5_A_t||TDQS5_A_t
DQS5_A_t||TDQS5_A_t
DQS5_B_c||TDQS5_B_c
DQS5_B_t||TDQS5_B_t
DQS6_A_c||TDQS6_A_c||DQS6_A_t||TDQS6_A_t
DQS6_B_c||TDQS6_B_c
DQS6_B_t||TDQS6_B_t
DQS7_A_t||TDQS7_A_t
DQS7_B_c||TDQS7_B_c
DQS8_A_c||TDQS8_A_c
DQS8_A_t||TDQS8_A_t
DQS9_A_c||TDQS9_A_c
DQS9_A_t||TDQS9_A_t
DQS9_B_c||TDQS9_B_c
DQS9_B_t||TDQS9_B_t||DBI4_B_n
R3880
93
94
201
200
283
282
190
189
272
271
179
178
261
260
168
167
250
249
157
156
239
238
55
56
137
138
44
45
126
127
33
34
115
116
22
23
104
105
11
12
288
286
284
281
279
277
275
273
270
268
266
264
262
259
257
255
253
251
248
246
244
242
240
237
235
233
230
228
226
224
222
219
216
214
212
210
208
206
204
202
199
197
195
193
191
188
186
184
182
180
177
175
173
171
169
166
164
162
160
158
155
153
151
143
141
139
136
134
132
130
128
125
123
121
119
117
114
112
110
108
106
103
101
99
97
95
92
90
88
85
83
81
79
77
75
73
71
69
67
65
63
61
59
57
54
52
50
48
46
43
41
39
37
35
32
30
28
26
24
21
19
17
15
13
10
8
6
146
145
1
G3
G2
G1
3
232
231
220
150
149
144
2
207
147
227
74
87
86
5
4
148
287
194
285
192
142
49
140
47
280
187
278
185
135
42
133
40
276
183
274
181
131
38
129
36
269
176
267
174
124
31
122
29
265
172
263
170
120
27
118
25
258
165
256
163
113
20
111
18
254
161
252
159
109
16
107
14
247
154
245
152
102
9
100
7
229
209
84
64
217
218
236
205
234
203
91
60
89
58
243
198
241
196
98
53
96
51
82
72
225
215
80
70
223
213
78
68
221
211
76
66
62
9
8
6
7
5
4
3
1
2
0
9
8
7
5
6
4
3
2
0
1
9
8
7
6
5
4
3
2
1
0
9
8
7
6
5
4
3
2
1
0
0
31
4
5
7
11
22
10
20
18
19
16
17
15
13
14
12
8
9
7
6
5
4
2
3
1
0
30
29
28
26
27
25
24
23
21
22
20
19
17
18
15
16
14
13
12
10
11
9
8
7
5
6
3
4
2
0
1
5
3
4
6
1
2
6
5
3
1
0
2
7
6
3
4
2
0
1
31
30
29
28
27
25
26
6
5
2
3
4
0
1
23
24
21
J6
J6J6
1/3
DQ31_A
CB7_A
CB4_A
CB1_A
CB7_B
ALERT_n
CA0_A
CA0_B
CA1_A
CA1_B
CA2_A
CA2_B
CA3_A
CA3_B
CA4_A
CA4_B
CA5_A
CA5_B
CA6_A
CA6_B
CB6_A
CB5_A
CB3_A
CB2_A
CB0_A
CB6_B
CB5_B
CB4_B
CB3_B
CB2_B
CB1_B
CB0_B
CK_c
CK_t
CS0_A_n
CS0_B_n
CS1_A_n
CS1_B_n
DQ30_A
DQ29_A
DQ28_A
DQ27_A
DQ26_A
DQ25_A
DQ24_A
DQ23_A
DQ22_A
DQ21_A
DQ20_A
DQ19_A
DQ18_A
DQ17_A
DQ16_A
DQ15_A
DQ14_A
DQ13_A
DQ12_A
DQ11_A
DQ10_A
DQ9_A
DQ8_A
DQ7_A
DQ6_A
DQ5_A
DQ4_A
DQ3_A
DQ2_A
DQ1_A
DQ0_A
DQ31_B
DQ30_B
DQ29_B
DQ28_B
DQ27_B
DQ26_B
DQ25_B
DQ24_B
DQ23_B
DQ22_B
DQ21_B
DQ20_B
DQ19_B
DQ18_B
DQ17_B
DQ16_B
DQ15_B
DQ14_B
DQ13_B
DQ12_B
DQ11_B
DQ10_B
DQ9_B
DQ8_B
DQ7_B
DQ6_B
DQ5_B
DQ4_B
DQ3_B
DQ2_B
DQ1_B
DQ0_B
HSA
HSCL
HSDA
LBD||RSP_A_n
LBS||RSP_B_n
PAR_A
PAR_B
PWR_GOOD||FAIL_n
RESET_n
RFU6
RFU5
RFU4
RFU3
RFU2
RFU1
RFU0
VIN_MGMT
2/3 3/3
G3
G2
G1
VSS62
VSS61
VSS60
VSS58
VSS104
VSS102
VSS100
VIN_BULK2
VIN_BULK1
VIN_BULK0
VSS126
VSS125
VSS124
VSS123
VSS122
VSS121
VSS120
VSS119
VSS118
VSS117
VSS116
VSS115
VSS114
VSS113
VSS112
VSS111
VSS110
VSS109
VSS108
VSS107
VSS106
VSS105
VSS103
VSS101
VSS99
VSS98
VSS97
VSS96
VSS95
VSS94
VSS93
VSS92
VSS91
VSS90
VSS89
VSS88
VSS87
VSS86
VSS85
VSS84
VSS83
VSS82
VSS81
VSS80
VSS79
VSS78
VSS77
VSS76
VSS75
VSS74
VSS73
VSS72
VSS71
VSS70
VSS69
VSS68
VSS67
VSS66
VSS65
VSS64
VSS63
VSS59
VSS57
VSS56
VSS55
VSS54
VSS53
VSS52
VSS51
VSS50
VSS49
VSS48
VSS47
VSS46
VSS45
VSS44
VSS43
VSS42
VSS41
VSS40
VSS39
VSS38
VSS37
VSS36
VSS35
VSS34
VSS33
VSS32
VSS31
VSS30
VSS29
VSS28
VSS27
VSS26
VSS25
VSS24
VSS23
VSS22
VSS21
VSS20
VSS19
VSS18
VSS17
VSS16
VSS15
VSS14
VSS13
VSS12
VSS11
VSS10
VSS9
VSS8
VSS7
VSS6
VSS5
VSS4
VSS3
VSS2
VSS1
VSS0
21
2
1
2
1
2
1
2
1
CAD NOTE:
SHEETDATE
DEPARTMENT
SIZE
PROJECT DOCUMENT NUMBER REV
REVIEWER
DESIGNER
123
7 3 2 1 6 5 4
E
A
B
C
E
D
C
B
A
7 6 5 4
D
BI
IN
IN
ININ
OUTOUT
IN
IN
IN
BI
OUTOUT
IN
BI
OUTOUT
ININ
ININ
BI
ININ
IN
BI
OUT
C19C18C17
R31
C



20210728 MODIFY FOR GT
Fri Aug 25 14:01:07 2023N/AN/AN/AN/AV0588 OF 312
P3V3_AUXP12V_S3_AUX_CPU0_NVDIMM
P3V3_AUX P12V_S3_AUX_CPU0_NVDIMMDDR5 - CPU0 CHD DIMM1(YELLOW)
129868789229828384858687898823892298283848586878911423 8923 8923 8923 892323 892389238988
2389238923 892389238923232323232323I3C_SPD_DDRABCD_CPU0_LVC1_SCL_R7RST_M_CD_CPU0_FPGA_NI3C_SPD_DDRABCD_CPU0_LVC1_SDAPD_CHD_CPU0_DIMM1_SAAM_D_CPU0_ALERT_N49.9I3C_SPD_DDRABCD_CPU0_LVC1_SCLPWRGD_CHD_CPU0_DIMM1M_D_CPU0_SA_DQS_DN<9:0>M_D_CPU0_SA_DQS_DP<9:0>M_D_CPU0_SB_DQS_DP<9:0>M_D_CPU0_SB_DQS_DN<9:0>M_D_CPU0_CLK_DP<0>CHIP
SMLFSCONN288_ADR50017-P130CCIOIOSMLFSMLFSCONN288_ADR50017-P130CCM_D_CPU0_SA_DQ<31:0>
C040220%2.2UFX6S6.3VPLACE THE BYPASS CAPS CLOSE TO DIMM
M_D_CPU0_SA_CB<7:0>M_D_CPU0_SB_CB<7:0>PD_CHD_CPU0_DIMM1_SAA16V10UF10%C0805X6S16V10%10UFC0805X6S127K1%CHIP0402LF
M_D_CPU0_SA_CA<6:0>M_D_CPU0_SB_CA<6:0>
1/16WM_D_CPU0_SB_DQ<31:0>IO
TP_CHD_CPU0_DIMM1_FRU_0TP_CHD_CPU0_DIMM1_FRU_1TP_CHD_CPU0_DIMM1_FRU_2TP_CHD_CPU0_DIMM1_FRU_3TP_CHD_CPU0_DIMM1_FRU_5TP_CHD_CPU0_DIMM1_FRU_6M_D_CPU0_SB_PARM_D_CPU0_SA_PARM_D_CPU0_SB_RSP<0>M_D_CPU0_SA_RSP<0>M_D_CPU0_SB_CS_N<1>M_D_CPU0_SA_CS_N<1>M_D_CPU0_SB_CS_N<0>M_D_CPU0_SA_CS_N<0>M_D_CPU0_CLK_DN<0>TP_CHD_CPU0_DIMM1_FRU_4
SCONN288_ADR50017-P130CC
DQS7_A_c||TDQS7_A_c
DQS6_A_t||TDQS6_A_t
DQS8_B_t||TDQS8_B_t
DQS8_B_c||TDQS8_B_c
DQS7_B_t||TDQS7_B_t
DQS0_A_c
DQS0_A_t
DQS0_B_c
DQS0_B_t
DQS1_A_c
DQS1_A_t
DQS1_B_c
DQS1_B_t
DQS2_A_c
DQS2_A_t
DQS2_B_c
DQS2_B_t
DQS3_A_c
DQS3_A_t
DQS3_B_c
DQS3_B_t
DQS4_A_c
DQS4_A_t
DQS4_B_c
DQS4_B_t
DQS5_A_c||TDQS5_A_c||DQS5_A_t||TDQS5_A_t
DQS5_A_t||TDQS5_A_t
DQS5_B_c||TDQS5_B_c
DQS5_B_t||TDQS5_B_t
DQS6_A_c||TDQS6_A_c||DQS6_A_t||TDQS6_A_t
DQS6_B_c||TDQS6_B_c
DQS6_B_t||TDQS6_B_t
DQS7_A_t||TDQS7_A_t
DQS7_B_c||TDQS7_B_c
DQS8_A_c||TDQS8_A_c
DQS8_A_t||TDQS8_A_t
DQS9_A_c||TDQS9_A_c
DQS9_A_t||TDQS9_A_t
DQS9_B_c||TDQS9_B_c
DQS9_B_t||TDQS9_B_t||DBI4_B_n
R3881
93
94
201
200
283
282
190
189
272
271
179
178
261
260
168
167
250
249
157
156
239
238
55
56
137
138
44
45
126
127
33
34
115
116
22
23
104
105
11
12
288
286
284
281
279
277
275
273
270
268
266
264
262
259
257
255
253
251
248
246
244
242
240
237
235
233
230
228
226
224
222
219
216
214
212
210
208
206
204
202
199
197
195
193
191
188
186
184
182
180
177
175
173
171
169
166
164
162
160
158
155
153
151
143
141
139
136
134
132
130
128
125
123
121
119
117
114
112
110
108
106
103
101
99
97
95
92
90
88
85
83
81
79
77
75
73
71
69
67
65
63
61
59
57
54
52
50
48
46
43
41
39
37
35
32
30
28
26
24
21
19
17
15
13
10
8
6
146
145
1
G3
G2
G1
3
232
231
220
150
149
144
2
207
147
227
74
87
86
5
4
148
287
194
285
192
142
49
140
47
280
187
278
185
135
42
133
40
276
183
274
181
131
38
129
36
269
176
267
174
124
31
122
29
265
172
263
170
120
27
118
25
258
165
256
163
113
20
111
18
254
161
252
159
109
16
107
14
247
154
245
152
102
9
100
7
229
209
84
64
217
218
236
205
234
203
91
60
89
58
243
198
241
196
98
53
96
51
82
72
225
215
80
70
223
213
78
68
221
211
76
66
62
4
9
8
7
6
5
4
3
2
1
0
9
8
7
6
5
3
2
1
0
9
8
7
6
5
4
3
2
1
0
9
8
7
6
5
4
3
2
1
0
28
29
27
26
25
7
21
17
16
19
18
20
22
21
23
24
6
5
31
30
1
3
2
4
5
6
7
0
2
1
3
5
4
6
7
0
2
1
4
5
6
1
0
2
4
3
1
0
2
4
3
5
6
7
8
9
11
10
12
13
14
15
16
17
18
19
20
23
24
25
27
26
28
29
31
0
1
2
3
4
5
6
8
9
10
11
12
14
13
3
22
30
0
15
J7 J7J7
2/3 3/3
G3
G2
G1
VSS62
VSS61
VSS60
VSS58
VSS104
VSS102
VSS100
VIN_BULK2
VIN_BULK1
VIN_BULK0
VSS126
VSS125
VSS124
VSS123
VSS122
VSS121
VSS120
VSS119
VSS118
VSS117
VSS116
VSS115
VSS114
VSS113
VSS112
VSS111
VSS110
VSS109
VSS108
VSS107
VSS106
VSS105
VSS103
VSS101
VSS99
VSS98
VSS97
VSS96
VSS95
VSS94
VSS93
VSS92
VSS91
VSS90
VSS89
VSS88
VSS87
VSS86
VSS85
VSS84
VSS83
VSS82
VSS81
VSS80
VSS79
VSS78
VSS77
VSS76
VSS75
VSS74
VSS73
VSS72
VSS71
VSS70
VSS69
VSS68
VSS67
VSS66
VSS65
VSS64
VSS63
VSS59
VSS57
VSS56
VSS55
VSS54
VSS53
VSS52
VSS51
VSS50
VSS49
VSS48
VSS47
VSS46
VSS45
VSS44
VSS43
VSS42
VSS41
VSS40
VSS39
VSS38
VSS37
VSS36
VSS35
VSS34
VSS33
VSS32
VSS31
VSS30
VSS29
VSS28
VSS27
VSS26
VSS25
VSS24
VSS23
VSS22
VSS21
VSS20
VSS19
VSS18
VSS17
VSS16
VSS15
VSS14
VSS13
VSS12
VSS11
VSS10
VSS9
VSS8
VSS7
VSS6
VSS5
VSS4
VSS3
VSS2
VSS1
VSS0
1/3
DQ31_A
CB7_A
CB4_A
CB1_A
CB7_B
ALERT_n
CA0_A
CA0_B
CA1_A
CA1_B
CA2_A
CA2_B
CA3_A
CA3_B
CA4_A
CA4_B
CA5_A
CA5_B
CA6_A
CA6_B
CB6_A
CB5_A
CB3_A
CB2_A
CB0_A
CB6_B
CB5_B
CB4_B
CB3_B
CB2_B
CB1_B
CB0_B
CK_c
CK_t
CS0_A_n
CS0_B_n
CS1_A_n
CS1_B_n
DQ30_A
DQ29_A
DQ28_A
DQ27_A
DQ26_A
DQ25_A
DQ24_A
DQ23_A
DQ22_A
DQ21_A
DQ20_A
DQ19_A
DQ18_A
DQ17_A
DQ16_A
DQ15_A
DQ14_A
DQ13_A
DQ12_A
DQ11_A
DQ10_A
DQ9_A
DQ8_A
DQ7_A
DQ6_A
DQ5_A
DQ4_A
DQ3_A
DQ2_A
DQ1_A
DQ0_A
DQ31_B
DQ30_B
DQ29_B
DQ28_B
DQ27_B
DQ26_B
DQ25_B
DQ24_B
DQ23_B
DQ22_B
DQ21_B
DQ20_B
DQ19_B
DQ18_B
DQ17_B
DQ16_B
DQ15_B
DQ14_B
DQ13_B
DQ12_B
DQ11_B
DQ10_B
DQ9_B
DQ8_B
DQ7_B
DQ6_B
DQ5_B
DQ4_B
DQ3_B
DQ2_B
DQ1_B
DQ0_B
HSA
HSCL
HSDA
LBD||RSP_A_n
LBS||RSP_B_n
PAR_A
PAR_B
PWR_GOOD||FAIL_n
RESET_n
RFU6
RFU5
RFU4
RFU3
RFU2
RFU1
RFU0
VIN_MGMT
21
2
1
2
1
2
1
2
1
CAD NOTE:
SHEETDATE
DEPARTMENT
SIZE
PROJECT DOCUMENT NUMBER REV
REVIEWER
DESIGNER
123
7 3 2 1 6 5 4
E
A
B
C
E
D
C
B
A
7 6 5 4
D
ININ
IN
OUTOUT
OUT
IN
ININ
ININ
IN
ININ
IN
BI
OUTOUT
OUT
IN
OUT
BI
BI
BIIN
BI
IN
C22C21C20
R32
C



20210728 MODIFY FOR GT
Fri Aug 25 14:01:08 2023N/AN/AN/AN/AV0589 OF 312
P3V3_AUXP3V3_AUX P12V_S3_AUX_CPU0_NVDIMM
P12V_S3_AUX_CPU0_NVDIMM
DDR5 - CPU0 CHD DIMM2(BLACK)
2298283848586878889238812986878823882298283848586878811423 8823 8823 8823 8823 8823232323232323232388238823 88238823882388
89I3C_SPD_DDRABCD_CPU0_LVC1_SCL_R8I3C_SPD_DDRABCD_CPU0_LVC1_SDAPD_CHD_CPU0_DIMM2_SAAM_D_CPU0_ALERT_NRST_M_CD_CPU0_FPGA_NM_D_CPU0_SB_CB<7:0>I3C_SPD_DDRABCD_CPU0_LVC1_SCLPWRGD_CHD_CPU0_DIMM2TP_CHD_CPU0_DIMM2_FRU_6CHIPM_D_CPU0_SA_DQS_DP<9:0>M_D_CPU0_SA_DQS_DN<9:0>M_D_CPU0_SB_DQS_DN<9:0>M_D_CPU0_SB_DQS_DP<9:0>49.9TP_CHD_CPU0_DIMM2_FRU_5TP_CHD_CPU0_DIMM2_FRU_4
SCONN288_ADR50017-P087CCSMLFSMLFSCONN288_ADR50017-P087CCSCONN288_ADR50017-P087CCM_D_CPU0_SB_DQ<31:0>M_D_CPU0_CLK_DN<1>M_D_CPU0_CLK_DP<1>M_D_CPU0_SA_CS_N<2>M_D_CPU0_SB_CS_N<2>M_D_CPU0_SA_CS_N<3>M_D_CPU0_SB_CS_N<3>M_D_CPU0_SA_RSP<1>M_D_CPU0_SB_RSP<1>M_D_CPU0_SA_PARM_D_CPU0_SB_PARTP_CHD_CPU0_DIMM2_FRU_3TP_CHD_CPU0_DIMM2_FRU_2TP_CHD_CPU0_DIMM2_FRU_1TP_CHD_CPU0_DIMM2_FRU_0
IO SMLFIOIO
196K0402LFCHIP1%1/16W6.3VX6S2.2UF20%
M_D_CPU0_SA_DQ<31:0>M_D_CPU0_SA_CB<7:0>M_D_CPU0_SA_CA<6:0>M_D_CPU0_SB_CA<6:0>
PD_CHD_CPU0_DIMM2_SAAPLACE THE BYPASS CAPS CLOSE TO DIMMC040216VC080510%10UFX6S16VX6SC080510UF10%
DQS7_A_c||TDQS7_A_c
DQS6_A_t||TDQS6_A_t
DQS8_B_t||TDQS8_B_t
DQS8_B_c||TDQS8_B_c
DQS7_B_t||TDQS7_B_t
DQS0_A_c
DQS0_A_t
DQS0_B_c
DQS0_B_t
DQS1_A_c
DQS1_A_t
DQS1_B_c
DQS1_B_t
DQS2_A_c
DQS2_A_t
DQS2_B_c
DQS2_B_t
DQS3_A_c
DQS3_A_t
DQS3_B_c
DQS3_B_t
DQS4_A_c
DQS4_A_t
DQS4_B_c
DQS4_B_t
DQS5_A_c||TDQS5_A_c||DQS5_A_t||TDQS5_A_t
DQS5_A_t||TDQS5_A_t
DQS5_B_c||TDQS5_B_c
DQS5_B_t||TDQS5_B_t
DQS6_A_c||TDQS6_A_c||DQS6_A_t||TDQS6_A_t
DQS6_B_c||TDQS6_B_c
DQS6_B_t||TDQS6_B_t
DQS7_A_t||TDQS7_A_t
DQS7_B_c||TDQS7_B_c
DQS8_A_c||TDQS8_A_c
DQS8_A_t||TDQS8_A_t
DQS9_A_c||TDQS9_A_c
DQS9_A_t||TDQS9_A_t
DQS9_B_c||TDQS9_B_c
DQS9_B_t||TDQS9_B_t||DBI4_B_n
R3882
93
94
201
200
283
282
190
189
272
271
179
178
261
260
168
167
250
249
157
156
239
238
55
56
137
138
44
45
126
127
33
34
115
116
22
23
104
105
11
12
288
286
284
281
279
277
275
273
270
268
266
264
262
259
257
255
253
251
248
246
244
242
240
237
235
233
230
228
226
224
222
219
216
214
212
210
208
206
204
202
199
197
195
193
191
188
186
184
182
180
177
175
173
171
169
166
164
162
160
158
155
153
151
143
141
139
136
134
132
130
128
125
123
121
119
117
114
112
110
108
106
103
101
99
97
95
92
90
88
85
83
81
79
77
75
73
71
69
67
65
63
61
59
57
54
52
50
48
46
43
41
39
37
35
32
30
28
26
24
21
19
17
15
13
10
8
6
146
145
1
G3
G2
G1
3
232
231
220
150
149
144
2
207
147
227
74
87
86
5
4
148
287
194
285
192
142
49
140
47
280
187
278
185
135
42
133
40
276
183
274
181
131
38
129
36
269
176
267
174
124
31
122
29
265
172
263
170
120
27
118
25
258
165
256
163
113
20
111
18
254
161
252
159
109
16
107
14
247
154
245
152
102
9
100
7
229
209
84
64
217
218
236
205
234
203
91
60
89
58
243
198
241
196
98
53
96
51
82
72
225
215
80
70
223
213
78
68
221
211
76
66
62
1
9
8
6
7
5
4
3
1
2
0
9
8
7
6
5
4
3
2
0
9
8
0
1
2
3
4
5
6
7
8
9
0
1
2
3
4
5
6
7
30
31
5
13
16
7
12
17
18
19
20
21
22
23
25
24
26
27
28
4
6
29
30
31
0
1
2
3
4
5
6
0
1
2
3
4
5
6
7
0
1
2
3
4
6
5
0
1
3
2
0
1
3
2
4
5
6
8
7
9
10
11
12
13
14
15
17
16
18
19
20
21
22
23
24
26
25
27
28
29
0
2
1
3
4
5
7
6
8
9
10
11
14
15
J8
J8J8
1/3
DQ31_A
CB7_A
CB4_A
CB1_A
CB7_B
ALERT_n
CA0_A
CA0_B
CA1_A
CA1_B
CA2_A
CA2_B
CA3_A
CA3_B
CA4_A
CA4_B
CA5_A
CA5_B
CA6_A
CA6_B
CB6_A
CB5_A
CB3_A
CB2_A
CB0_A
CB6_B
CB5_B
CB4_B
CB3_B
CB2_B
CB1_B
CB0_B
CK_c
CK_t
CS0_A_n
CS0_B_n
CS1_A_n
CS1_B_n
DQ30_A
DQ29_A
DQ28_A
DQ27_A
DQ26_A
DQ25_A
DQ24_A
DQ23_A
DQ22_A
DQ21_A
DQ20_A
DQ19_A
DQ18_A
DQ17_A
DQ16_A
DQ15_A
DQ14_A
DQ13_A
DQ12_A
DQ11_A
DQ10_A
DQ9_A
DQ8_A
DQ7_A
DQ6_A
DQ5_A
DQ4_A
DQ3_A
DQ2_A
DQ1_A
DQ0_A
DQ31_B
DQ30_B
DQ29_B
DQ28_B
DQ27_B
DQ26_B
DQ25_B
DQ24_B
DQ23_B
DQ22_B
DQ21_B
DQ20_B
DQ19_B
DQ18_B
DQ17_B
DQ16_B
DQ15_B
DQ14_B
DQ13_B
DQ12_B
DQ11_B
DQ10_B
DQ9_B
DQ8_B
DQ7_B
DQ6_B
DQ5_B
DQ4_B
DQ3_B
DQ2_B
DQ1_B
DQ0_B
HSA
HSCL
HSDA
LBD||RSP_A_n
LBS||RSP_B_n
PAR_A
PAR_B
PWR_GOOD||FAIL_n
RESET_n
RFU6
RFU5
RFU4
RFU3
RFU2
RFU1
RFU0
VIN_MGMT
2/3 3/3
G3
G2
G1
VSS62
VSS61
VSS60
VSS58
VSS104
VSS102
VSS100
VIN_BULK2
VIN_BULK1
VIN_BULK0
VSS126
VSS125
VSS124
VSS123
VSS122
VSS121
VSS120
VSS119
VSS118
VSS117
VSS116
VSS115
VSS114
VSS113
VSS112
VSS111
VSS110
VSS109
VSS108
VSS107
VSS106
VSS105
VSS103
VSS101
VSS99
VSS98
VSS97
VSS96
VSS95
VSS94
VSS93
VSS92
VSS91
VSS90
VSS89
VSS88
VSS87
VSS86
VSS85
VSS84
VSS83
VSS82
VSS81
VSS80
VSS79
VSS78
VSS77
VSS76
VSS75
VSS74
VSS73
VSS72
VSS71
VSS70
VSS69
VSS68
VSS67
VSS66
VSS65
VSS64
VSS63
VSS59
VSS57
VSS56
VSS55
VSS54
VSS53
VSS52
VSS51
VSS50
VSS49
VSS48
VSS47
VSS46
VSS45
VSS44
VSS43
VSS42
VSS41
VSS40
VSS39
VSS38
VSS37
VSS36
VSS35
VSS34
VSS33
VSS32
VSS31
VSS30
VSS29
VSS28
VSS27
VSS26
VSS25
VSS24
VSS23
VSS22
VSS21
VSS20
VSS19
VSS18
VSS17
VSS16
VSS15
VSS14
VSS13
VSS12
VSS11
VSS10
VSS9
VSS8
VSS7
VSS6
VSS5
VSS4
VSS3
VSS2
VSS1
VSS0
21
2
1
2
1
2
1
2
1
CAD NOTE:
SHEETDATE
DEPARTMENT
SIZE
PROJECT DOCUMENT NUMBER REV
REVIEWER
DESIGNER
123
7 3 2 1 6 5 4
E
A
B
C
E
D
C
B
A
7 6 5 4
D
IN
ININ
OUTOUT
OUT
IN
ININ
ININ
IN
IN
BI
OUTOUT
IN
BI
OUTOUT
ININ
BI
BI
BI
IN
IN
C25C24C23
R33
C



20210728 MODIFY FOR GT
N/AN/AN/AN/A V0590 OF 312Fri Aug 25 14:01:09 2023
P3V3_AUXP12V_S3_AUX_CPU0_NVDIMM
P12V_S3_AUX_CPU0_NVDIMMP3V3_AUXDDR5 - CPU0 CHE DIMM1(YELLOW)114229919293949596972299192939495969790129919293249124 249124912491249124912491249124249124912424242424242491
90
24912491
TP_CHE_CPU0_DIMM1_FRU_0TP_CHE_CPU0_DIMM1_FRU_1TP_CHE_CPU0_DIMM1_FRU_2TP_CHE_CPU0_DIMM1_FRU_3TP_CHE_CPU0_DIMM1_FRU_4TP_CHE_CPU0_DIMM1_FRU_5TP_CHE_CPU0_DIMM1_FRU_6PWRGD_CHE_CPU0_DIMM1I3C_SPD_DDREFGH_CPU0_LVC1_SCLI3C_SPD_DDREFGH_CPU0_LVC1_SCL_R1I3C_SPD_DDREFGH_CPU0_LVC1_SDA49.9CHIPPD_CHE_CPU0_DIMM1_SAARST_M_EF_CPU0_FPGA_NM_E_CPU0_ALERT_NM_E_CPU0_CLK_DN<0>M_E_CPU0_SA_DQS_DN<9:0>M_E_CPU0_SA_DQS_DP<9:0>M_E_CPU0_SB_DQS_DP<9:0>M_E_CPU0_SB_DQS_DN<9:0>M_E_CPU0_SA_DQ<31:0>M_E_CPU0_SB_DQ<31:0>M_E_CPU0_SB_CB<7:0>M_E_CPU0_CLK_DP<0>M_E_CPU0_SA_CB<7:0>SCONN288_ADR50017-P130CCM_E_CPU0_SA_PARSMLFSCONN288_ADR50017-P130CC SCONN288_ADR50017-P130CCSMLFSMLFIOIOM_E_CPU0_SA_CS_N<0>M_E_CPU0_SB_CS_N<0>M_E_CPU0_SA_CS_N<1>M_E_CPU0_SB_CS_N<1>M_E_CPU0_SA_RSP<0>M_E_CPU0_SB_RSP<0>M_E_CPU0_SB_PARIO
1/16WCHIP10K0402LF1%X6S10UF16V10%C0805X6S10%10UF16VC0805PD_CHE_CPU0_DIMM1_SAA
M_E_CPU0_SB_CA<6:0>M_E_CPU0_SA_CA<6:0>
PLACE THE BYPASS CAPS CLOSE TO DIMM6.3VX6S2.2UF20%C0402
DQS7_A_c||TDQS7_A_c
DQS6_A_t||TDQS6_A_t
DQS8_B_t||TDQS8_B_t
DQS8_B_c||TDQS8_B_c
DQS7_B_t||TDQS7_B_t
DQS0_A_c
DQS0_A_t
DQS0_B_c
DQS0_B_t
DQS1_A_c
DQS1_A_t
DQS1_B_c
DQS1_B_t
DQS2_A_c
DQS2_A_t
DQS2_B_c
DQS2_B_t
DQS3_A_c
DQS3_A_t
DQS3_B_c
DQS3_B_t
DQS4_A_c
DQS4_A_t
DQS4_B_c
DQS4_B_t
DQS5_A_c||TDQS5_A_c||DQS5_A_t||TDQS5_A_t
DQS5_A_t||TDQS5_A_t
DQS5_B_c||TDQS5_B_c
DQS5_B_t||TDQS5_B_t
DQS6_A_c||TDQS6_A_c||DQS6_A_t||TDQS6_A_t
DQS6_B_c||TDQS6_B_c
DQS6_B_t||TDQS6_B_t
DQS7_A_t||TDQS7_A_t
DQS7_B_c||TDQS7_B_c
DQS8_A_c||TDQS8_A_c
DQS8_A_t||TDQS8_A_t
DQS9_A_c||TDQS9_A_c
DQS9_A_t||TDQS9_A_t
DQS9_B_c||TDQS9_B_c
DQS9_B_t||TDQS9_B_t||DBI4_B_n
R3883
93
94
201
200
283
282
190
189
272
271
179
178
261
260
168
167
250
249
157
156
239
238
55
56
137
138
44
45
126
127
33
34
115
116
22
23
104
105
11
12
288
286
284
281
279
277
275
273
270
268
266
264
262
259
257
255
253
251
248
246
244
242
240
237
235
233
230
228
226
224
222
219
216
214
212
210
208
206
204
202
199
197
195
193
191
188
186
184
182
180
177
175
173
171
169
166
164
162
160
158
155
153
151
143
141
139
136
134
132
130
128
125
123
121
119
117
114
112
110
108
106
103
101
99
97
95
92
90
88
85
83
81
79
77
75
73
71
69
67
65
63
61
59
57
54
52
50
48
46
43
41
39
37
35
32
30
28
26
24
21
19
17
15
13
10
8
6
146
145
1
G3
G2
G1
3
232
231
220
150
149
144
2
207
147
227
74
87
86
5
4
148
287
194
285
192
142
49
140
47
280
187
278
185
135
42
133
40
276
183
274
181
131
38
129
36
269
176
267
174
124
31
122
29
265
172
263
170
120
27
118
25
258
165
256
163
113
20
111
18
254
161
252
159
109
16
107
14
247
154
245
152
102
9
100
7
229
209
84
64
217
218
236
205
234
203
91
60
89
58
243
198
241
196
98
53
96
51
82
72
225
215
80
70
223
213
78
68
221
211
76
66
62
9
8
7
6
5
4
3
2
1
0
9
8
7
6
5
4
3
2
1
0
9
8
7
6
5
4
3
2
1
0
9
8
7
6
5
4
3
2
1
0
28
0
23
1
19
18
9
7
6
30
6
14
9
15
16
12
14
13
10
11
8
5
4
3
2
1
0
31
29
27
26
25
22
24
23
20
21
19
18
17
16
15
13
12
11
10
8
7
4
5
2
3
1
0
0
1
5
6
3
4
2
0
6
7
5
4
3
2
1
7
5
6
4
3
2
0
1
31
30
28
27
29
5
6
4
3
2
26
25
24
22
21
20
17
J9 J9J9
2/3 3/3
G3
G2
G1
VSS62
VSS61
VSS60
VSS58
VSS104
VSS102
VSS100
VIN_BULK2
VIN_BULK1
VIN_BULK0
VSS126
VSS125
VSS124
VSS123
VSS122
VSS121
VSS120
VSS119
VSS118
VSS117
VSS116
VSS115
VSS114
VSS113
VSS112
VSS111
VSS110
VSS109
VSS108
VSS107
VSS106
VSS105
VSS103
VSS101
VSS99
VSS98
VSS97
VSS96
VSS95
VSS94
VSS93
VSS92
VSS91
VSS90
VSS89
VSS88
VSS87
VSS86
VSS85
VSS84
VSS83
VSS82
VSS81
VSS80
VSS79
VSS78
VSS77
VSS76
VSS75
VSS74
VSS73
VSS72
VSS71
VSS70
VSS69
VSS68
VSS67
VSS66
VSS65
VSS64
VSS63
VSS59
VSS57
VSS56
VSS55
VSS54
VSS53
VSS52
VSS51
VSS50
VSS49
VSS48
VSS47
VSS46
VSS45
VSS44
VSS43
VSS42
VSS41
VSS40
VSS39
VSS38
VSS37
VSS36
VSS35
VSS34
VSS33
VSS32
VSS31
VSS30
VSS29
VSS28
VSS27
VSS26
VSS25
VSS24
VSS23
VSS22
VSS21
VSS20
VSS19
VSS18
VSS17
VSS16
VSS15
VSS14
VSS13
VSS12
VSS11
VSS10
VSS9
VSS8
VSS7
VSS6
VSS5
VSS4
VSS3
VSS2
VSS1
VSS0
1/3
DQ31_A
CB7_A
CB4_A
CB1_A
CB7_B
ALERT_n
CA0_A
CA0_B
CA1_A
CA1_B
CA2_A
CA2_B
CA3_A
CA3_B
CA4_A
CA4_B
CA5_A
CA5_B
CA6_A
CA6_B
CB6_A
CB5_A
CB3_A
CB2_A
CB0_A
CB6_B
CB5_B
CB4_B
CB3_B
CB2_B
CB1_B
CB0_B
CK_c
CK_t
CS0_A_n
CS0_B_n
CS1_A_n
CS1_B_n
DQ30_A
DQ29_A
DQ28_A
DQ27_A
DQ26_A
DQ25_A
DQ24_A
DQ23_A
DQ22_A
DQ21_A
DQ20_A
DQ19_A
DQ18_A
DQ17_A
DQ16_A
DQ15_A
DQ14_A
DQ13_A
DQ12_A
DQ11_A
DQ10_A
DQ9_A
DQ8_A
DQ7_A
DQ6_A
DQ5_A
DQ4_A
DQ3_A
DQ2_A
DQ1_A
DQ0_A
DQ31_B
DQ30_B
DQ29_B
DQ28_B
DQ27_B
DQ26_B
DQ25_B
DQ24_B
DQ23_B
DQ22_B
DQ21_B
DQ20_B
DQ19_B
DQ18_B
DQ17_B
DQ16_B
DQ15_B
DQ14_B
DQ13_B
DQ12_B
DQ11_B
DQ10_B
DQ9_B
DQ8_B
DQ7_B
DQ6_B
DQ5_B
DQ4_B
DQ3_B
DQ2_B
DQ1_B
DQ0_B
HSA
HSCL
HSDA
LBD||RSP_A_n
LBS||RSP_B_n
PAR_A
PAR_B
PWR_GOOD||FAIL_n
RESET_n
RFU6
RFU5
RFU4
RFU3
RFU2
RFU1
RFU0
VIN_MGMT
21
2
1
2
1
2
1
2
1
CAD NOTE:
SHEETDATE
DEPARTMENT
SIZE
PROJECT DOCUMENT NUMBER REV
REVIEWER
DESIGNER
123
7 3 2 1 6 5 4
E
A
B
C
E
D
C
B
A
7 6 5 4
D
IN
ININ
BI
OUTOUT
IN
ININ
IN
IN
OUT
IN
IN
IN
OUTOUT
IN
BI
OUTOUT
IN
BI
BI
BI
IN
IN
C28C27C26
R34
C



20210728 MODIFY FOR GT
Fri Aug 25 14:01:10 2023N/AN/AN/AN/AV0591 OF 312P3V3_AUXP3V3_AUXP12V_S3_AUX_CPU0_NVDIMM
P12V_S3_AUX_CPU0_NVDIMMDDR5 - CPU0 CHE DIMM2(BLACK)22990929394959697912299092939495969712990929324901142490 24 9024 9024 9024 90242424242424242424902490
9124 9024902490249024 90
PLACE THE BYPASS CAPS CLOSE TO DIMMX6SC040220%I3C_SPD_DDREFGH_CPU0_LVC1_SCLI3C_SPD_DDREFGH_CPU0_LVC1_SCL_R2PD_CHE_CPU0_DIMM2_SAAI3C_SPD_DDREFGH_CPU0_LVC1_SDARST_M_EF_CPU0_FPGA_NM_E_CPU0_ALERT_NCHIP49.9TP_CHE_CPU0_DIMM2_FRU_6PWRGD_CHE_CPU0_DIMM2M_E_CPU0_SA_CB<7:0>M_E_CPU0_SA_DQS_DP<9:0>M_E_CPU0_SA_DQS_DN<9:0>M_E_CPU0_SB_DQS_DP<9:0>M_E_CPU0_SB_DQS_DN<9:0>TP_CHE_CPU0_DIMM2_FRU_5TP_CHE_CPU0_DIMM2_FRU_3TP_CHE_CPU0_DIMM2_FRU_2TP_CHE_CPU0_DIMM2_FRU_0
SCONN288_ADR50017-P087CCSMLFSCONN288_ADR50017-P087CCSCONN288_ADR50017-P087CCSMLFIOM_E_CPU0_CLK_DN<1>M_E_CPU0_CLK_DP<1>M_E_CPU0_SA_CS_N<2>M_E_CPU0_SB_CS_N<2>M_E_CPU0_SA_CS_N<3>M_E_CPU0_SB_CS_N<3>M_E_CPU0_SA_RSP<1>M_E_CPU0_SB_RSP<1>M_E_CPU0_SA_PARM_E_CPU0_SB_PARTP_CHE_CPU0_DIMM2_FRU_4TP_CHE_CPU0_DIMM2_FRU_1
IOSMLFIO
0402LF15.4K1%CHIP1/16WX6SC080510UF16V10%X6S16V10UF10%C0805PD_CHE_CPU0_DIMM2_SAAM_E_CPU0_SB_DQ<31:0>M_E_CPU0_SB_CA<6:0>M_E_CPU0_SA_CA<6:0>M_E_CPU0_SB_CB<7:0>M_E_CPU0_SA_DQ<31:0>
6.3V2.2UF
DQS7_A_c||TDQS7_A_c
DQS6_A_t||TDQS6_A_t
DQS8_B_t||TDQS8_B_t
DQS8_B_c||TDQS8_B_c
DQS7_B_t||TDQS7_B_t
DQS0_A_c
DQS0_A_t
DQS0_B_c
DQS0_B_t
DQS1_A_c
DQS1_A_t
DQS1_B_c
DQS1_B_t
DQS2_A_c
DQS2_A_t
DQS2_B_c
DQS2_B_t
DQS3_A_c
DQS3_A_t
DQS3_B_c
DQS3_B_t
DQS4_A_c
DQS4_A_t
DQS4_B_c
DQS4_B_t
DQS5_A_c||TDQS5_A_c||DQS5_A_t||TDQS5_A_t
DQS5_A_t||TDQS5_A_t
DQS5_B_c||TDQS5_B_c
DQS5_B_t||TDQS5_B_t
DQS6_A_c||TDQS6_A_c||DQS6_A_t||TDQS6_A_t
DQS6_B_c||TDQS6_B_c
DQS6_B_t||TDQS6_B_t
DQS7_A_t||TDQS7_A_t
DQS7_B_c||TDQS7_B_c
DQS8_A_c||TDQS8_A_c
DQS8_A_t||TDQS8_A_t
DQS9_A_c||TDQS9_A_c
DQS9_A_t||TDQS9_A_t
DQS9_B_c||TDQS9_B_c
DQS9_B_t||TDQS9_B_t||DBI4_B_n
R3884
93
94
201
200
283
282
190
189
272
271
179
178
261
260
168
167
250
249
157
156
239
238
55
56
137
138
44
45
126
127
33
34
115
116
22
23
104
105
11
12
288
286
284
281
279
277
275
273
270
268
266
264
262
259
257
255
253
251
248
246
244
242
240
237
235
233
230
228
226
224
222
219
216
214
212
210
208
206
204
202
199
197
195
193
191
188
186
184
182
180
177
175
173
171
169
166
164
162
160
158
155
153
151
143
141
139
136
134
132
130
128
125
123
121
119
117
114
112
110
108
106
103
101
99
97
95
92
90
88
85
83
81
79
77
75
73
71
69
67
65
63
61
59
57
54
52
50
48
46
43
41
39
37
35
32
30
28
26
24
21
19
17
15
13
10
8
6
146
145
1
G3
G2
G1
3
232
231
220
150
149
144
2
207
147
227
74
87
86
5
4
148
287
194
285
192
142
49
140
47
280
187
278
185
135
42
133
40
276
183
274
181
131
38
129
36
269
176
267
174
124
31
122
29
265
172
263
170
120
27
118
25
258
165
256
163
113
20
111
18
254
161
252
159
109
16
107
14
247
154
245
152
102
9
100
7
229
209
84
64
217
218
236
205
234
203
91
60
89
58
243
198
241
196
98
53
96
51
82
72
225
215
80
70
223
213
78
68
221
211
76
66
62
9
8
7
6
5
3
4
2
1
0
9
7
8
6
5
4
2
3
1
0
9
8
7
6
5
4
3
2
1
0
9
8
7
6
5
4
3
2
1
0
0
25
30
3
28
27
16
14
13
12
11
10
9
6
8
7
5
4
1
2
0
31
29
25
26
24
23
22
21
20
19
18
16
17
15
14
13
12
11
10
9
7
8
6
5
4
2
3
1
0
3
2
1
0
5
6
4
3
2
1
0
7
5
6
4
3
2
0
1
7
6
5
4
3
2
1
29
30
316
4
5
28
27
26
24
23
22
21
20
19
18
17
15
J10
J10J10
2/3 3/3
G3
G2
G1
VSS62
VSS61
VSS60
VSS58
VSS104
VSS102
VSS100
VIN_BULK2
VIN_BULK1
VIN_BULK0
VSS126
VSS125
VSS124
VSS123
VSS122
VSS121
VSS120
VSS119
VSS118
VSS117
VSS116
VSS115
VSS114
VSS113
VSS112
VSS111
VSS110
VSS109
VSS108
VSS107
VSS106
VSS105
VSS103
VSS101
VSS99
VSS98
VSS97
VSS96
VSS95
VSS94
VSS93
VSS92
VSS91
VSS90
VSS89
VSS88
VSS87
VSS86
VSS85
VSS84
VSS83
VSS82
VSS81
VSS80
VSS79
VSS78
VSS77
VSS76
VSS75
VSS74
VSS73
VSS72
VSS71
VSS70
VSS69
VSS68
VSS67
VSS66
VSS65
VSS64
VSS63
VSS59
VSS57
VSS56
VSS55
VSS54
VSS53
VSS52
VSS51
VSS50
VSS49
VSS48
VSS47
VSS46
VSS45
VSS44
VSS43
VSS42
VSS41
VSS40
VSS39
VSS38
VSS37
VSS36
VSS35
VSS34
VSS33
VSS32
VSS31
VSS30
VSS29
VSS28
VSS27
VSS26
VSS25
VSS24
VSS23
VSS22
VSS21
VSS20
VSS19
VSS18
VSS17
VSS16
VSS15
VSS14
VSS13
VSS12
VSS11
VSS10
VSS9
VSS8
VSS7
VSS6
VSS5
VSS4
VSS3
VSS2
VSS1
VSS0
1/3
DQ31_A
CB7_A
CB4_A
CB1_A
CB7_B
ALERT_n
CA0_A
CA0_B
CA1_A
CA1_B
CA2_A
CA2_B
CA3_A
CA3_B
CA4_A
CA4_B
CA5_A
CA5_B
CA6_A
CA6_B
CB6_A
CB5_A
CB3_A
CB2_A
CB0_A
CB6_B
CB5_B
CB4_B
CB3_B
CB2_B
CB1_B
CB0_B
CK_c
CK_t
CS0_A_n
CS0_B_n
CS1_A_n
CS1_B_n
DQ30_A
DQ29_A
DQ28_A
DQ27_A
DQ26_A
DQ25_A
DQ24_A
DQ23_A
DQ22_A
DQ21_A
DQ20_A
DQ19_A
DQ18_A
DQ17_A
DQ16_A
DQ15_A
DQ14_A
DQ13_A
DQ12_A
DQ11_A
DQ10_A
DQ9_A
DQ8_A
DQ7_A
DQ6_A
DQ5_A
DQ4_A
DQ3_A
DQ2_A
DQ1_A
DQ0_A
DQ31_B
DQ30_B
DQ29_B
DQ28_B
DQ27_B
DQ26_B
DQ25_B
DQ24_B
DQ23_B
DQ22_B
DQ21_B
DQ20_B
DQ19_B
DQ18_B
DQ17_B
DQ16_B
DQ15_B
DQ14_B
DQ13_B
DQ12_B
DQ11_B
DQ10_B
DQ9_B
DQ8_B
DQ7_B
DQ6_B
DQ5_B
DQ4_B
DQ3_B
DQ2_B
DQ1_B
DQ0_B
HSA
HSCL
HSDA
LBD||RSP_A_n
LBS||RSP_B_n
PAR_A
PAR_B
PWR_GOOD||FAIL_n
RESET_n
RFU6
RFU5
RFU4
RFU3
RFU2
RFU1
RFU0
VIN_MGMT
21
2
1
2
1
2
1
2
1
CAD NOTE:
SHEETDATE
DEPARTMENT
SIZE
PROJECT DOCUMENT NUMBER REV
REVIEWER
DESIGNER
123
7 3 2 1 6 5 4
E
A
B
C
E
D
C
B
A
7 6 5 4
D
ININ
BI
OUTOUT
OUT
IN
ININ
ININ
ININ
IN
IN
OUTOUTBI
IN
OUTOUT
BI
BI
BI
IN
IN
IN
C31C30C29
R35
C



20210728 MODIFY FOR GT
N/AN/AN/AFri Aug 25 14:01:11 2023N/A92 OF 312V05
P3V3_AUXP12V_S3_AUX_CPU0_NVDIMMP3V3_AUX
P12V_S3_AUX_CPU0_NVDIMM
DDR5 - CPU0 CHF DIMM1(YELLOW)
922299091939495969725931299091932299091939495969711425 9325 9325 9325 9325932593
2525252525252525259325932593
9225 93259325 93PD_CHF_CPU0_DIMM1_SAAI3C_SPD_DDREFGH_CPU0_LVC1_SDAI3C_SPD_DDREFGH_CPU0_LVC1_SCL_R3M_F_CPU0_ALERT_NRST_M_EF_CPU0_FPGA_NI3C_SPD_DDREFGH_CPU0_LVC1_SCL49.9CHIPPWRGD_CHF_CPU0_DIMM1TP_CHF_CPU0_DIMM1_FRU_6TP_CHF_CPU0_DIMM1_FRU_5
M_F_CPU0_SA_DQS_DP<9:0>M_F_CPU0_SA_DQS_DN<9:0>M_F_CPU0_SB_DQS_DP<9:0>M_F_CPU0_SB_DQS_DN<9:0>TP_CHF_CPU0_DIMM1_FRU_3TP_CHF_CPU0_DIMM1_FRU_4M_F_CPU0_SB_CB<7:0>M_F_CPU0_SA_CA<6:0>SMLFSCONN288_ADR50017-P130CCIOSMLFSCONN288_ADR50017-P130CCSMLF
M_F_CPU0_SA_RSP<0>M_F_CPU0_SB_RSP<0>
IOSCONN288_ADR50017-P130CC
TP_CHF_CPU0_DIMM1_FRU_2M_F_CPU0_CLK_DN<0>M_F_CPU0_CLK_DP<0>M_F_CPU0_SA_CS_N<0>M_F_CPU0_SB_CS_N<0>M_F_CPU0_SA_CS_N<1>M_F_CPU0_SB_CS_N<1>M_F_CPU0_SA_PARM_F_CPU0_SB_PARTP_CHF_CPU0_DIMM1_FRU_1TP_CHF_CPU0_DIMM1_FRU_0
IOM_F_CPU0_SB_CA<6:0>
0402LFCHIP1/16W1%23.2KX6S16V10UF10%C0805X6S16V10UF10%C0805PD_CHF_CPU0_DIMM1_SAAM_F_CPU0_SB_DQ<31:0>M_F_CPU0_SA_CB<7:0>M_F_CPU0_SA_DQ<31:0>
PLACE THE BYPASS CAPS CLOSE TO DIMM6.3V2.2UF20%X6SC0402
DQS7_A_c||TDQS7_A_c
DQS6_A_t||TDQS6_A_t
DQS8_B_t||TDQS8_B_t
DQS8_B_c||TDQS8_B_c
DQS7_B_t||TDQS7_B_t
DQS0_A_c
DQS0_A_t
DQS0_B_c
DQS0_B_t
DQS1_A_c
DQS1_A_t
DQS1_B_c
DQS1_B_t
DQS2_A_c
DQS2_A_t
DQS2_B_c
DQS2_B_t
DQS3_A_c
DQS3_A_t
DQS3_B_c
DQS3_B_t
DQS4_A_c
DQS4_A_t
DQS4_B_c
DQS4_B_t
DQS5_A_c||TDQS5_A_c||DQS5_A_t||TDQS5_A_t
DQS5_A_t||TDQS5_A_t
DQS5_B_c||TDQS5_B_c
DQS5_B_t||TDQS5_B_t
DQS6_A_c||TDQS6_A_c||DQS6_A_t||TDQS6_A_t
DQS6_B_c||TDQS6_B_c
DQS6_B_t||TDQS6_B_t
DQS7_A_t||TDQS7_A_t
DQS7_B_c||TDQS7_B_c
DQS8_A_c||TDQS8_A_c
DQS8_A_t||TDQS8_A_t
DQS9_A_c||TDQS9_A_c
DQS9_A_t||TDQS9_A_t
DQS9_B_c||TDQS9_B_c
DQS9_B_t||TDQS9_B_t||DBI4_B_n
R3885
93
94
201
200
283
282
190
189
272
271
179
178
261
260
168
167
250
249
157
156
239
238
55
56
137
138
44
45
126
127
33
34
115
116
22
23
104
105
11
12
288
286
284
281
279
277
275
273
270
268
266
264
262
259
257
255
253
251
248
246
244
242
240
237
235
233
230
228
226
224
222
219
216
214
212
210
208
206
204
202
199
197
195
193
191
188
186
184
182
180
177
175
173
171
169
166
164
162
160
158
155
153
151
143
141
139
136
134
132
130
128
125
123
121
119
117
114
112
110
108
106
103
101
99
97
95
92
90
88
85
83
81
79
77
75
73
71
69
67
65
63
61
59
57
54
52
50
48
46
43
41
39
37
35
32
30
28
26
24
21
19
17
15
13
10
8
6
146
145
1
G3
G2
G1
3
232
231
220
150
149
144
2
207
147
227
74
87
86
5
4
148
287
194
285
192
142
49
140
47
280
187
278
185
135
42
133
40
276
183
274
181
131
38
129
36
269
176
267
174
124
31
122
29
265
172
263
170
120
27
118
25
258
165
256
163
113
20
111
18
254
161
252
159
109
16
107
14
247
154
245
152
102
9
100
7
229
209
84
64
217
218
236
205
234
203
91
60
89
58
243
198
241
196
98
53
96
51
82
72
225
215
80
70
223
213
78
68
221
211
76
66
62
9
8
7
6
4
5
3
2
1
0
9
8
7
6
5
3
4
2
1
0
9
8
7
6
5
4
3
2
1
0
9
8
7
6
5
4
3
2
1
0
312
19
2
0
11
10
8
7
9
5
6
3
4
1
0
30
28
29
25
26
27
6
5
4
3
2
0
1
6
5
4
3
2
1
0
6
7
4
5
3
1
7
5
6
23
24
22
21
20
17
18
15
16
12
13
14
10
11
7
8
9
6
5
4
3
2
0
1
4
1
0
2
3
31
30
28
29
25
26
27
23
24
20
21
22
18
19
16
15
17
13
14
12
J11 J11J11
1/3
DQ31_A
CB7_A
CB4_A
CB1_A
CB7_B
ALERT_n
CA0_A
CA0_B
CA1_A
CA1_B
CA2_A
CA2_B
CA3_A
CA3_B
CA4_A
CA4_B
CA5_A
CA5_B
CA6_A
CA6_B
CB6_A
CB5_A
CB3_A
CB2_A
CB0_A
CB6_B
CB5_B
CB4_B
CB3_B
CB2_B
CB1_B
CB0_B
CK_c
CK_t
CS0_A_n
CS0_B_n
CS1_A_n
CS1_B_n
DQ30_A
DQ29_A
DQ28_A
DQ27_A
DQ26_A
DQ25_A
DQ24_A
DQ23_A
DQ22_A
DQ21_A
DQ20_A
DQ19_A
DQ18_A
DQ17_A
DQ16_A
DQ15_A
DQ14_A
DQ13_A
DQ12_A
DQ11_A
DQ10_A
DQ9_A
DQ8_A
DQ7_A
DQ6_A
DQ5_A
DQ4_A
DQ3_A
DQ2_A
DQ1_A
DQ0_A
DQ31_B
DQ30_B
DQ29_B
DQ28_B
DQ27_B
DQ26_B
DQ25_B
DQ24_B
DQ23_B
DQ22_B
DQ21_B
DQ20_B
DQ19_B
DQ18_B
DQ17_B
DQ16_B
DQ15_B
DQ14_B
DQ13_B
DQ12_B
DQ11_B
DQ10_B
DQ9_B
DQ8_B
DQ7_B
DQ6_B
DQ5_B
DQ4_B
DQ3_B
DQ2_B
DQ1_B
DQ0_B
HSA
HSCL
HSDA
LBD||RSP_A_n
LBS||RSP_B_n
PAR_A
PAR_B
PWR_GOOD||FAIL_n
RESET_n
RFU6
RFU5
RFU4
RFU3
RFU2
RFU1
RFU0
VIN_MGMT
2/3 3/3
G3
G2
G1
VSS62
VSS61
VSS60
VSS58
VSS104
VSS102
VSS100
VIN_BULK2
VIN_BULK1
VIN_BULK0
VSS126
VSS125
VSS124
VSS123
VSS122
VSS121
VSS120
VSS119
VSS118
VSS117
VSS116
VSS115
VSS114
VSS113
VSS112
VSS111
VSS110
VSS109
VSS108
VSS107
VSS106
VSS105
VSS103
VSS101
VSS99
VSS98
VSS97
VSS96
VSS95
VSS94
VSS93
VSS92
VSS91
VSS90
VSS89
VSS88
VSS87
VSS86
VSS85
VSS84
VSS83
VSS82
VSS81
VSS80
VSS79
VSS78
VSS77
VSS76
VSS75
VSS74
VSS73
VSS72
VSS71
VSS70
VSS69
VSS68
VSS67
VSS66
VSS65
VSS64
VSS63
VSS59
VSS57
VSS56
VSS55
VSS54
VSS53
VSS52
VSS51
VSS50
VSS49
VSS48
VSS47
VSS46
VSS45
VSS44
VSS43
VSS42
VSS41
VSS40
VSS39
VSS38
VSS37
VSS36
VSS35
VSS34
VSS33
VSS32
VSS31
VSS30
VSS29
VSS28
VSS27
VSS26
VSS25
VSS24
VSS23
VSS22
VSS21
VSS20
VSS19
VSS18
VSS17
VSS16
VSS15
VSS14
VSS13
VSS12
VSS11
VSS10
VSS9
VSS8
VSS7
VSS6
VSS5
VSS4
VSS3
VSS2
VSS1
VSS0
21
2
1
2
1
2
1
2
1
CAD NOTE:
SHEETDATE
DEPARTMENT
SIZE
PROJECT DOCUMENT NUMBER REV
REVIEWER
DESIGNER
123
7 3 2 1 6 5 4
E
A
B
C
E
D
C
B
A
7 6 5 4
D
ININ
BI
OUTOUT
OUT
IN
IN
ININ
ININ
IN
IN
OUTOUT
OUTOUTIN
BI
ININ
BI
BI
BI
IN
IN
C34C33C32
R36
C



20210728 MODIFY FOR GT
Fri Aug 25 14:01:12 2023N/AN/AN/AN/AV0593 OF 312
P3V3_AUXP12V_S3_AUX_CPU0_NVDIMM
P12V_S3_AUX_CPU0_NVDIMMP3V3_AUXDDR5 - CPU0 CHF DIMM2(BLACK)
229909192949596979325921299091922299091929495969711425 9225 9225 9225 9225252525252525252592259225 9293
259225922592259225 92
PLACE THE BYPASS CAPS CLOSE TO DIMMC0805X6SI3C_SPD_DDREFGH_CPU0_LVC1_SCL_R4I3C_SPD_DDREFGH_CPU0_LVC1_SDAPD_CHF_CPU0_DIMM2_SAAM_F_CPU0_ALERT_NRST_M_EF_CPU0_FPGA_NI3C_SPD_DDREFGH_CPU0_LVC1_SCLCHIPPWRGD_CHF_CPU0_DIMM2TP_CHF_CPU0_DIMM2_FRU_4TP_CHF_CPU0_DIMM2_FRU_5TP_CHF_CPU0_DIMM2_FRU_6M_F_CPU0_SA_DQS_DN<9:0>M_F_CPU0_SA_DQS_DP<9:0>M_F_CPU0_SB_DQS_DP<9:0>M_F_CPU0_SB_DQS_DN<9:0>49.9
SCONN288_ADR50017-P087CCIO SCONN288_ADR50017-P087CCSMLFIOM_F_CPU0_CLK_DN<1>M_F_CPU0_CLK_DP<1>M_F_CPU0_SA_CS_N<2>M_F_CPU0_SB_CS_N<2>M_F_CPU0_SA_CS_N<3>M_F_CPU0_SB_CS_N<3>M_F_CPU0_SA_RSP<1>M_F_CPU0_SB_RSP<1>M_F_CPU0_SA_PARM_F_CPU0_SB_PARTP_CHF_CPU0_DIMM2_FRU_3TP_CHF_CPU0_DIMM2_FRU_2TP_CHF_CPU0_DIMM2_FRU_1TP_CHF_CPU0_DIMM2_FRU_0
SMLFM_F_CPU0_SB_DQ<31:0>SCONN288_ADR50017-P087CCIOSMLF
0402LF1/16WCHIP1%35.7KX6S10%16V10UFC080510UF16V10%PD_CHF_CPU0_DIMM2_SAA
M_F_CPU0_SB_CA<6:0>M_F_CPU0_SA_CA<6:0>M_F_CPU0_SB_CB<7:0>M_F_CPU0_SA_CB<7:0>M_F_CPU0_SA_DQ<31:0>
2.2UF6.3VX6SC040220%
DQS7_A_c||TDQS7_A_c
DQS6_A_t||TDQS6_A_t
DQS8_B_t||TDQS8_B_t
DQS8_B_c||TDQS8_B_c
DQS7_B_t||TDQS7_B_t
DQS0_A_c
DQS0_A_t
DQS0_B_c
DQS0_B_t
DQS1_A_c
DQS1_A_t
DQS1_B_c
DQS1_B_t
DQS2_A_c
DQS2_A_t
DQS2_B_c
DQS2_B_t
DQS3_A_c
DQS3_A_t
DQS3_B_c
DQS3_B_t
DQS4_A_c
DQS4_A_t
DQS4_B_c
DQS4_B_t
DQS5_A_c||TDQS5_A_c||DQS5_A_t||TDQS5_A_t
DQS5_A_t||TDQS5_A_t
DQS5_B_c||TDQS5_B_c
DQS5_B_t||TDQS5_B_t
DQS6_A_c||TDQS6_A_c||DQS6_A_t||TDQS6_A_t
DQS6_B_c||TDQS6_B_c
DQS6_B_t||TDQS6_B_t
DQS7_A_t||TDQS7_A_t
DQS7_B_c||TDQS7_B_c
DQS8_A_c||TDQS8_A_c
DQS8_A_t||TDQS8_A_t
DQS9_A_c||TDQS9_A_c
DQS9_A_t||TDQS9_A_t
DQS9_B_c||TDQS9_B_c
DQS9_B_t||TDQS9_B_t||DBI4_B_n
R3886
93
94
201
200
283
282
190
189
272
271
179
178
261
260
168
167
250
249
157
156
239
238
55
56
137
138
44
45
126
127
33
34
115
116
22
23
104
105
11
12
288
286
284
281
279
277
275
273
270
268
266
264
262
259
257
255
253
251
248
246
244
242
240
237
235
233
230
228
226
224
222
219
216
214
212
210
208
206
204
202
199
197
195
193
191
188
186
184
182
180
177
175
173
171
169
166
164
162
160
158
155
153
151
143
141
139
136
134
132
130
128
125
123
121
119
117
114
112
110
108
106
103
101
99
97
95
92
90
88
85
83
81
79
77
75
73
71
69
67
65
63
61
59
57
54
52
50
48
46
43
41
39
37
35
32
30
28
26
24
21
19
17
15
13
10
8
6
146
145
1
G3
G2
G1
3
232
231
220
150
149
144
2
207
147
227
74
87
86
5
4
148
287
194
285
192
142
49
140
47
280
187
278
185
135
42
133
40
276
183
274
181
131
38
129
36
269
176
267
174
124
31
122
29
265
172
263
170
120
27
118
25
258
165
256
163
113
20
111
18
254
161
252
159
109
16
107
14
247
154
245
152
102
9
100
7
229
209
84
64
217
218
236
205
234
203
91
60
89
58
243
198
241
196
98
53
96
51
82
72
225
215
80
70
223
213
78
68
221
211
76
66
62
15
24
1
9
8
7
6
5
4
3
2
0
1
8
9
7
6
5
4
3
2
0
6
8
7
9
1
3
2
4
5
6
7
8
0
9
1
3
2
4
5
0
31
30
29
28
27
7
31
15
12
11
10
5
7
8
6
9
3
4
1
2
0
28
29
30
26
25
27
23
5
3
4
2
1
0
4
5
6
3
0
1
2
4
6
7
5
1
2
3
0
6
5
4
3
18
19
20
21
22
17
16
14
13
8
9
10
11
12
5
6
7
3
2
4
1
0
2
1
0
6
26
24
25
23
22
21
16
20
19
18
17
14
13
J12
J12J12
1/3
DQ31_A
CB7_A
CB4_A
CB1_A
CB7_B
ALERT_n
CA0_A
CA0_B
CA1_A
CA1_B
CA2_A
CA2_B
CA3_A
CA3_B
CA4_A
CA4_B
CA5_A
CA5_B
CA6_A
CA6_B
CB6_A
CB5_A
CB3_A
CB2_A
CB0_A
CB6_B
CB5_B
CB4_B
CB3_B
CB2_B
CB1_B
CB0_B
CK_c
CK_t
CS0_A_n
CS0_B_n
CS1_A_n
CS1_B_n
DQ30_A
DQ29_A
DQ28_A
DQ27_A
DQ26_A
DQ25_A
DQ24_A
DQ23_A
DQ22_A
DQ21_A
DQ20_A
DQ19_A
DQ18_A
DQ17_A
DQ16_A
DQ15_A
DQ14_A
DQ13_A
DQ12_A
DQ11_A
DQ10_A
DQ9_A
DQ8_A
DQ7_A
DQ6_A
DQ5_A
DQ4_A
DQ3_A
DQ2_A
DQ1_A
DQ0_A
DQ31_B
DQ30_B
DQ29_B
DQ28_B
DQ27_B
DQ26_B
DQ25_B
DQ24_B
DQ23_B
DQ22_B
DQ21_B
DQ20_B
DQ19_B
DQ18_B
DQ17_B
DQ16_B
DQ15_B
DQ14_B
DQ13_B
DQ12_B
DQ11_B
DQ10_B
DQ9_B
DQ8_B
DQ7_B
DQ6_B
DQ5_B
DQ4_B
DQ3_B
DQ2_B
DQ1_B
DQ0_B
HSA
HSCL
HSDA
LBD||RSP_A_n
LBS||RSP_B_n
PAR_A
PAR_B
PWR_GOOD||FAIL_n
RESET_n
RFU6
RFU5
RFU4
RFU3
RFU2
RFU1
RFU0
VIN_MGMT
2/3 3/3
G3
G2
G1
VSS62
VSS61
VSS60
VSS58
VSS104
VSS102
VSS100
VIN_BULK2
VIN_BULK1
VIN_BULK0
VSS126
VSS125
VSS124
VSS123
VSS122
VSS121
VSS120
VSS119
VSS118
VSS117
VSS116
VSS115
VSS114
VSS113
VSS112
VSS111
VSS110
VSS109
VSS108
VSS107
VSS106
VSS105
VSS103
VSS101
VSS99
VSS98
VSS97
VSS96
VSS95
VSS94
VSS93
VSS92
VSS91
VSS90
VSS89
VSS88
VSS87
VSS86
VSS85
VSS84
VSS83
VSS82
VSS81
VSS80
VSS79
VSS78
VSS77
VSS76
VSS75
VSS74
VSS73
VSS72
VSS71
VSS70
VSS69
VSS68
VSS67
VSS66
VSS65
VSS64
VSS63
VSS59
VSS57
VSS56
VSS55
VSS54
VSS53
VSS52
VSS51
VSS50
VSS49
VSS48
VSS47
VSS46
VSS45
VSS44
VSS43
VSS42
VSS41
VSS40
VSS39
VSS38
VSS37
VSS36
VSS35
VSS34
VSS33
VSS32
VSS31
VSS30
VSS29
VSS28
VSS27
VSS26
VSS25
VSS24
VSS23
VSS22
VSS21
VSS20
VSS19
VSS18
VSS17
VSS16
VSS15
VSS14
VSS13
VSS12
VSS11
VSS10
VSS9
VSS8
VSS7
VSS6
VSS5
VSS4
VSS3
VSS2
VSS1
VSS0
21
2
1
2
1
2
1
2
1
CAD NOTE:
SHEETDATE
DEPARTMENT
SIZE
PROJECT DOCUMENT NUMBER REV
REVIEWER
DESIGNER
123
7 3 2 1 6 5 4
E
A
B
C
E
D
C
B
A
7 6 5 4
D
ININ
BI
OUTOUT
OUT
IN
IN
ININ
IN
IN
IN
OUTBI OUT
IN
OUTOUT
IN
IN
BI
BI
BI
IN
IN
IN
C37C36C35
R37
C



20210728 MODIFY FOR GT
Fri Aug 25 14:01:13 202394 OF 312V05N/AN/AN/AN/A
P3V3_AUXP12V_S3_AUX_CPU0_NVDIMM
P12V_S3_AUX_CPU0_NVDIMM
P3V3_AUXDDR5 - CPU0 CHG DIMM1(YELLOW)
94229909192939596972695129959697229909192939596972626 26 9526 9526 9526 95114269526 9526262626262626952695269594
2695269526 95PD_CHG_CPU0_DIMM1_SAAI3C_SPD_DDREFGH_CPU0_LVC1_SDAI3C_SPD_DDREFGH_CPU0_LVC1_SCL_R5M_G_CPU0_ALERT_NRST_M_GH_CPU0_FPGA_NI3C_SPD_DDREFGH_CPU0_LVC1_SCLCHIPTP_CHG_CPU0_DIMM1_FRU_6M_G_CPU0_CLK_DP<0>M_G_CPU0_SB_CS_N<1>M_G_CPU0_SA_DQS_DP<9:0>M_G_CPU0_SA_DQS_DN<9:0>M_G_CPU0_SB_DQS_DP<9:0>M_G_CPU0_SB_DQS_DN<9:0>49.9PWRGD_CHG_CPU0_DIMM1M_G_CPU0_SA_CA<6:0>SCONN288_ADR50017-P130CCSMLFSCONN288_ADR50017-P130CCSMLFIOSMLFSCONN288_ADR50017-P130CCIOM_G_CPU0_SB_DQ<31:0>M_G_CPU0_CLK_DN<0>M_G_CPU0_SA_CS_N<0>M_G_CPU0_SB_CS_N<0>M_G_CPU0_SA_CS_N<1>M_G_CPU0_SA_RSP<0>M_G_CPU0_SB_RSP<0>M_G_CPU0_SA_PARM_G_CPU0_SB_PARTP_CHG_CPU0_DIMM1_FRU_5TP_CHG_CPU0_DIMM1_FRU_4TP_CHG_CPU0_DIMM1_FRU_3TP_CHG_CPU0_DIMM1_FRU_2TP_CHG_CPU0_DIMM1_FRU_1TP_CHG_CPU0_DIMM1_FRU_0
IO
0402LFM_G_CPU0_SB_CB<7:0>1/16WCHIP1%54.9KX6SC080510UF16V10%X6S10UF16VC080510%PD_CHG_CPU0_DIMM1_SAA
M_G_CPU0_SB_CA<6:0>M_G_CPU0_SA_CB<7:0>M_G_CPU0_SA_DQ<31:0>
PLACE THE BYPASS CAPS CLOSE TO DIMM2.2UF6.3VX6S20%C0402
DQS7_A_c||TDQS7_A_c
DQS6_A_t||TDQS6_A_t
DQS8_B_t||TDQS8_B_t
DQS8_B_c||TDQS8_B_c
DQS7_B_t||TDQS7_B_t
DQS0_A_c
DQS0_A_t
DQS0_B_c
DQS0_B_t
DQS1_A_c
DQS1_A_t
DQS1_B_c
DQS1_B_t
DQS2_A_c
DQS2_A_t
DQS2_B_c
DQS2_B_t
DQS3_A_c
DQS3_A_t
DQS3_B_c
DQS3_B_t
DQS4_A_c
DQS4_A_t
DQS4_B_c
DQS4_B_t
DQS5_A_c||TDQS5_A_c||DQS5_A_t||TDQS5_A_t
DQS5_A_t||TDQS5_A_t
DQS5_B_c||TDQS5_B_c
DQS5_B_t||TDQS5_B_t
DQS6_A_c||TDQS6_A_c||DQS6_A_t||TDQS6_A_t
DQS6_B_c||TDQS6_B_c
DQS6_B_t||TDQS6_B_t
DQS7_A_t||TDQS7_A_t
DQS7_B_c||TDQS7_B_c
DQS8_A_c||TDQS8_A_c
DQS8_A_t||TDQS8_A_t
DQS9_A_c||TDQS9_A_c
DQS9_A_t||TDQS9_A_t
DQS9_B_c||TDQS9_B_c
DQS9_B_t||TDQS9_B_t||DBI4_B_n
R3887
93
94
201
200
283
282
190
189
272
271
179
178
261
260
168
167
250
249
157
156
239
238
55
56
137
138
44
45
126
127
33
34
115
116
22
23
104
105
11
12
288
286
284
281
279
277
275
273
270
268
266
264
262
259
257
255
253
251
248
246
244
242
240
237
235
233
230
228
226
224
222
219
216
214
212
210
208
206
204
202
199
197
195
193
191
188
186
184
182
180
177
175
173
171
169
166
164
162
160
158
155
153
151
143
141
139
136
134
132
130
128
125
123
121
119
117
114
112
110
108
106
103
101
99
97
95
92
90
88
85
83
81
79
77
75
73
71
69
67
65
63
61
59
57
54
52
50
48
46
43
41
39
37
35
32
30
28
26
24
21
19
17
15
13
10
8
6
146
145
1
G3
G2
G1
3
232
231
220
150
149
144
2
207
147
227
74
87
86
5
4
148
287
194
285
192
142
49
140
47
280
187
278
185
135
42
133
40
276
183
274
181
131
38
129
36
269
176
267
174
124
31
122
29
265
172
263
170
120
27
118
25
258
165
256
163
113
20
111
18
254
161
252
159
109
16
107
14
247
154
245
152
102
9
100
7
229
209
84
64
217
218
236
205
234
203
91
60
89
58
243
198
241
196
98
53
96
51
82
72
225
215
80
70
223
213
78
68
221
211
76
66
62
7
8
9
5
6
4
3
2
1
0
8
9
6
7
5
3
4
0
1
2
9
7
8
4
5
6
2
3
0
1
7
8
9
6
5
4
2
3
0
1
31
29
18
19
17
16
15
13
14
12
11
10
8
9
7
5
6
4
2
3
1
0
30
31
28
27
26
25
23
24
21
22
20
19
18
17
15
16
14
13
12
10
11
9
8
7
5
6
3
4
2
0
1
6
5
4
3
2
1
0
6
7
4
5
3
2
1
0
7
5
6
4
3
2
1
0
29
30
28
27
26
25
6
5
4
3
2
0
1
23
24
22
21
20
J13 J13J13
2/3 3/3
G3
G2
G1
VSS62
VSS61
VSS60
VSS58
VSS104
VSS102
VSS100
VIN_BULK2
VIN_BULK1
VIN_BULK0
VSS126
VSS125
VSS124
VSS123
VSS122
VSS121
VSS120
VSS119
VSS118
VSS117
VSS116
VSS115
VSS114
VSS113
VSS112
VSS111
VSS110
VSS109
VSS108
VSS107
VSS106
VSS105
VSS103
VSS101
VSS99
VSS98
VSS97
VSS96
VSS95
VSS94
VSS93
VSS92
VSS91
VSS90
VSS89
VSS88
VSS87
VSS86
VSS85
VSS84
VSS83
VSS82
VSS81
VSS80
VSS79
VSS78
VSS77
VSS76
VSS75
VSS74
VSS73
VSS72
VSS71
VSS70
VSS69
VSS68
VSS67
VSS66
VSS65
VSS64
VSS63
VSS59
VSS57
VSS56
VSS55
VSS54
VSS53
VSS52
VSS51
VSS50
VSS49
VSS48
VSS47
VSS46
VSS45
VSS44
VSS43
VSS42
VSS41
VSS40
VSS39
VSS38
VSS37
VSS36
VSS35
VSS34
VSS33
VSS32
VSS31
VSS30
VSS29
VSS28
VSS27
VSS26
VSS25
VSS24
VSS23
VSS22
VSS21
VSS20
VSS19
VSS18
VSS17
VSS16
VSS15
VSS14
VSS13
VSS12
VSS11
VSS10
VSS9
VSS8
VSS7
VSS6
VSS5
VSS4
VSS3
VSS2
VSS1
VSS0
1/3
DQ31_A
CB7_A
CB4_A
CB1_A
CB7_B
ALERT_n
CA0_A
CA0_B
CA1_A
CA1_B
CA2_A
CA2_B
CA3_A
CA3_B
CA4_A
CA4_B
CA5_A
CA5_B
CA6_A
CA6_B
CB6_A
CB5_A
CB3_A
CB2_A
CB0_A
CB6_B
CB5_B
CB4_B
CB3_B
CB2_B
CB1_B
CB0_B
CK_c
CK_t
CS0_A_n
CS0_B_n
CS1_A_n
CS1_B_n
DQ30_A
DQ29_A
DQ28_A
DQ27_A
DQ26_A
DQ25_A
DQ24_A
DQ23_A
DQ22_A
DQ21_A
DQ20_A
DQ19_A
DQ18_A
DQ17_A
DQ16_A
DQ15_A
DQ14_A
DQ13_A
DQ12_A
DQ11_A
DQ10_A
DQ9_A
DQ8_A
DQ7_A
DQ6_A
DQ5_A
DQ4_A
DQ3_A
DQ2_A
DQ1_A
DQ0_A
DQ31_B
DQ30_B
DQ29_B
DQ28_B
DQ27_B
DQ26_B
DQ25_B
DQ24_B
DQ23_B
DQ22_B
DQ21_B
DQ20_B
DQ19_B
DQ18_B
DQ17_B
DQ16_B
DQ15_B
DQ14_B
DQ13_B
DQ12_B
DQ11_B
DQ10_B
DQ9_B
DQ8_B
DQ7_B
DQ6_B
DQ5_B
DQ4_B
DQ3_B
DQ2_B
DQ1_B
DQ0_B
HSA
HSCL
HSDA
LBD||RSP_A_n
LBS||RSP_B_n
PAR_A
PAR_B
PWR_GOOD||FAIL_n
RESET_n
RFU6
RFU5
RFU4
RFU3
RFU2
RFU1
RFU0
VIN_MGMT
21
2
1
2
1
2
1
2
1
CAD NOTE:
SHEETDATE
DEPARTMENT
SIZE
PROJECT DOCUMENT NUMBER REV
REVIEWER
DESIGNER
123
7 3 2 1 6 5 4
E
A
B
C
E
D
C
B
A
7 6 5 4
D
IN
ININ
BI
OUT
IN
IN
ININ
IN
OUT
IN
IN
IN
OUTOUT
IN
OUTOUT
IN
BI
BI
BI
IN
IN
BI
OUT
C40C39C38
R38
C



20210728 MODIFY FOR GT
Fri Aug 25 14:01:14 2023N/AN/AN/AN/AV0595 OF 312
P3V3_AUXP12V_S3_AUX_CPU0_NVDIMM
P12V_S3_AUX_CPU0_NVDIMMP3V3_AUXDDR5 - CPU0 CHG DIMM2(BLACK)
952299091929394969712994969726942299091929394969711426 26 9426 9426 9426 942694262626262626262694269426 9495
26942694269426 94
C0402PD_CHG_CPU0_DIMM2_SAAI3C_SPD_DDREFGH_CPU0_LVC1_SDAI3C_SPD_DDREFGH_CPU0_LVC1_SCL_R6RST_M_GH_CPU0_FPGA_NM_G_CPU0_ALERT_NCHIPI3C_SPD_DDREFGH_CPU0_LVC1_SCL49.9PWRGD_CHG_CPU0_DIMM2TP_CHG_CPU0_DIMM2_FRU_6TP_CHG_CPU0_DIMM2_FRU_5TP_CHG_CPU0_DIMM2_FRU_1M_G_CPU0_SA_RSP<1>TP_CHG_CPU0_DIMM2_FRU_4TP_CHG_CPU0_DIMM2_FRU_3TP_CHG_CPU0_DIMM2_FRU_2M_G_CPU0_SB_DQS_DP<9:0>M_G_CPU0_SB_DQS_DN<9:0>M_G_CPU0_SA_DQS_DN<9:0>M_G_CPU0_SA_DQS_DP<9:0>M_G_CPU0_SA_CA<6:0>SCONN288_ADR50017-P087CCIOSCONN288_ADR50017-P087CCSMLFM_G_CPU0_CLK_DN<1>M_G_CPU0_CLK_DP<1>M_G_CPU0_SA_CS_N<2>M_G_CPU0_SB_CS_N<2>M_G_CPU0_SA_CS_N<3>M_G_CPU0_SB_CS_N<3>M_G_CPU0_SB_RSP<1>M_G_CPU0_SA_PARM_G_CPU0_SB_PARTP_CHG_CPU0_DIMM2_FRU_0
SMLFIOM_G_CPU0_SB_DQ<31:0>SCONN288_ADR50017-P087CCIOSMLF
0402LF1%CHIP1/16W84.5KX6SC080510UF16V10%X6SC080510UF16V10%PD_CHG_CPU0_DIMM2_SAA
M_G_CPU0_SB_CA<6:0>M_G_CPU0_SB_CB<7:0>M_G_CPU0_SA_CB<7:0>M_G_CPU0_SA_DQ<31:0>
PLACE THE BYPASS CAPS CLOSE TO DIMM2.2UF6.3V20%X6S
DQS7_A_c||TDQS7_A_c
DQS6_A_t||TDQS6_A_t
DQS8_B_t||TDQS8_B_t
DQS8_B_c||TDQS8_B_c
DQS7_B_t||TDQS7_B_t
DQS0_A_c
DQS0_A_t
DQS0_B_c
DQS0_B_t
DQS1_A_c
DQS1_A_t
DQS1_B_c
DQS1_B_t
DQS2_A_c
DQS2_A_t
DQS2_B_c
DQS2_B_t
DQS3_A_c
DQS3_A_t
DQS3_B_c
DQS3_B_t
DQS4_A_c
DQS4_A_t
DQS4_B_c
DQS4_B_t
DQS5_A_c||TDQS5_A_c||DQS5_A_t||TDQS5_A_t
DQS5_A_t||TDQS5_A_t
DQS5_B_c||TDQS5_B_c
DQS5_B_t||TDQS5_B_t
DQS6_A_c||TDQS6_A_c||DQS6_A_t||TDQS6_A_t
DQS6_B_c||TDQS6_B_c
DQS6_B_t||TDQS6_B_t
DQS7_A_t||TDQS7_A_t
DQS7_B_c||TDQS7_B_c
DQS8_A_c||TDQS8_A_c
DQS8_A_t||TDQS8_A_t
DQS9_A_c||TDQS9_A_c
DQS9_A_t||TDQS9_A_t
DQS9_B_c||TDQS9_B_c
DQS9_B_t||TDQS9_B_t||DBI4_B_n
R3888
93
94
201
200
283
282
190
189
272
271
179
178
261
260
168
167
250
249
157
156
239
238
55
56
137
138
44
45
126
127
33
34
115
116
22
23
104
105
11
12
288
286
284
281
279
277
275
273
270
268
266
264
262
259
257
255
253
251
248
246
244
242
240
237
235
233
230
228
226
224
222
219
216
214
212
210
208
206
204
202
199
197
195
193
191
188
186
184
182
180
177
175
173
171
169
166
164
162
160
158
155
153
151
143
141
139
136
134
132
130
128
125
123
121
119
117
114
112
110
108
106
103
101
99
97
95
92
90
88
85
83
81
79
77
75
73
71
69
67
65
63
61
59
57
54
52
50
48
46
43
41
39
37
35
32
30
28
26
24
21
19
17
15
13
10
8
6
146
145
1
G3
G2
G1
3
232
231
220
150
149
144
2
207
147
227
74
87
86
5
4
148
287
194
285
192
142
49
140
47
280
187
278
185
135
42
133
40
276
183
274
181
131
38
129
36
269
176
267
174
124
31
122
29
265
172
263
170
120
27
118
25
258
165
256
163
113
20
111
18
254
161
252
159
109
16
107
14
247
154
245
152
102
9
100
7
229
209
84
64
217
218
236
205
234
203
91
60
89
58
243
198
241
196
98
53
96
51
82
72
225
215
80
70
223
213
78
68
221
211
76
66
62
0
2
1
3
4
5
6
7
8
9
0
1
2
3
4
5
6
7
8
9
1
0
2
3
4
5
6
7
8
9
1
0
2
3
4
5
6
7
8
96
13
21
1
31
17
18
19
15
16
14
12
11
10
9
8
7
6
5
4
2
3
0
30
27
28
29
26
25
22
23
24
20
21
17
18
19
16
15
14
12
13
11
10
9
7
8
4
5
6
3
2
0
1
5
6
4
3
2
1
0
6
7
5
4
3
1
2
7
0
6
5
4
3
2
0
1
31
30
27
29
28
25
26
5
3
4
2
0
1
24
23
22
20
J14
J14J14
1/3
DQ31_A
CB7_A
CB4_A
CB1_A
CB7_B
ALERT_n
CA0_A
CA0_B
CA1_A
CA1_B
CA2_A
CA2_B
CA3_A
CA3_B
CA4_A
CA4_B
CA5_A
CA5_B
CA6_A
CA6_B
CB6_A
CB5_A
CB3_A
CB2_A
CB0_A
CB6_B
CB5_B
CB4_B
CB3_B
CB2_B
CB1_B
CB0_B
CK_c
CK_t
CS0_A_n
CS0_B_n
CS1_A_n
CS1_B_n
DQ30_A
DQ29_A
DQ28_A
DQ27_A
DQ26_A
DQ25_A
DQ24_A
DQ23_A
DQ22_A
DQ21_A
DQ20_A
DQ19_A
DQ18_A
DQ17_A
DQ16_A
DQ15_A
DQ14_A
DQ13_A
DQ12_A
DQ11_A
DQ10_A
DQ9_A
DQ8_A
DQ7_A
DQ6_A
DQ5_A
DQ4_A
DQ3_A
DQ2_A
DQ1_A
DQ0_A
DQ31_B
DQ30_B
DQ29_B
DQ28_B
DQ27_B
DQ26_B
DQ25_B
DQ24_B
DQ23_B
DQ22_B
DQ21_B
DQ20_B
DQ19_B
DQ18_B
DQ17_B
DQ16_B
DQ15_B
DQ14_B
DQ13_B
DQ12_B
DQ11_B
DQ10_B
DQ9_B
DQ8_B
DQ7_B
DQ6_B
DQ5_B
DQ4_B
DQ3_B
DQ2_B
DQ1_B
DQ0_B
HSA
HSCL
HSDA
LBD||RSP_A_n
LBS||RSP_B_n
PAR_A
PAR_B
PWR_GOOD||FAIL_n
RESET_n
RFU6
RFU5
RFU4
RFU3
RFU2
RFU1
RFU0
VIN_MGMT
2/3 3/3
G3
G2
G1
VSS62
VSS61
VSS60
VSS58
VSS104
VSS102
VSS100
VIN_BULK2
VIN_BULK1
VIN_BULK0
VSS126
VSS125
VSS124
VSS123
VSS122
VSS121
VSS120
VSS119
VSS118
VSS117
VSS116
VSS115
VSS114
VSS113
VSS112
VSS111
VSS110
VSS109
VSS108
VSS107
VSS106
VSS105
VSS103
VSS101
VSS99
VSS98
VSS97
VSS96
VSS95
VSS94
VSS93
VSS92
VSS91
VSS90
VSS89
VSS88
VSS87
VSS86
VSS85
VSS84
VSS83
VSS82
VSS81
VSS80
VSS79
VSS78
VSS77
VSS76
VSS75
VSS74
VSS73
VSS72
VSS71
VSS70
VSS69
VSS68
VSS67
VSS66
VSS65
VSS64
VSS63
VSS59
VSS57
VSS56
VSS55
VSS54
VSS53
VSS52
VSS51
VSS50
VSS49
VSS48
VSS47
VSS46
VSS45
VSS44
VSS43
VSS42
VSS41
VSS40
VSS39
VSS38
VSS37
VSS36
VSS35
VSS34
VSS33
VSS32
VSS31
VSS30
VSS29
VSS28
VSS27
VSS26
VSS25
VSS24
VSS23
VSS22
VSS21
VSS20
VSS19
VSS18
VSS17
VSS16
VSS15
VSS14
VSS13
VSS12
VSS11
VSS10
VSS9
VSS8
VSS7
VSS6
VSS5
VSS4
VSS3
VSS2
VSS1
VSS0
21
2
1
2
1
2
1
2
1
CAD NOTE:
SHEETDATE
DEPARTMENT
SIZE
PROJECT DOCUMENT NUMBER REV
REVIEWER
DESIGNER
123
7 3 2 1 6 5 4
E
A
B
C
E
D
C
B
A
7 6 5 4
D
IN
IN
ININ
BI
OUT
IN
OUT
IN
IN
IN
OUTOUT
IN
BI
OUTOUT
IN
IN
ININ
BI
IN
BI
IN
BI
OUT
C43C42C41
R39
C



20210728 MODIFY FOR GT
Fri Aug 25 14:01:16 202396 OF 312V05N/AN/AN/AN/A
P3V3_AUXP12V_S3_AUX_CPU0_NVDIMM
P12V_S3_AUX_CPU0_NVDIMMP3V3_AUXDDR5 - CPU0 CHH DIMM1(YELLOW)
2797962299091929394959727971299495972299091929394959711427 9727 9727 9727 9727 972727 972727272727272727972797
96
279727972797M_H_CPU0_SA_CB<7:0>PD_CHH_CPU0_DIMM1_SAAI3C_SPD_DDREFGH_CPU0_LVC1_SDAM_H_CPU0_ALERT_NI3C_SPD_DDREFGH_CPU0_LVC1_SCL_R7RST_M_GH_CPU0_FPGA_NCHIPI3C_SPD_DDREFGH_CPU0_LVC1_SCL49.9TP_CHH_CPU0_DIMM1_FRU_6PWRGD_CHH_CPU0_DIMM1M_H_CPU0_SA_DQS_DN<9:0>M_H_CPU0_SA_DQS_DP<9:0>M_H_CPU0_SB_DQS_DP<9:0>M_H_CPU0_SB_DQS_DN<9:0>SMLFSCONN288_ADR50017-P130CCIOSCONN288_ADR50017-P130CCSMLFM_H_CPU0_SA_DQ<31:0>IOM_H_CPU0_CLK_DP<0>IOSCONN288_ADR50017-P130CCSMLFM_H_CPU0_SB_DQ<31:0>M_H_CPU0_CLK_DN<0>M_H_CPU0_SA_CS_N<0>M_H_CPU0_SB_CS_N<0>M_H_CPU0_SA_CS_N<1>M_H_CPU0_SB_CS_N<1>M_H_CPU0_SA_RSP<0>M_H_CPU0_SB_RSP<0>M_H_CPU0_SA_PARM_H_CPU0_SB_PARTP_CHH_CPU0_DIMM1_FRU_5TP_CHH_CPU0_DIMM1_FRU_4TP_CHH_CPU0_DIMM1_FRU_3TP_CHH_CPU0_DIMM1_FRU_2TP_CHH_CPU0_DIMM1_FRU_1TP_CHH_CPU0_DIMM1_FRU_01/16W0402LF1%CHIP127KX6S10%16V10UFC0805X6S10UF16V10%C0805PD_CHH_CPU0_DIMM1_SAA
M_H_CPU0_SB_CA<6:0>M_H_CPU0_SA_CA<6:0>M_H_CPU0_SB_CB<7:0>PLACE THE BYPASS CAPS CLOSE TO DIMM2.2UF6.3V20%X6SC0402
DQS7_A_c||TDQS7_A_c
DQS6_A_t||TDQS6_A_t
DQS8_B_t||TDQS8_B_t
DQS8_B_c||TDQS8_B_c
DQS7_B_t||TDQS7_B_t
DQS0_A_c
DQS0_A_t
DQS0_B_c
DQS0_B_t
DQS1_A_c
DQS1_A_t
DQS1_B_c
DQS1_B_t
DQS2_A_c
DQS2_A_t
DQS2_B_c
DQS2_B_t
DQS3_A_c
DQS3_A_t
DQS3_B_c
DQS3_B_t
DQS4_A_c
DQS4_A_t
DQS4_B_c
DQS4_B_t
DQS5_A_c||TDQS5_A_c||DQS5_A_t||TDQS5_A_t
DQS5_A_t||TDQS5_A_t
DQS5_B_c||TDQS5_B_c
DQS5_B_t||TDQS5_B_t
DQS6_A_c||TDQS6_A_c||DQS6_A_t||TDQS6_A_t
DQS6_B_c||TDQS6_B_c
DQS6_B_t||TDQS6_B_t
DQS7_A_t||TDQS7_A_t
DQS7_B_c||TDQS7_B_c
DQS8_A_c||TDQS8_A_c
DQS8_A_t||TDQS8_A_t
DQS9_A_c||TDQS9_A_c
DQS9_A_t||TDQS9_A_t
DQS9_B_c||TDQS9_B_c
DQS9_B_t||TDQS9_B_t||DBI4_B_n
R3889
93
94
201
200
283
282
190
189
272
271
179
178
261
260
168
167
250
249
157
156
239
238
55
56
137
138
44
45
126
127
33
34
115
116
22
23
104
105
11
12
288
286
284
281
279
277
275
273
270
268
266
264
262
259
257
255
253
251
248
246
244
242
240
237
235
233
230
228
226
224
222
219
216
214
212
210
208
206
204
202
199
197
195
193
191
188
186
184
182
180
177
175
173
171
169
166
164
162
160
158
155
153
151
143
141
139
136
134
132
130
128
125
123
121
119
117
114
112
110
108
106
103
101
99
97
95
92
90
88
85
83
81
79
77
75
73
71
69
67
65
63
61
59
57
54
52
50
48
46
43
41
39
37
35
32
30
28
26
24
21
19
17
15
13
10
8
6
146
145
1
G3
G2
G1
3
232
231
220
150
149
144
2
207
147
227
74
87
86
5
4
148
287
194
285
192
142
49
140
47
280
187
278
185
135
42
133
40
276
183
274
181
131
38
129
36
269
176
267
174
124
31
122
29
265
172
263
170
120
27
118
25
258
165
256
163
113
20
111
18
254
161
252
159
109
16
107
14
247
154
245
152
102
9
100
7
229
209
84
64
217
218
236
205
234
203
91
60
89
58
243
198
241
196
98
53
96
51
82
72
225
215
80
70
223
213
78
68
221
211
76
66
62
9
8
7
6
5
4
2
3
1
0
9
8
6
7
5
4
3
1
2
0
9
8
7
6
5
4
3
2
1
0
9
8
7
6
5
4
3
2
1
0
19
3
11
2
31
30
29
6
14
15
16
18
17
13
12
10
9
8
7
5
4
1
0
28
27
26
25
24
23
22
21
20
18
19
16
17
15
14
13
11
12
10
9
8
7
6
4
5
3
1
2
0
0
4
5
6
0
2
1
3
5
7
6
4
0
2
3
1
7
6
4
5
3
1
2
0
30
31
29
28
26
27
6
4
5
3
1
2
24
25
23
22
21
20
J15 J15J15
1/3
DQ31_A
CB7_A
CB4_A
CB1_A
CB7_B
ALERT_n
CA0_A
CA0_B
CA1_A
CA1_B
CA2_A
CA2_B
CA3_A
CA3_B
CA4_A
CA4_B
CA5_A
CA5_B
CA6_A
CA6_B
CB6_A
CB5_A
CB3_A
CB2_A
CB0_A
CB6_B
CB5_B
CB4_B
CB3_B
CB2_B
CB1_B
CB0_B
CK_c
CK_t
CS0_A_n
CS0_B_n
CS1_A_n
CS1_B_n
DQ30_A
DQ29_A
DQ28_A
DQ27_A
DQ26_A
DQ25_A
DQ24_A
DQ23_A
DQ22_A
DQ21_A
DQ20_A
DQ19_A
DQ18_A
DQ17_A
DQ16_A
DQ15_A
DQ14_A
DQ13_A
DQ12_A
DQ11_A
DQ10_A
DQ9_A
DQ8_A
DQ7_A
DQ6_A
DQ5_A
DQ4_A
DQ3_A
DQ2_A
DQ1_A
DQ0_A
DQ31_B
DQ30_B
DQ29_B
DQ28_B
DQ27_B
DQ26_B
DQ25_B
DQ24_B
DQ23_B
DQ22_B
DQ21_B
DQ20_B
DQ19_B
DQ18_B
DQ17_B
DQ16_B
DQ15_B
DQ14_B
DQ13_B
DQ12_B
DQ11_B
DQ10_B
DQ9_B
DQ8_B
DQ7_B
DQ6_B
DQ5_B
DQ4_B
DQ3_B
DQ2_B
DQ1_B
DQ0_B
HSA
HSCL
HSDA
LBD||RSP_A_n
LBS||RSP_B_n
PAR_A
PAR_B
PWR_GOOD||FAIL_n
RESET_n
RFU6
RFU5
RFU4
RFU3
RFU2
RFU1
RFU0
VIN_MGMT
2/3 3/3
G3
G2
G1
VSS62
VSS61
VSS60
VSS58
VSS104
VSS102
VSS100
VIN_BULK2
VIN_BULK1
VIN_BULK0
VSS126
VSS125
VSS124
VSS123
VSS122
VSS121
VSS120
VSS119
VSS118
VSS117
VSS116
VSS115
VSS114
VSS113
VSS112
VSS111
VSS110
VSS109
VSS108
VSS107
VSS106
VSS105
VSS103
VSS101
VSS99
VSS98
VSS97
VSS96
VSS95
VSS94
VSS93
VSS92
VSS91
VSS90
VSS89
VSS88
VSS87
VSS86
VSS85
VSS84
VSS83
VSS82
VSS81
VSS80
VSS79
VSS78
VSS77
VSS76
VSS75
VSS74
VSS73
VSS72
VSS71
VSS70
VSS69
VSS68
VSS67
VSS66
VSS65
VSS64
VSS63
VSS59
VSS57
VSS56
VSS55
VSS54
VSS53
VSS52
VSS51
VSS50
VSS49
VSS48
VSS47
VSS46
VSS45
VSS44
VSS43
VSS42
VSS41
VSS40
VSS39
VSS38
VSS37
VSS36
VSS35
VSS34
VSS33
VSS32
VSS31
VSS30
VSS29
VSS28
VSS27
VSS26
VSS25
VSS24
VSS23
VSS22
VSS21
VSS20
VSS19
VSS18
VSS17
VSS16
VSS15
VSS14
VSS13
VSS12
VSS11
VSS10
VSS9
VSS8
VSS7
VSS6
VSS5
VSS4
VSS3
VSS2
VSS1
VSS0
21
2
1
2
1
2
1
2
1
CAD NOTE:
SHEETDATE
DEPARTMENT
SIZE
PROJECT DOCUMENT NUMBER REV
REVIEWER
DESIGNER
123
7 3 2 1 6 5 4
E
A
B
C
E
D
C
B
A
7 6 5 4
D
IN
IN
IN
BI
OUTOUT
IN
IN
OUT
IN
IN
IN
OUTOUT
IN
BI
OUTOUT
ININ
ININ
BI
BI
BI
IN
IN
C46C45C44
R40
C



20210728 MODIFY FOR GT
Fri Aug 25 14:01:17 2023N/AN/AN/AN/AV0597 OF 312P12V_S3_AUX_CPU0_NVDIMMP3V3_AUXP3V3_AUX
P12V_S3_AUX_CPU0_NVDIMM
DDR5 - CPU0 CHH DIMM2(BLACK)
97229909192939495962796129949596229909192939495961142796 27 9627 9627 9627 96272727272727279627962727279627 9697
27962796 27 96
PLACE THE BYPASS CAPS CLOSE TO DIMM10UFPD_CHH_CPU0_DIMM2_SAAI3C_SPD_DDREFGH_CPU0_LVC1_SDAI3C_SPD_DDREFGH_CPU0_LVC1_SCL_R8M_H_CPU0_ALERT_NRST_M_GH_CPU0_FPGA_NI3C_SPD_DDREFGH_CPU0_LVC1_SCLCHIPPWRGD_CHH_CPU0_DIMM2TP_CHH_CPU0_DIMM2_FRU_6M_H_CPU0_SB_CB<7:0>M_H_CPU0_SA_DQS_DN<9:0>M_H_CPU0_SA_DQS_DP<9:0>M_H_CPU0_SB_DQS_DP<9:0>M_H_CPU0_SB_DQS_DN<9:0>49.9M_H_CPU0_SA_RSP<1>M_H_CPU0_SB_RSP<1>M_H_CPU0_SB_CS_N<2>M_H_CPU0_CLK_DP<1>M_H_CPU0_SB_CS_N<3>M_H_CPU0_SA_CS_N<3>M_H_CPU0_SB_PARM_H_CPU0_SA_PARM_H_CPU0_SA_CS_N<2>M_H_CPU0_CLK_DN<1>M_H_CPU0_SA_CB<7:0>SCONN288_ADR50017-P087CCSMLFSMLFSCONN288_ADR50017-P087CC
TP_CHH_CPU0_DIMM2_FRU_5TP_CHH_CPU0_DIMM2_FRU_4TP_CHH_CPU0_DIMM2_FRU_3TP_CHH_CPU0_DIMM2_FRU_2TP_CHH_CPU0_DIMM2_FRU_1TP_CHH_CPU0_DIMM2_FRU_0
IOM_H_CPU0_SB_DQ<31:0>IOSCONN288_ADR50017-P087CCIOSMLF
1%1/16W0402LFCHIP196KX6S10%16V10UFC0805X6SC080516V10%PD_CHH_CPU0_DIMM2_SAA
M_H_CPU0_SB_CA<6:0>M_H_CPU0_SA_CA<6:0> M_H_CPU0_SA_DQ<31:0>
2.2UF6.3V20%C0402X6S
DQS7_A_c||TDQS7_A_c
DQS6_A_t||TDQS6_A_t
DQS8_B_t||TDQS8_B_t
DQS8_B_c||TDQS8_B_c
DQS7_B_t||TDQS7_B_t
DQS0_A_c
DQS0_A_t
DQS0_B_c
DQS0_B_t
DQS1_A_c
DQS1_A_t
DQS1_B_c
DQS1_B_t
DQS2_A_c
DQS2_A_t
DQS2_B_c
DQS2_B_t
DQS3_A_c
DQS3_A_t
DQS3_B_c
DQS3_B_t
DQS4_A_c
DQS4_A_t
DQS4_B_c
DQS4_B_t
DQS5_A_c||TDQS5_A_c||DQS5_A_t||TDQS5_A_t
DQS5_A_t||TDQS5_A_t
DQS5_B_c||TDQS5_B_c
DQS5_B_t||TDQS5_B_t
DQS6_A_c||TDQS6_A_c||DQS6_A_t||TDQS6_A_t
DQS6_B_c||TDQS6_B_c
DQS6_B_t||TDQS6_B_t
DQS7_A_t||TDQS7_A_t
DQS7_B_c||TDQS7_B_c
DQS8_A_c||TDQS8_A_c
DQS8_A_t||TDQS8_A_t
DQS9_A_c||TDQS9_A_c
DQS9_A_t||TDQS9_A_t
DQS9_B_c||TDQS9_B_c
DQS9_B_t||TDQS9_B_t||DBI4_B_n
R3890
93
94
201
200
283
282
190
189
272
271
179
178
261
260
168
167
250
249
157
156
239
238
55
56
137
138
44
45
126
127
33
34
115
116
22
23
104
105
11
12
288
286
284
281
279
277
275
273
270
268
266
264
262
259
257
255
253
251
248
246
244
242
240
237
235
233
230
228
226
224
222
219
216
214
212
210
208
206
204
202
199
197
195
193
191
188
186
184
182
180
177
175
173
171
169
166
164
162
160
158
155
153
151
143
141
139
136
134
132
130
128
125
123
121
119
117
114
112
110
108
106
103
101
99
97
95
92
90
88
85
83
81
79
77
75
73
71
69
67
65
63
61
59
57
54
52
50
48
46
43
41
39
37
35
32
30
28
26
24
21
19
17
15
13
10
8
6
146
145
1
G3
G2
G1
3
232
231
220
150
149
144
2
207
147
227
74
87
86
5
4
148
287
194
285
192
142
49
140
47
280
187
278
185
135
42
133
40
276
183
274
181
131
38
129
36
269
176
267
174
124
31
122
29
265
172
263
170
120
27
118
25
258
165
256
163
113
20
111
18
254
161
252
159
109
16
107
14
247
154
245
152
102
9
100
7
229
209
84
64
217
218
236
205
234
203
91
60
89
58
243
198
241
196
98
53
96
51
82
72
225
215
80
70
223
213
78
68
221
211
76
66
62
0
9
8
7
5
6
4
3
2
0
1
9
8
7
6
4
5
3
2
0
1
9
8
7
6
5
4
3
2
1
0
9
8
7
6
5
4
3
2
1
0
17
11
25
18
17
20
5
23
14
16
2
31
0
30
29
27
28
26
25
24
21
22
20
19
18
16
15
13
14
12
10
8
9
6
7
4
5
3
2
1
0
6
4
5
3
2
1
0
6
4
5
2
3
0
1
7
5
6
4
2
3
1
0
7
6
4
5
3
1
2
30
29
31
27
28
26
24
23
21
22
19
15
13
11
12
9
10
8
6
7
4
3
1
J16
J16J16
3/3
G3
G2
G1
VSS62
VSS61
VSS60
VSS58
VSS104
VSS102
VSS100
VIN_BULK2
VIN_BULK1
VIN_BULK0
VSS126
VSS125
VSS124
VSS123
VSS122
VSS121
VSS120
VSS119
VSS118
VSS117
VSS116
VSS115
VSS114
VSS113
VSS112
VSS111
VSS110
VSS109
VSS108
VSS107
VSS106
VSS105
VSS103
VSS101
VSS99
VSS98
VSS97
VSS96
VSS95
VSS94
VSS93
VSS92
VSS91
VSS90
VSS89
VSS88
VSS87
VSS86
VSS85
VSS84
VSS83
VSS82
VSS81
VSS80
VSS79
VSS78
VSS77
VSS76
VSS75
VSS74
VSS73
VSS72
VSS71
VSS70
VSS69
VSS68
VSS67
VSS66
VSS65
VSS64
VSS63
VSS59
VSS57
VSS56
VSS55
VSS54
VSS53
VSS52
VSS51
VSS50
VSS49
VSS48
VSS47
VSS46
VSS45
VSS44
VSS43
VSS42
VSS41
VSS40
VSS39
VSS38
VSS37
VSS36
VSS35
VSS34
VSS33
VSS32
VSS31
VSS30
VSS29
VSS28
VSS27
VSS26
VSS25
VSS24
VSS23
VSS22
VSS21
VSS20
VSS19
VSS18
VSS17
VSS16
VSS15
VSS14
VSS13
VSS12
VSS11
VSS10
VSS9
VSS8
VSS7
VSS6
VSS5
VSS4
VSS3
VSS2
VSS1
VSS0
1/3
DQ31_A
CB7_A
CB4_A
CB1_A
CB7_B
ALERT_n
CA0_A
CA0_B
CA1_A
CA1_B
CA2_A
CA2_B
CA3_A
CA3_B
CA4_A
CA4_B
CA5_A
CA5_B
CA6_A
CA6_B
CB6_A
CB5_A
CB3_A
CB2_A
CB0_A
CB6_B
CB5_B
CB4_B
CB3_B
CB2_B
CB1_B
CB0_B
CK_c
CK_t
CS0_A_n
CS0_B_n
CS1_A_n
CS1_B_n
DQ30_A
DQ29_A
DQ28_A
DQ27_A
DQ26_A
DQ25_A
DQ24_A
DQ23_A
DQ22_A
DQ21_A
DQ20_A
DQ19_A
DQ18_A
DQ17_A
DQ16_A
DQ15_A
DQ14_A
DQ13_A
DQ12_A
DQ11_A
DQ10_A
DQ9_A
DQ8_A
DQ7_A
DQ6_A
DQ5_A
DQ4_A
DQ3_A
DQ2_A
DQ1_A
DQ0_A
DQ31_B
DQ30_B
DQ29_B
DQ28_B
DQ27_B
DQ26_B
DQ25_B
DQ24_B
DQ23_B
DQ22_B
DQ21_B
DQ20_B
DQ19_B
DQ18_B
DQ17_B
DQ16_B
DQ15_B
DQ14_B
DQ13_B
DQ12_B
DQ11_B
DQ10_B
DQ9_B
DQ8_B
DQ7_B
DQ6_B
DQ5_B
DQ4_B
DQ3_B
DQ2_B
DQ1_B
DQ0_B
HSA
HSCL
HSDA
LBD||RSP_A_n
LBS||RSP_B_n
PAR_A
PAR_B
PWR_GOOD||FAIL_n
RESET_n
RFU6
RFU5
RFU4
RFU3
RFU2
RFU1
RFU0
VIN_MGMT
2/3
21
2
1
2
1
2
1
2
1
CAD NOTE:
SHEETDATE
DEPARTMENT
SIZE
PROJECT DOCUMENT NUMBER REV
REVIEWER
DESIGNER
123
7 3 2 1 6 5 4
E
A
B
C
E
D
C
B
A
7 6 5 4
D
IN
IN
BI
OUT
IN
IN
ININ
IN
OUT
IN
IN
IN
OUTOUT
OUTOUT
IN
ININ
BI
BI
BI
IN
IN
BI
OUT
C49C48C47
R41
C



20210728 MODIFY FOR GT
N/AN/AN/AFri Aug 25 14:01:18 2023N/A98 OF 312V05
P3V3_AUXP12V_S3_AUX_CPU1_NVDIMM
P12V_S3_AUX_CPU1_NVDIMMP3V3_AUXDDR5 - CPU1 CHA DIMM1(YELLOW)
98230991001011021031041055199130991001012309910010110210310410511451 519951995199519951995151515151515151995199
9851995199519951995199PD_CHA_CPU1_DIMM1_SAAI3C_SPD_DDRABCD_CPU1_LVC1_SDAI3C_SPD_DDRABCD_CPU1_LVC1_SCL_R1M_A_CPU1_ALERT_NRST_M_AB_CPU1_FPGA_NCHIPI3C_SPD_DDRABCD_CPU1_LVC1_SCL49.9PWRGD_CHA_CPU1_DIMM1M_A_CPU1_SA_CS_N<1>M_A_CPU1_SA_DQS_DP<9:0>M_A_CPU1_SA_DQS_DN<9:0>M_A_CPU1_SB_DQS_DN<9:0>M_A_CPU1_SB_DQS_DP<9:0>TP_CHA_CPU1_DIMM1_FRU_6TP_CHA_CPU1_DIMM1_FRU_5TP_CHA_CPU1_DIMM1_FRU_4TP_CHA_CPU1_DIMM1_FRU_3
SMLFSCONN288_ADR50017-P130CCSCONN288_ADR50017-P130CCSMLFSCONN288_ADR50017-P130CCSMLFIOM_A_CPU1_SA_CB<7:0>M_A_CPU1_CLK_DN<0>M_A_CPU1_CLK_DP<0>M_A_CPU1_SA_CS_N<0>M_A_CPU1_SB_CS_N<0>M_A_CPU1_SB_CS_N<1>M_A_CPU1_SA_RSP<0>M_A_CPU1_SB_RSP<0>M_A_CPU1_SA_PARM_A_CPU1_SB_PARTP_CHA_CPU1_DIMM1_FRU_2TP_CHA_CPU1_DIMM1_FRU_1TP_CHA_CPU1_DIMM1_FRU_0
IO IO
10K0402LFCHIP1%1/16WX6SC080510UF16V10%X6S16V10UF10%C0805PD_CHA_CPU1_DIMM1_SAAM_A_CPU1_SB_DQ<31:0>M_A_CPU1_SB_CA<6:0>M_A_CPU1_SA_CA<6:0>M_A_CPU1_SB_CB<7:0>M_A_CPU1_SA_DQ<31:0>
PLACE THE BYPASS CAPS CLOSE TO DIMMC040220%6.3VX6S2.2UF
DQS7_A_c||TDQS7_A_c
DQS6_A_t||TDQS6_A_t
DQS8_B_t||TDQS8_B_t
DQS8_B_c||TDQS8_B_c
DQS7_B_t||TDQS7_B_t
DQS0_A_c
DQS0_A_t
DQS0_B_c
DQS0_B_t
DQS1_A_c
DQS1_A_t
DQS1_B_c
DQS1_B_t
DQS2_A_c
DQS2_A_t
DQS2_B_c
DQS2_B_t
DQS3_A_c
DQS3_A_t
DQS3_B_c
DQS3_B_t
DQS4_A_c
DQS4_A_t
DQS4_B_c
DQS4_B_t
DQS5_A_c||TDQS5_A_c||DQS5_A_t||TDQS5_A_t
DQS5_A_t||TDQS5_A_t
DQS5_B_c||TDQS5_B_c
DQS5_B_t||TDQS5_B_t
DQS6_A_c||TDQS6_A_c||DQS6_A_t||TDQS6_A_t
DQS6_B_c||TDQS6_B_c
DQS6_B_t||TDQS6_B_t
DQS7_A_t||TDQS7_A_t
DQS7_B_c||TDQS7_B_c
DQS8_A_c||TDQS8_A_c
DQS8_A_t||TDQS8_A_t
DQS9_A_c||TDQS9_A_c
DQS9_A_t||TDQS9_A_t
DQS9_B_c||TDQS9_B_c
DQS9_B_t||TDQS9_B_t||DBI4_B_n
R3891
93
94
201
200
283
282
190
189
272
271
179
178
261
260
168
167
250
249
157
156
239
238
55
56
137
138
44
45
126
127
33
34
115
116
22
23
104
105
11
12
288
286
284
281
279
277
275
273
270
268
266
264
262
259
257
255
253
251
248
246
244
242
240
237
235
233
230
228
226
224
222
219
216
214
212
210
208
206
204
202
199
197
195
193
191
188
186
184
182
180
177
175
173
171
169
166
164
162
160
158
155
153
151
143
141
139
136
134
132
130
128
125
123
121
119
117
114
112
110
108
106
103
101
99
97
95
92
90
88
85
83
81
79
77
75
73
71
69
67
65
63
61
59
57
54
52
50
48
46
43
41
39
37
35
32
30
28
26
24
21
19
17
15
13
10
8
6
146
145
1
G3
G2
G1
3
232
231
220
150
149
144
2
207
147
227
74
87
86
5
4
148
287
194
285
192
142
49
140
47
280
187
278
185
135
42
133
40
276
183
274
181
131
38
129
36
269
176
267
174
124
31
122
29
265
172
263
170
120
27
118
25
258
165
256
163
113
20
111
18
254
161
252
159
109
16
107
14
247
154
245
152
102
9
100
7
229
209
84
64
217
218
236
205
234
203
91
60
89
58
243
198
241
196
98
53
96
51
82
72
225
215
80
70
223
213
78
68
221
211
76
66
62
9
8
6
7
5
4
3
1
2
0
9
8
7
5
6
4
3
2
0
1
9
8
7
6
5
4
3
2
1
0
9
8
7
6
5
4
3
2
1
0
2
31
9
12
3
19
15
16
14
13
10
11
9
7
8
6
5
4
2
1
0
30
29
28
27
26
25
22
24
23
20
21
19
18
17
16
15
14
13
12
11
10
8
7
4
5
6
2
3
1
0
0
1
5
6
3
4
0
1
2
6
7
5
4
3
2
1
0
7
5
6
4
3
0
1
31
30
28
27
29
5
6
4
3
2
26
25
24
23
22
21
20
17
18
J17 J17J17
2/3 3/3
G3
G2
G1
VSS62
VSS61
VSS60
VSS58
VSS104
VSS102
VSS100
VIN_BULK2
VIN_BULK1
VIN_BULK0
VSS126
VSS125
VSS124
VSS123
VSS122
VSS121
VSS120
VSS119
VSS118
VSS117
VSS116
VSS115
VSS114
VSS113
VSS112
VSS111
VSS110
VSS109
VSS108
VSS107
VSS106
VSS105
VSS103
VSS101
VSS99
VSS98
VSS97
VSS96
VSS95
VSS94
VSS93
VSS92
VSS91
VSS90
VSS89
VSS88
VSS87
VSS86
VSS85
VSS84
VSS83
VSS82
VSS81
VSS80
VSS79
VSS78
VSS77
VSS76
VSS75
VSS74
VSS73
VSS72
VSS71
VSS70
VSS69
VSS68
VSS67
VSS66
VSS65
VSS64
VSS63
VSS59
VSS57
VSS56
VSS55
VSS54
VSS53
VSS52
VSS51
VSS50
VSS49
VSS48
VSS47
VSS46
VSS45
VSS44
VSS43
VSS42
VSS41
VSS40
VSS39
VSS38
VSS37
VSS36
VSS35
VSS34
VSS33
VSS32
VSS31
VSS30
VSS29
VSS28
VSS27
VSS26
VSS25
VSS24
VSS23
VSS22
VSS21
VSS20
VSS19
VSS18
VSS17
VSS16
VSS15
VSS14
VSS13
VSS12
VSS11
VSS10
VSS9
VSS8
VSS7
VSS6
VSS5
VSS4
VSS3
VSS2
VSS1
VSS0
1/3
DQ31_A
CB7_A
CB4_A
CB1_A
CB7_B
ALERT_n
CA0_A
CA0_B
CA1_A
CA1_B
CA2_A
CA2_B
CA3_A
CA3_B
CA4_A
CA4_B
CA5_A
CA5_B
CA6_A
CA6_B
CB6_A
CB5_A
CB3_A
CB2_A
CB0_A
CB6_B
CB5_B
CB4_B
CB3_B
CB2_B
CB1_B
CB0_B
CK_c
CK_t
CS0_A_n
CS0_B_n
CS1_A_n
CS1_B_n
DQ30_A
DQ29_A
DQ28_A
DQ27_A
DQ26_A
DQ25_A
DQ24_A
DQ23_A
DQ22_A
DQ21_A
DQ20_A
DQ19_A
DQ18_A
DQ17_A
DQ16_A
DQ15_A
DQ14_A
DQ13_A
DQ12_A
DQ11_A
DQ10_A
DQ9_A
DQ8_A
DQ7_A
DQ6_A
DQ5_A
DQ4_A
DQ3_A
DQ2_A
DQ1_A
DQ0_A
DQ31_B
DQ30_B
DQ29_B
DQ28_B
DQ27_B
DQ26_B
DQ25_B
DQ24_B
DQ23_B
DQ22_B
DQ21_B
DQ20_B
DQ19_B
DQ18_B
DQ17_B
DQ16_B
DQ15_B
DQ14_B
DQ13_B
DQ12_B
DQ11_B
DQ10_B
DQ9_B
DQ8_B
DQ7_B
DQ6_B
DQ5_B
DQ4_B
DQ3_B
DQ2_B
DQ1_B
DQ0_B
HSA
HSCL
HSDA
LBD||RSP_A_n
LBS||RSP_B_n
PAR_A
PAR_B
PWR_GOOD||FAIL_n
RESET_n
RFU6
RFU5
RFU4
RFU3
RFU2
RFU1
RFU0
VIN_MGMT
21
2
1
2
1
2
1
2
1
CAD NOTE:
SHEETDATE
DEPARTMENT
SIZE
PROJECT DOCUMENT NUMBER REV
REVIEWER
DESIGNER
123
7 3 2 1 6 5 4
E
A
B
C
E
D
C
B
A
7 6 5 4
D
IN
ININ
BI
OUTOUT
IN
ININ
IN
IN
OUT
IN
IN
IN
OUTOUT
IN
BI
OUTOUT
IN
BI
BI
BI
IN
IN
C52C51C50
R42
C



20210728 MODIFY FOR GT
Fri Aug 25 14:01:19 2023N/AN/AN/AN/AV0599 OF 312
P3V3_AUXP12V_S3_AUX_CPU1_NVDIMM
P12V_S3_AUX_CPU1_NVDIMMP3V3_AUXDDR5 - CPU1 CHA DIMM2(BLACK)
515198519851985198519899
5198519851515151515198 51985198519851985151114230981001011021031041055198130981001012309810010110210310410599 X6SM_A_CPU1_CLK_DP<1>C04026.3VX6S20%2.2UFPLACE THE BYPASS CAPS CLOSE TO DIMM
M_A_CPU1_SA_DQ<31:0>M_A_CPU1_SA_CB<7:0>M_A_CPU1_SA_CA<6:0>M_A_CPU1_SB_CA<6:0>M_A_CPU1_SB_DQ<31:0>PD_CHA_CPU1_DIMM2_SAA16V10%C080510UF10%16VC080510UFX6S1/16W15.4K1%CHIP0402LF
IOSCONN288_ADR50017-P087CCIO
TP_CHA_CPU1_DIMM2_FRU_0TP_CHA_CPU1_DIMM2_FRU_1TP_CHA_CPU1_DIMM2_FRU_2TP_CHA_CPU1_DIMM2_FRU_3TP_CHA_CPU1_DIMM2_FRU_4TP_CHA_CPU1_DIMM2_FRU_5TP_CHA_CPU1_DIMM2_FRU_6M_A_CPU1_SB_PARM_A_CPU1_SA_PARM_A_CPU1_SB_RSP<1>M_A_CPU1_SA_RSP<1>M_A_CPU1_SA_CS_N<3>M_A_CPU1_SA_CS_N<2>M_A_CPU1_CLK_DN<1>SCONN288_ADR50017-P087CCSMLFSMLFSMLFSCONN288_ADR50017-P087CCIOM_A_CPU1_SB_CB<7:0>M_A_CPU1_SB_DQS_DN<9:0>M_A_CPU1_SB_DQS_DP<9:0>M_A_CPU1_SA_DQS_DN<9:0>M_A_CPU1_SA_DQS_DP<9:0>M_A_CPU1_SB_CS_N<3>M_A_CPU1_SB_CS_N<2>PWRGD_CHA_CPU1_DIMM2CHIP49.9I3C_SPD_DDRABCD_CPU1_LVC1_SCLM_A_CPU1_ALERT_NRST_M_AB_CPU1_FPGA_NI3C_SPD_DDRABCD_CPU1_LVC1_SCL_R2I3C_SPD_DDRABCD_CPU1_LVC1_SDAPD_CHA_CPU1_DIMM2_SAA
DQS7_A_c||TDQS7_A_c
DQS6_A_t||TDQS6_A_t
DQS8_B_t||TDQS8_B_t
DQS8_B_c||TDQS8_B_c
DQS7_B_t||TDQS7_B_t
DQS0_A_c
DQS0_A_t
DQS0_B_c
DQS0_B_t
DQS1_A_c
DQS1_A_t
DQS1_B_c
DQS1_B_t
DQS2_A_c
DQS2_A_t
DQS2_B_c
DQS2_B_t
DQS3_A_c
DQS3_A_t
DQS3_B_c
DQS3_B_t
DQS4_A_c
DQS4_A_t
DQS4_B_c
DQS4_B_t
DQS5_A_c||TDQS5_A_c||DQS5_A_t||TDQS5_A_t
DQS5_A_t||TDQS5_A_t
DQS5_B_c||TDQS5_B_c
DQS5_B_t||TDQS5_B_t
DQS6_A_c||TDQS6_A_c||DQS6_A_t||TDQS6_A_t
DQS6_B_c||TDQS6_B_c
DQS6_B_t||TDQS6_B_t
DQS7_A_t||TDQS7_A_t
DQS7_B_c||TDQS7_B_c
DQS8_A_c||TDQS8_A_c
DQS8_A_t||TDQS8_A_t
DQS9_A_c||TDQS9_A_c
DQS9_A_t||TDQS9_A_t
DQS9_B_c||TDQS9_B_c
DQS9_B_t||TDQS9_B_t||DBI4_B_n
R3892
93
94
201
200
283
282
190
189
272
271
179
178
261
260
168
167
250
249
157
156
239
238
55
56
137
138
44
45
126
127
33
34
115
116
22
23
104
105
11
12
288
286
284
281
279
277
275
273
270
268
266
264
262
259
257
255
253
251
248
246
244
242
240
237
235
233
230
228
226
224
222
219
216
214
212
210
208
206
204
202
199
197
195
193
191
188
186
184
182
180
177
175
173
171
169
166
164
162
160
158
155
153
151
143
141
139
136
134
132
130
128
125
123
121
119
117
114
112
110
108
106
103
101
99
97
95
92
90
88
85
83
81
79
77
75
73
71
69
67
65
63
61
59
57
54
52
50
48
46
43
41
39
37
35
32
30
28
26
24
21
19
17
15
13
10
8
6
146
145
1
G3
G2
G1
3
232
231
220
150
149
144
2
207
147
227
74
87
86
5
4
148
287
194
285
192
142
49
140
47
280
187
278
185
135
42
133
40
276
183
274
181
131
38
129
36
269
176
267
174
124
31
122
29
265
172
263
170
120
27
118
25
258
165
256
163
113
20
111
18
254
161
252
159
109
16
107
14
247
154
245
152
102
9
100
7
229
209
84
64
217
218
236
205
234
203
91
60
89
58
243
198
241
196
98
53
96
51
82
72
225
215
80
70
223
213
78
68
221
211
76
66
62
16
18
17
19
21
20
23
22
25
24
26
27
28
5
4
6
29
30
31
0
0
1
3
2
4
5
6
7
8
9
10
11
12
13
15
14
17
16
18
19
20
1
2
3
4
5
6
7
0
1
2
4
3
5
6
7
1
0
2
3
4
5
6
0
1
3
2
22
21
23
24
25
26
28
27
29
31
30
0
2
1
3
5
4
7
6
8
9
10
11
13
12
14
15
0
1
3
2
4
5
6
7
8
9
0
1
2
3
4
5
6
7
8
9
1
0
2
3
5
6
7
8
9
0
1
2
3
4
6
5
7
8
9
4
J18
J18J18
1/3
DQ31_A
CB7_A
CB4_A
CB1_A
CB7_B
ALERT_n
CA0_A
CA0_B
CA1_A
CA1_B
CA2_A
CA2_B
CA3_A
CA3_B
CA4_A
CA4_B
CA5_A
CA5_B
CA6_A
CA6_B
CB6_A
CB5_A
CB3_A
CB2_A
CB0_A
CB6_B
CB5_B
CB4_B
CB3_B
CB2_B
CB1_B
CB0_B
CK_c
CK_t
CS0_A_n
CS0_B_n
CS1_A_n
CS1_B_n
DQ30_A
DQ29_A
DQ28_A
DQ27_A
DQ26_A
DQ25_A
DQ24_A
DQ23_A
DQ22_A
DQ21_A
DQ20_A
DQ19_A
DQ18_A
DQ17_A
DQ16_A
DQ15_A
DQ14_A
DQ13_A
DQ12_A
DQ11_A
DQ10_A
DQ9_A
DQ8_A
DQ7_A
DQ6_A
DQ5_A
DQ4_A
DQ3_A
DQ2_A
DQ1_A
DQ0_A
DQ31_B
DQ30_B
DQ29_B
DQ28_B
DQ27_B
DQ26_B
DQ25_B
DQ24_B
DQ23_B
DQ22_B
DQ21_B
DQ20_B
DQ19_B
DQ18_B
DQ17_B
DQ16_B
DQ15_B
DQ14_B
DQ13_B
DQ12_B
DQ11_B
DQ10_B
DQ9_B
DQ8_B
DQ7_B
DQ6_B
DQ5_B
DQ4_B
DQ3_B
DQ2_B
DQ1_B
DQ0_B
HSA
HSCL
HSDA
LBD||RSP_A_n
LBS||RSP_B_n
PAR_A
PAR_B
PWR_GOOD||FAIL_n
RESET_n
RFU6
RFU5
RFU4
RFU3
RFU2
RFU1
RFU0
VIN_MGMT
2/3 3/3
G3
G2
G1
VSS62
VSS61
VSS60
VSS58
VSS104
VSS102
VSS100
VIN_BULK2
VIN_BULK1
VIN_BULK0
VSS126
VSS125
VSS124
VSS123
VSS122
VSS121
VSS120
VSS119
VSS118
VSS117
VSS116
VSS115
VSS114
VSS113
VSS112
VSS111
VSS110
VSS109
VSS108
VSS107
VSS106
VSS105
VSS103
VSS101
VSS99
VSS98
VSS97
VSS96
VSS95
VSS94
VSS93
VSS92
VSS91
VSS90
VSS89
VSS88
VSS87
VSS86
VSS85
VSS84
VSS83
VSS82
VSS81
VSS80
VSS79
VSS78
VSS77
VSS76
VSS75
VSS74
VSS73
VSS72
VSS71
VSS70
VSS69
VSS68
VSS67
VSS66
VSS65
VSS64
VSS63
VSS59
VSS57
VSS56
VSS55
VSS54
VSS53
VSS52
VSS51
VSS50
VSS49
VSS48
VSS47
VSS46
VSS45
VSS44
VSS43
VSS42
VSS41
VSS40
VSS39
VSS38
VSS37
VSS36
VSS35
VSS34
VSS33
VSS32
VSS31
VSS30
VSS29
VSS28
VSS27
VSS26
VSS25
VSS24
VSS23
VSS22
VSS21
VSS20
VSS19
VSS18
VSS17
VSS16
VSS15
VSS14
VSS13
VSS12
VSS11
VSS10
VSS9
VSS8
VSS7
VSS6
VSS5
VSS4
VSS3
VSS2
VSS1
VSS0
21
2
1
2
1
2
1
2
1
CAD NOTE:
SHEETDATE
DEPARTMENT
SIZE
PROJECT DOCUMENT NUMBER REV
REVIEWER
DESIGNER
123
7 3 2 1 6 5 4
E
A
B
C
E
D
C
B
A
7 6 5 4
D
ININ
BI
OUTOUT
OUT
IN
ININ
ININ
IN
IN
OUTOUT
IN
BI
OUTOUT
ININ
BI
BI
BI
IN
IN
IN
C55C54C53
C
R43



20210728 MODIFY FOR GT
Fri Aug 25 14:01:20 2023N/A100 OF 312V05N/AN/AN/AP3V3_AUX P12V_S3_AUX_CPU1_NVDIMM
P12V_S3_AUX_CPU1_NVDIMMP3V3_AUX
DDR5 - CPU1 CHB DIMM1(YELLOW)
1309899101230989910110210310410510052101230989910110210310410511452 10152 10152 10152 101525210152525252525252521015210152101100521015210152101 52101
PLACE THE BYPASS CAPS CLOSE TO DIMMRST_M_AB_CPU1_FPGA_NI3C_SPD_DDRABCD_CPU1_LVC1_SDAI3C_SPD_DDRABCD_CPU1_LVC1_SCL_R3PD_CHB_CPU1_DIMM1_SAAM_B_CPU1_ALERT_NI3C_SPD_DDRABCD_CPU1_LVC1_SCL49.9CHIPPWRGD_CHB_CPU1_DIMM1TP_CHB_CPU1_DIMM1_FRU_6TP_CHB_CPU1_DIMM1_FRU_5TP_CHB_CPU1_DIMM1_FRU_4TP_CHB_CPU1_DIMM1_FRU_3TP_CHB_CPU1_DIMM1_FRU_2TP_CHB_CPU1_DIMM1_FRU_1TP_CHB_CPU1_DIMM1_FRU_0
M_B_CPU1_SA_DQS_DP<9:0>M_B_CPU1_SA_DQS_DN<9:0>M_B_CPU1_SB_DQS_DP<9:0>M_B_CPU1_SB_DQS_DN<9:0>SCONN288_ADR50017-P130CCSMLFSCONN288_ADR50017-P130CCSMLF SMLFSCONN288_ADR50017-P130CCM_B_CPU1_CLK_DN<0>M_B_CPU1_SA_CB<7:0>IOM_B_CPU1_CLK_DP<0>M_B_CPU1_SA_CS_N<0>M_B_CPU1_SB_CS_N<0>M_B_CPU1_SA_CS_N<1>M_B_CPU1_SB_CS_N<1>M_B_CPU1_SA_RSP<0>M_B_CPU1_SB_RSP<0>M_B_CPU1_SA_PARM_B_CPU1_SB_PARIOM_B_CPU1_SB_CB<7:0>IO
0402LF1/16WCHIP1%23.2KX6S10UF16V10%C0805X6S10UF16V10%C0805PD_CHB_CPU1_DIMM1_SAAM_B_CPU1_SB_DQ<31:0>M_B_CPU1_SB_CA<6:0>M_B_CPU1_SA_CA<6:0> M_B_CPU1_SA_DQ<31:0>
C04026.3V2.2UF20%X6S
DQS7_A_c||TDQS7_A_c
DQS6_A_t||TDQS6_A_t
DQS8_B_t||TDQS8_B_t
DQS8_B_c||TDQS8_B_c
DQS7_B_t||TDQS7_B_t
DQS0_A_c
DQS0_A_t
DQS0_B_c
DQS0_B_t
DQS1_A_c
DQS1_A_t
DQS1_B_c
DQS1_B_t
DQS2_A_c
DQS2_A_t
DQS2_B_c
DQS2_B_t
DQS3_A_c
DQS3_A_t
DQS3_B_c
DQS3_B_t
DQS4_A_c
DQS4_A_t
DQS4_B_c
DQS4_B_t
DQS5_A_c||TDQS5_A_c||DQS5_A_t||TDQS5_A_t
DQS5_A_t||TDQS5_A_t
DQS5_B_c||TDQS5_B_c
DQS5_B_t||TDQS5_B_t
DQS6_A_c||TDQS6_A_c||DQS6_A_t||TDQS6_A_t
DQS6_B_c||TDQS6_B_c
DQS6_B_t||TDQS6_B_t
DQS7_A_t||TDQS7_A_t
DQS7_B_c||TDQS7_B_c
DQS8_A_c||TDQS8_A_c
DQS8_A_t||TDQS8_A_t
DQS9_A_c||TDQS9_A_c
DQS9_A_t||TDQS9_A_t
DQS9_B_c||TDQS9_B_c
DQS9_B_t||TDQS9_B_t||DBI4_B_n
R3893
93
94
201
200
283
282
190
189
272
271
179
178
261
260
168
167
250
249
157
156
239
238
55
56
137
138
44
45
126
127
33
34
115
116
22
23
104
105
11
12
288
286
284
281
279
277
275
273
270
268
266
264
262
259
257
255
253
251
248
246
244
242
240
237
235
233
230
228
226
224
222
219
216
214
212
210
208
206
204
202
199
197
195
193
191
188
186
184
182
180
177
175
173
171
169
166
164
162
160
158
155
153
151
143
141
139
136
134
132
130
128
125
123
121
119
117
114
112
110
108
106
103
101
99
97
95
92
90
88
85
83
81
79
77
75
73
71
69
67
65
63
61
59
57
54
52
50
48
46
43
41
39
37
35
32
30
28
26
24
21
19
17
15
13
10
8
6
146
145
1
G3
G2
G1
3
232
231
220
150
149
144
2
207
147
227
74
87
86
5
4
148
287
194
285
192
142
49
140
47
280
187
278
185
135
42
133
40
276
183
274
181
131
38
129
36
269
176
267
174
124
31
122
29
265
172
263
170
120
27
118
25
258
165
256
163
113
20
111
18
254
161
252
159
109
16
107
14
247
154
245
152
102
9
100
7
229
209
84
64
217
218
236
205
234
203
91
60
89
58
243
198
241
196
98
53
96
51
82
72
225
215
80
70
223
213
78
68
221
211
76
66
62
3
8
9
7
6
5
4
3
2
1
0
9
8
7
6
5
4
2
0
1
9
8
7
6
5
4
3
2
1
0
9
8
7
6
5
4
3
2
1
0
28
4
29
2
24
13
12
4
12
13
8
7
9
6
5
2
3
1
0
27
28
30
31
5
6
4
3
2
1
0
6
5
3
4
0
1
2
6
7
5
3
2
1
0
7
23
22
26
25
17
18
19
20
21
14
16
15
10
11
9
8
7
6
4
5
2
3
0
1
5
6
4
3
0
1
30
31
25
26
29
27
20
21
22
24
23
17
16
15
18
19
11
10
14
J19 J19J19
1/3
DQ31_A
CB7_A
CB4_A
CB1_A
CB7_B
ALERT_n
CA0_A
CA0_B
CA1_A
CA1_B
CA2_A
CA2_B
CA3_A
CA3_B
CA4_A
CA4_B
CA5_A
CA5_B
CA6_A
CA6_B
CB6_A
CB5_A
CB3_A
CB2_A
CB0_A
CB6_B
CB5_B
CB4_B
CB3_B
CB2_B
CB1_B
CB0_B
CK_c
CK_t
CS0_A_n
CS0_B_n
CS1_A_n
CS1_B_n
DQ30_A
DQ29_A
DQ28_A
DQ27_A
DQ26_A
DQ25_A
DQ24_A
DQ23_A
DQ22_A
DQ21_A
DQ20_A
DQ19_A
DQ18_A
DQ17_A
DQ16_A
DQ15_A
DQ14_A
DQ13_A
DQ12_A
DQ11_A
DQ10_A
DQ9_A
DQ8_A
DQ7_A
DQ6_A
DQ5_A
DQ4_A
DQ3_A
DQ2_A
DQ1_A
DQ0_A
DQ31_B
DQ30_B
DQ29_B
DQ28_B
DQ27_B
DQ26_B
DQ25_B
DQ24_B
DQ23_B
DQ22_B
DQ21_B
DQ20_B
DQ19_B
DQ18_B
DQ17_B
DQ16_B
DQ15_B
DQ14_B
DQ13_B
DQ12_B
DQ11_B
DQ10_B
DQ9_B
DQ8_B
DQ7_B
DQ6_B
DQ5_B
DQ4_B
DQ3_B
DQ2_B
DQ1_B
DQ0_B
HSA
HSCL
HSDA
LBD||RSP_A_n
LBS||RSP_B_n
PAR_A
PAR_B
PWR_GOOD||FAIL_n
RESET_n
RFU6
RFU5
RFU4
RFU3
RFU2
RFU1
RFU0
VIN_MGMT
2/3 3/3
G3
G2
G1
VSS62
VSS61
VSS60
VSS58
VSS104
VSS102
VSS100
VIN_BULK2
VIN_BULK1
VIN_BULK0
VSS126
VSS125
VSS124
VSS123
VSS122
VSS121
VSS120
VSS119
VSS118
VSS117
VSS116
VSS115
VSS114
VSS113
VSS112
VSS111
VSS110
VSS109
VSS108
VSS107
VSS106
VSS105
VSS103
VSS101
VSS99
VSS98
VSS97
VSS96
VSS95
VSS94
VSS93
VSS92
VSS91
VSS90
VSS89
VSS88
VSS87
VSS86
VSS85
VSS84
VSS83
VSS82
VSS81
VSS80
VSS79
VSS78
VSS77
VSS76
VSS75
VSS74
VSS73
VSS72
VSS71
VSS70
VSS69
VSS68
VSS67
VSS66
VSS65
VSS64
VSS63
VSS59
VSS57
VSS56
VSS55
VSS54
VSS53
VSS52
VSS51
VSS50
VSS49
VSS48
VSS47
VSS46
VSS45
VSS44
VSS43
VSS42
VSS41
VSS40
VSS39
VSS38
VSS37
VSS36
VSS35
VSS34
VSS33
VSS32
VSS31
VSS30
VSS29
VSS28
VSS27
VSS26
VSS25
VSS24
VSS23
VSS22
VSS21
VSS20
VSS19
VSS18
VSS17
VSS16
VSS15
VSS14
VSS13
VSS12
VSS11
VSS10
VSS9
VSS8
VSS7
VSS6
VSS5
VSS4
VSS3
VSS2
VSS1
VSS0
21
2
1
2
1
2
1
2
1
CAD NOTE:
SHEETDATE
DEPARTMENT
SIZE
PROJECT DOCUMENT NUMBER REV
REVIEWER
DESIGNER
123
7 3 2 1 6 5 4
E
A
B
C
E
D
C
B
A
7 6 5 4
D
ININ
BI
OUTOUT
IN
IN
ININ
ININ
IN
IN
OUTOUT
OUTOUT
IN
IN
IN
BI
BI
BI
BI
IN
IN
OUT
C58C57C56
R44
C



20210728 MODIFY FOR GT
Fri Aug 25 14:01:21 2023N/AN/AN/AN/AV05101 OF 312P3V3_AUX P12V_S3_AUX_CPU1_NVDIMM
P12V_S3_AUX_CPU1_NVDIMMP3V3_AUX
DDR5 - CPU1 CHB DIMM2(BLACK)114101230989910010210310410552100130989910023098991001021031041055210052100521005210052525252525252525210052100
10152 1005210052100521005210052 100PWRGD_CHB_CPU1_DIMM2PD_CHB_CPU1_DIMM2_SAAI3C_SPD_DDRABCD_CPU1_LVC1_SDAI3C_SPD_DDRABCD_CPU1_LVC1_SCL_R4M_B_CPU1_ALERT_NRST_M_AB_CPU1_FPGA_NCHIPTP_CHB_CPU1_DIMM2_FRU_6I3C_SPD_DDRABCD_CPU1_LVC1_SCL49.9M_B_CPU1_SA_DQS_DP<9:0>M_B_CPU1_SA_DQS_DN<9:0>M_B_CPU1_SB_DQS_DP<9:0>M_B_CPU1_SB_DQS_DN<9:0>SMLFSCONN288_ADR50017-P087CC SCONN288_ADR50017-P087CCSMLFM_B_CPU1_CLK_DN<1>M_B_CPU1_CLK_DP<1>M_B_CPU1_SA_CS_N<2>M_B_CPU1_SB_CS_N<2>M_B_CPU1_SA_CS_N<3>M_B_CPU1_SB_CS_N<3>M_B_CPU1_SA_RSP<1>M_B_CPU1_SB_RSP<1>M_B_CPU1_SA_PARM_B_CPU1_SB_PARTP_CHB_CPU1_DIMM2_FRU_5TP_CHB_CPU1_DIMM2_FRU_4TP_CHB_CPU1_DIMM2_FRU_3TP_CHB_CPU1_DIMM2_FRU_2TP_CHB_CPU1_DIMM2_FRU_1TP_CHB_CPU1_DIMM2_FRU_0
IO IOSCONN288_ADR50017-P087CCIOSMLF
1%1/16W0402LFCHIP35.7KX6S16VC080510UF10%X6S16VC080510UF10%PD_CHB_CPU1_DIMM2_SAAM_B_CPU1_SB_DQ<31:0>M_B_CPU1_SB_CA<6:0>M_B_CPU1_SA_CA<6:0>M_B_CPU1_SB_CB<7:0>M_B_CPU1_SA_CB<7:0>M_B_CPU1_SA_DQ<31:0>
PLACE THE BYPASS CAPS CLOSE TO DIMM2.2UF6.3VX6SC040220%
DQS7_A_c||TDQS7_A_c
DQS6_A_t||TDQS6_A_t
DQS8_B_t||TDQS8_B_t
DQS8_B_c||TDQS8_B_c
DQS7_B_t||TDQS7_B_t
DQS0_A_c
DQS0_A_t
DQS0_B_c
DQS0_B_t
DQS1_A_c
DQS1_A_t
DQS1_B_c
DQS1_B_t
DQS2_A_c
DQS2_A_t
DQS2_B_c
DQS2_B_t
DQS3_A_c
DQS3_A_t
DQS3_B_c
DQS3_B_t
DQS4_A_c
DQS4_A_t
DQS4_B_c
DQS4_B_t
DQS5_A_c||TDQS5_A_c||DQS5_A_t||TDQS5_A_t
DQS5_A_t||TDQS5_A_t
DQS5_B_c||TDQS5_B_c
DQS5_B_t||TDQS5_B_t
DQS6_A_c||TDQS6_A_c||DQS6_A_t||TDQS6_A_t
DQS6_B_c||TDQS6_B_c
DQS6_B_t||TDQS6_B_t
DQS7_A_t||TDQS7_A_t
DQS7_B_c||TDQS7_B_c
DQS8_A_c||TDQS8_A_c
DQS8_A_t||TDQS8_A_t
DQS9_A_c||TDQS9_A_c
DQS9_A_t||TDQS9_A_t
DQS9_B_c||TDQS9_B_c
DQS9_B_t||TDQS9_B_t||DBI4_B_n
R3894
93
94
201
200
283
282
190
189
272
271
179
178
261
260
168
167
250
249
157
156
239
238
55
56
137
138
44
45
126
127
33
34
115
116
22
23
104
105
11
12
288
286
284
281
279
277
275
273
270
268
266
264
262
259
257
255
253
251
248
246
244
242
240
237
235
233
230
228
226
224
222
219
216
214
212
210
208
206
204
202
199
197
195
193
191
188
186
184
182
180
177
175
173
171
169
166
164
162
160
158
155
153
151
143
141
139
136
134
132
130
128
125
123
121
119
117
114
112
110
108
106
103
101
99
97
95
92
90
88
85
83
81
79
77
75
73
71
69
67
65
63
61
59
57
54
52
50
48
46
43
41
39
37
35
32
30
28
26
24
21
19
17
15
13
10
8
6
146
145
1
G3
G2
G1
3
232
231
220
150
149
144
2
207
147
227
74
87
86
5
4
148
287
194
285
192
142
49
140
47
280
187
278
185
135
42
133
40
276
183
274
181
131
38
129
36
269
176
267
174
124
31
122
29
265
172
263
170
120
27
118
25
258
165
256
163
113
20
111
18
254
161
252
159
109
16
107
14
247
154
245
152
102
9
100
7
229
209
84
64
217
218
236
205
234
203
91
60
89
58
243
198
241
196
98
53
96
51
82
72
225
215
80
70
223
213
78
68
221
211
76
66
62
8
9
7
6
5
4
3
2
1
0
9
8
7
6
5
4
3
2
1
0
9
8
7
6
5
4
3
2
1
0
9
8
7
6
5
4
3
2
1
0
15
14
2
18
19
16
17
15
13
14
11
12
10
8
9
7
5
6
4
3
0
1
30
31
29
28
26
27
25
24
23
21
22
20
19
18
17
16
13
12
11
10
9
8
7
5
6
3
4
2
1
0
3
5
6
4
2
1
0
7
6
5
4
3
1
2
0
7
6
5
4
3
2
1
0
31
29
30
28
27
26
25
6
5
2
3
4
1
0
24
23
22
21
20
J20
J20J20
1/3
DQ31_A
CB7_A
CB4_A
CB1_A
CB7_B
ALERT_n
CA0_A
CA0_B
CA1_A
CA1_B
CA2_A
CA2_B
CA3_A
CA3_B
CA4_A
CA4_B
CA5_A
CA5_B
CA6_A
CA6_B
CB6_A
CB5_A
CB3_A
CB2_A
CB0_A
CB6_B
CB5_B
CB4_B
CB3_B
CB2_B
CB1_B
CB0_B
CK_c
CK_t
CS0_A_n
CS0_B_n
CS1_A_n
CS1_B_n
DQ30_A
DQ29_A
DQ28_A
DQ27_A
DQ26_A
DQ25_A
DQ24_A
DQ23_A
DQ22_A
DQ21_A
DQ20_A
DQ19_A
DQ18_A
DQ17_A
DQ16_A
DQ15_A
DQ14_A
DQ13_A
DQ12_A
DQ11_A
DQ10_A
DQ9_A
DQ8_A
DQ7_A
DQ6_A
DQ5_A
DQ4_A
DQ3_A
DQ2_A
DQ1_A
DQ0_A
DQ31_B
DQ30_B
DQ29_B
DQ28_B
DQ27_B
DQ26_B
DQ25_B
DQ24_B
DQ23_B
DQ22_B
DQ21_B
DQ20_B
DQ19_B
DQ18_B
DQ17_B
DQ16_B
DQ15_B
DQ14_B
DQ13_B
DQ12_B
DQ11_B
DQ10_B
DQ9_B
DQ8_B
DQ7_B
DQ6_B
DQ5_B
DQ4_B
DQ3_B
DQ2_B
DQ1_B
DQ0_B
HSA
HSCL
HSDA
LBD||RSP_A_n
LBS||RSP_B_n
PAR_A
PAR_B
PWR_GOOD||FAIL_n
RESET_n
RFU6
RFU5
RFU4
RFU3
RFU2
RFU1
RFU0
VIN_MGMT
2/3 3/3
G3
G2
G1
VSS62
VSS61
VSS60
VSS58
VSS104
VSS102
VSS100
VIN_BULK2
VIN_BULK1
VIN_BULK0
VSS126
VSS125
VSS124
VSS123
VSS122
VSS121
VSS120
VSS119
VSS118
VSS117
VSS116
VSS115
VSS114
VSS113
VSS112
VSS111
VSS110
VSS109
VSS108
VSS107
VSS106
VSS105
VSS103
VSS101
VSS99
VSS98
VSS97
VSS96
VSS95
VSS94
VSS93
VSS92
VSS91
VSS90
VSS89
VSS88
VSS87
VSS86
VSS85
VSS84
VSS83
VSS82
VSS81
VSS80
VSS79
VSS78
VSS77
VSS76
VSS75
VSS74
VSS73
VSS72
VSS71
VSS70
VSS69
VSS68
VSS67
VSS66
VSS65
VSS64
VSS63
VSS59
VSS57
VSS56
VSS55
VSS54
VSS53
VSS52
VSS51
VSS50
VSS49
VSS48
VSS47
VSS46
VSS45
VSS44
VSS43
VSS42
VSS41
VSS40
VSS39
VSS38
VSS37
VSS36
VSS35
VSS34
VSS33
VSS32
VSS31
VSS30
VSS29
VSS28
VSS27
VSS26
VSS25
VSS24
VSS23
VSS22
VSS21
VSS20
VSS19
VSS18
VSS17
VSS16
VSS15
VSS14
VSS13
VSS12
VSS11
VSS10
VSS9
VSS8
VSS7
VSS6
VSS5
VSS4
VSS3
VSS2
VSS1
VSS0
21
2
1
2
1
2
1
2
1
CAD NOTE:
SHEETDATE
DEPARTMENT
SIZE
PROJECT DOCUMENT NUMBER REV
REVIEWER
DESIGNER
123
7 3 2 1 6 5 4
E
A
B
C
E
D
C
B
A
7 6 5 4
D
IN
IN
ININ
BI
OUT
IN
OUT
IN
IN
IN
OUTOUT
IN
BI
OUTOUT
IN
IN
ININ
BI
IN
BI
IN
BI
OUT
C61C60C59
R45
C



20210728 MODIFY FOR GT
Fri Aug 25 14:01:22 2023N/AN/AN/AN/AV05102 OF 312P3V3_AUX P12V_S3_AUX_CPU1_NVDIMM
P12V_S3_AUX_CPU1_NVDIMMP3V3_AUX
DDR5 - CPU1 CHC DIMM1(YELLOW)
23098991001011031041051025310313010310410523098991001011031041051145310353103531035310353 1035310353535353535353535310353103
102
53103531035310353 103I3C_SPD_DDRABCD_CPU1_LVC1_SCL_R5I3C_SPD_DDRABCD_CPU1_LVC1_SDAPD_CHC_CPU1_DIMM1_SAAM_C_CPU1_ALERT_NRST_M_CD_CPU1_FPGA_NCHIPI3C_SPD_DDRABCD_CPU1_LVC1_SCL49.9PWRGD_CHC_CPU1_DIMM1TP_CHC_CPU1_DIMM1_FRU_6TP_CHC_CPU1_DIMM1_FRU_5TP_CHC_CPU1_DIMM1_FRU_4TP_CHC_CPU1_DIMM1_FRU_3
M_C_CPU1_SA_DQS_DP<9:0>M_C_CPU1_SA_DQS_DN<9:0>M_C_CPU1_SB_DQS_DP<9:0>M_C_CPU1_SB_DQS_DN<9:0>M_C_CPU1_SB_DQ<31:0>M_C_CPU1_SA_CB<7:0>SMLFSCONN288_ADR50017-P130CCSMLFSCONN288_ADR50017-P130CCSMLFIOIOSCONN288_ADR50017-P130CCM_C_CPU1_CLK_DP<0>M_C_CPU1_CLK_DN<0>M_C_CPU1_SA_CS_N<0>M_C_CPU1_SB_CS_N<0>M_C_CPU1_SA_CS_N<1>M_C_CPU1_SB_CS_N<1>M_C_CPU1_SA_RSP<0>M_C_CPU1_SB_RSP<0>M_C_CPU1_SA_PARM_C_CPU1_SB_PARTP_CHC_CPU1_DIMM1_FRU_2TP_CHC_CPU1_DIMM1_FRU_1TP_CHC_CPU1_DIMM1_FRU_0
IO
0402LFCHIP1/16W1%54.9KX6S10%16VC080510UFX6SC080510%10UF16VPD_CHC_CPU1_DIMM1_SAA
M_C_CPU1_SB_CA<6:0>M_C_CPU1_SA_CA<6:0>M_C_CPU1_SB_CB<7:0>M_C_CPU1_SA_DQ<31:0>
PLACE THE BYPASS CAPS CLOSE TO DIMM20%X6SC04022.2UF6.3V
DQS7_A_c||TDQS7_A_c
DQS6_A_t||TDQS6_A_t
DQS8_B_t||TDQS8_B_t
DQS8_B_c||TDQS8_B_c
DQS7_B_t||TDQS7_B_t
DQS0_A_c
DQS0_A_t
DQS0_B_c
DQS0_B_t
DQS1_A_c
DQS1_A_t
DQS1_B_c
DQS1_B_t
DQS2_A_c
DQS2_A_t
DQS2_B_c
DQS2_B_t
DQS3_A_c
DQS3_A_t
DQS3_B_c
DQS3_B_t
DQS4_A_c
DQS4_A_t
DQS4_B_c
DQS4_B_t
DQS5_A_c||TDQS5_A_c||DQS5_A_t||TDQS5_A_t
DQS5_A_t||TDQS5_A_t
DQS5_B_c||TDQS5_B_c
DQS5_B_t||TDQS5_B_t
DQS6_A_c||TDQS6_A_c||DQS6_A_t||TDQS6_A_t
DQS6_B_c||TDQS6_B_c
DQS6_B_t||TDQS6_B_t
DQS7_A_t||TDQS7_A_t
DQS7_B_c||TDQS7_B_c
DQS8_A_c||TDQS8_A_c
DQS8_A_t||TDQS8_A_t
DQS9_A_c||TDQS9_A_c
DQS9_A_t||TDQS9_A_t
DQS9_B_c||TDQS9_B_c
DQS9_B_t||TDQS9_B_t||DBI4_B_n
R3895
93
94
201
200
283
282
190
189
272
271
179
178
261
260
168
167
250
249
157
156
239
238
55
56
137
138
44
45
126
127
33
34
115
116
22
23
104
105
11
12
288
286
284
281
279
277
275
273
270
268
266
264
262
259
257
255
253
251
248
246
244
242
240
237
235
233
230
228
226
224
222
219
216
214
212
210
208
206
204
202
199
197
195
193
191
188
186
184
182
180
177
175
173
171
169
166
164
162
160
158
155
153
151
143
141
139
136
134
132
130
128
125
123
121
119
117
114
112
110
108
106
103
101
99
97
95
92
90
88
85
83
81
79
77
75
73
71
69
67
65
63
61
59
57
54
52
50
48
46
43
41
39
37
35
32
30
28
26
24
21
19
17
15
13
10
8
6
146
145
1
G3
G2
G1
3
232
231
220
150
149
144
2
207
147
227
74
87
86
5
4
148
287
194
285
192
142
49
140
47
280
187
278
185
135
42
133
40
276
183
274
181
131
38
129
36
269
176
267
174
124
31
122
29
265
172
263
170
120
27
118
25
258
165
256
163
113
20
111
18
254
161
252
159
109
16
107
14
247
154
245
152
102
9
100
7
229
209
84
64
217
218
236
205
234
203
91
60
89
58
243
198
241
196
98
53
96
51
82
72
225
215
80
70
223
213
78
68
221
211
76
66
62
9
8
7
5
6
4
3
2
1
0
9
8
7
4
6
5
3
2
1
0
9
8
9
0
2
1
3
4
5
6
7
1
0
2
3
4
6
5
7
8
22
27
7
28
26
9
13
14
12
11
10
8
7
6
5
4
3
2
1
0
30
31
29
27
25
24
23
22
20
21
19
18
17
16
15
14
13
12
10
11
9
8
7
6
5
3
4
2
0
1
3
4
2
0
1
6
5
4
3
1
2
0
6
4
5
3
1
2
0
7
6
5
4
2
3
1
0
30
31
5
6
28
29
25
26
24
23
21
20
18
19
16
17
15
J21 J21J21
2/3 3/3
G3
G2
G1
VSS62
VSS61
VSS60
VSS58
VSS104
VSS102
VSS100
VIN_BULK2
VIN_BULK1
VIN_BULK0
VSS126
VSS125
VSS124
VSS123
VSS122
VSS121
VSS120
VSS119
VSS118
VSS117
VSS116
VSS115
VSS114
VSS113
VSS112
VSS111
VSS110
VSS109
VSS108
VSS107
VSS106
VSS105
VSS103
VSS101
VSS99
VSS98
VSS97
VSS96
VSS95
VSS94
VSS93
VSS92
VSS91
VSS90
VSS89
VSS88
VSS87
VSS86
VSS85
VSS84
VSS83
VSS82
VSS81
VSS80
VSS79
VSS78
VSS77
VSS76
VSS75
VSS74
VSS73
VSS72
VSS71
VSS70
VSS69
VSS68
VSS67
VSS66
VSS65
VSS64
VSS63
VSS59
VSS57
VSS56
VSS55
VSS54
VSS53
VSS52
VSS51
VSS50
VSS49
VSS48
VSS47
VSS46
VSS45
VSS44
VSS43
VSS42
VSS41
VSS40
VSS39
VSS38
VSS37
VSS36
VSS35
VSS34
VSS33
VSS32
VSS31
VSS30
VSS29
VSS28
VSS27
VSS26
VSS25
VSS24
VSS23
VSS22
VSS21
VSS20
VSS19
VSS18
VSS17
VSS16
VSS15
VSS14
VSS13
VSS12
VSS11
VSS10
VSS9
VSS8
VSS7
VSS6
VSS5
VSS4
VSS3
VSS2
VSS1
VSS0
1/3
DQ31_A
CB7_A
CB4_A
CB1_A
CB7_B
ALERT_n
CA0_A
CA0_B
CA1_A
CA1_B
CA2_A
CA2_B
CA3_A
CA3_B
CA4_A
CA4_B
CA5_A
CA5_B
CA6_A
CA6_B
CB6_A
CB5_A
CB3_A
CB2_A
CB0_A
CB6_B
CB5_B
CB4_B
CB3_B
CB2_B
CB1_B
CB0_B
CK_c
CK_t
CS0_A_n
CS0_B_n
CS1_A_n
CS1_B_n
DQ30_A
DQ29_A
DQ28_A
DQ27_A
DQ26_A
DQ25_A
DQ24_A
DQ23_A
DQ22_A
DQ21_A
DQ20_A
DQ19_A
DQ18_A
DQ17_A
DQ16_A
DQ15_A
DQ14_A
DQ13_A
DQ12_A
DQ11_A
DQ10_A
DQ9_A
DQ8_A
DQ7_A
DQ6_A
DQ5_A
DQ4_A
DQ3_A
DQ2_A
DQ1_A
DQ0_A
DQ31_B
DQ30_B
DQ29_B
DQ28_B
DQ27_B
DQ26_B
DQ25_B
DQ24_B
DQ23_B
DQ22_B
DQ21_B
DQ20_B
DQ19_B
DQ18_B
DQ17_B
DQ16_B
DQ15_B
DQ14_B
DQ13_B
DQ12_B
DQ11_B
DQ10_B
DQ9_B
DQ8_B
DQ7_B
DQ6_B
DQ5_B
DQ4_B
DQ3_B
DQ2_B
DQ1_B
DQ0_B
HSA
HSCL
HSDA
LBD||RSP_A_n
LBS||RSP_B_n
PAR_A
PAR_B
PWR_GOOD||FAIL_n
RESET_n
RFU6
RFU5
RFU4
RFU3
RFU2
RFU1
RFU0
VIN_MGMT
21
2
1
2
1
2
1
2
1
CAD NOTE:
SHEETDATE
DEPARTMENT
SIZE
PROJECT DOCUMENT NUMBER REV
REVIEWER
DESIGNER
123
7 3 2 1 6 5 4
E
A
B
C
E
D
C
B
A
7 6 5 4
D
IN
IN
BI
OUTOUT
OUT
IN
ININ
ININ
IN
ININ
IN
IN
OUTOUT
OUTOUT
BI
BI
BIIN
BI
IN
IN
C64C63C62
R46
C



20210728 MODIFY FOR GT
Fri Aug 25 14:01:23 2023N/AN/AN/AN/AV05103 OF 312P3V3_AUX P12V_S3_AUX_CPU1_NVDIMM
P12V_S3_AUX_CPU1_NVDIMMP3V3_AUX
DDR5 - CPU1 CHC DIMM2(BLACK)
1301021041052309899100101102104105103531022309899100101102104105114531025310253102531025353535353535353531025310253 102
10353 10253102531025310253102
PLACE THE BYPASS CAPS CLOSE TO DIMMC0402RST_M_CD_CPU1_FPGA_NI3C_SPD_DDRABCD_CPU1_LVC1_SDAPD_CHC_CPU1_DIMM2_SAAI3C_SPD_DDRABCD_CPU1_LVC1_SCL_R6M_C_CPU1_ALERT_NCHIPI3C_SPD_DDRABCD_CPU1_LVC1_SCLPWRGD_CHC_CPU1_DIMM2M_C_CPU1_SA_DQS_DP<9:0>M_C_CPU1_SA_DQS_DN<9:0>M_C_CPU1_SB_DQS_DP<9:0>M_C_CPU1_SB_DQS_DN<9:0>49.9IOSCONN288_ADR50017-P087CCSMLFSCONN288_ADR50017-P087CCSMLFSCONN288_ADR50017-P087CCM_C_CPU1_CLK_DP<1>M_C_CPU1_CLK_DN<1>M_C_CPU1_SA_CS_N<2>M_C_CPU1_SB_CS_N<2>M_C_CPU1_SA_CS_N<3>M_C_CPU1_SB_CS_N<3>M_C_CPU1_SA_RSP<1>M_C_CPU1_SB_RSP<1>M_C_CPU1_SA_PARM_C_CPU1_SB_PARTP_CHC_CPU1_DIMM2_FRU_6TP_CHC_CPU1_DIMM2_FRU_5TP_CHC_CPU1_DIMM2_FRU_4TP_CHC_CPU1_DIMM2_FRU_3TP_CHC_CPU1_DIMM2_FRU_2TP_CHC_CPU1_DIMM2_FRU_1TP_CHC_CPU1_DIMM2_FRU_0
IOIOSMLFM_C_CPU1_SA_DQ<31:0>
CHIP1%1/16W0402LF84.5KX6S10UF16VC080510%X6S10UF16VC080510%PD_CHC_CPU1_DIMM2_SAAM_C_CPU1_SB_DQ<31:0>M_C_CPU1_SB_CA<6:0>M_C_CPU1_SA_CA<6:0>M_C_CPU1_SB_CB<7:0>M_C_CPU1_SA_CB<7:0>X6S20%2.2UF6.3V
DQS7_A_c||TDQS7_A_c
DQS6_A_t||TDQS6_A_t
DQS8_B_t||TDQS8_B_t
DQS8_B_c||TDQS8_B_c
DQS7_B_t||TDQS7_B_t
DQS0_A_c
DQS0_A_t
DQS0_B_c
DQS0_B_t
DQS1_A_c
DQS1_A_t
DQS1_B_c
DQS1_B_t
DQS2_A_c
DQS2_A_t
DQS2_B_c
DQS2_B_t
DQS3_A_c
DQS3_A_t
DQS3_B_c
DQS3_B_t
DQS4_A_c
DQS4_A_t
DQS4_B_c
DQS4_B_t
DQS5_A_c||TDQS5_A_c||DQS5_A_t||TDQS5_A_t
DQS5_A_t||TDQS5_A_t
DQS5_B_c||TDQS5_B_c
DQS5_B_t||TDQS5_B_t
DQS6_A_c||TDQS6_A_c||DQS6_A_t||TDQS6_A_t
DQS6_B_c||TDQS6_B_c
DQS6_B_t||TDQS6_B_t
DQS7_A_t||TDQS7_A_t
DQS7_B_c||TDQS7_B_c
DQS8_A_c||TDQS8_A_c
DQS8_A_t||TDQS8_A_t
DQS9_A_c||TDQS9_A_c
DQS9_A_t||TDQS9_A_t
DQS9_B_c||TDQS9_B_c
DQS9_B_t||TDQS9_B_t||DBI4_B_n
R3896
93
94
201
200
283
282
190
189
272
271
179
178
261
260
168
167
250
249
157
156
239
238
55
56
137
138
44
45
126
127
33
34
115
116
22
23
104
105
11
12
288
286
284
281
279
277
275
273
270
268
266
264
262
259
257
255
253
251
248
246
244
242
240
237
235
233
230
228
226
224
222
219
216
214
212
210
208
206
204
202
199
197
195
193
191
188
186
184
182
180
177
175
173
171
169
166
164
162
160
158
155
153
151
143
141
139
136
134
132
130
128
125
123
121
119
117
114
112
110
108
106
103
101
99
97
95
92
90
88
85
83
81
79
77
75
73
71
69
67
65
63
61
59
57
54
52
50
48
46
43
41
39
37
35
32
30
28
26
24
21
19
17
15
13
10
8
6
146
145
1
G3
G2
G1
3
232
231
220
150
149
144
2
207
147
227
74
87
86
5
4
148
287
194
285
192
142
49
140
47
280
187
278
185
135
42
133
40
276
183
274
181
131
38
129
36
269
176
267
174
124
31
122
29
265
172
263
170
120
27
118
25
258
165
256
163
113
20
111
18
254
161
252
159
109
16
107
14
247
154
245
152
102
9
100
7
229
209
84
64
217
218
236
205
234
203
91
60
89
58
243
198
241
196
98
53
96
51
82
72
225
215
80
70
223
213
78
68
221
211
76
66
62
9
8
7
6
4
5
3
2
0
1
8
9
7
6
5
3
4
2
1
0
9
8
7
6
5
4
3
2
1
0
9
8
7
6
5
4
3
2
1
0
10
27
4
16
14
13
12
11
10
9
8
6
7
5
4
3
1
2
0
30
31
29
28
27
25
26
24
23
22
21
20
19
18
16
17
15
14
13
12
11
9
7
8
6
5
4
2
3
1
0
2
3
1
0
5
6
4
3
2
1
0
7
6
5
3
2
1
0
7
6
5
4
3
2
1
0
31
30
29
6
5
4
28
26
24
25
23
22
21
20
19
18
17
15
J22
J22J22
1/3
DQ31_A
CB7_A
CB4_A
CB1_A
CB7_B
ALERT_n
CA0_A
CA0_B
CA1_A
CA1_B
CA2_A
CA2_B
CA3_A
CA3_B
CA4_A
CA4_B
CA5_A
CA5_B
CA6_A
CA6_B
CB6_A
CB5_A
CB3_A
CB2_A
CB0_A
CB6_B
CB5_B
CB4_B
CB3_B
CB2_B
CB1_B
CB0_B
CK_c
CK_t
CS0_A_n
CS0_B_n
CS1_A_n
CS1_B_n
DQ30_A
DQ29_A
DQ28_A
DQ27_A
DQ26_A
DQ25_A
DQ24_A
DQ23_A
DQ22_A
DQ21_A
DQ20_A
DQ19_A
DQ18_A
DQ17_A
DQ16_A
DQ15_A
DQ14_A
DQ13_A
DQ12_A
DQ11_A
DQ10_A
DQ9_A
DQ8_A
DQ7_A
DQ6_A
DQ5_A
DQ4_A
DQ3_A
DQ2_A
DQ1_A
DQ0_A
DQ31_B
DQ30_B
DQ29_B
DQ28_B
DQ27_B
DQ26_B
DQ25_B
DQ24_B
DQ23_B
DQ22_B
DQ21_B
DQ20_B
DQ19_B
DQ18_B
DQ17_B
DQ16_B
DQ15_B
DQ14_B
DQ13_B
DQ12_B
DQ11_B
DQ10_B
DQ9_B
DQ8_B
DQ7_B
DQ6_B
DQ5_B
DQ4_B
DQ3_B
DQ2_B
DQ1_B
DQ0_B
HSA
HSCL
HSDA
LBD||RSP_A_n
LBS||RSP_B_n
PAR_A
PAR_B
PWR_GOOD||FAIL_n
RESET_n
RFU6
RFU5
RFU4
RFU3
RFU2
RFU1
RFU0
VIN_MGMT
2/3 3/3
G3
G2
G1
VSS62
VSS61
VSS60
VSS58
VSS104
VSS102
VSS100
VIN_BULK2
VIN_BULK1
VIN_BULK0
VSS126
VSS125
VSS124
VSS123
VSS122
VSS121
VSS120
VSS119
VSS118
VSS117
VSS116
VSS115
VSS114
VSS113
VSS112
VSS111
VSS110
VSS109
VSS108
VSS107
VSS106
VSS105
VSS103
VSS101
VSS99
VSS98
VSS97
VSS96
VSS95
VSS94
VSS93
VSS92
VSS91
VSS90
VSS89
VSS88
VSS87
VSS86
VSS85
VSS84
VSS83
VSS82
VSS81
VSS80
VSS79
VSS78
VSS77
VSS76
VSS75
VSS74
VSS73
VSS72
VSS71
VSS70
VSS69
VSS68
VSS67
VSS66
VSS65
VSS64
VSS63
VSS59
VSS57
VSS56
VSS55
VSS54
VSS53
VSS52
VSS51
VSS50
VSS49
VSS48
VSS47
VSS46
VSS45
VSS44
VSS43
VSS42
VSS41
VSS40
VSS39
VSS38
VSS37
VSS36
VSS35
VSS34
VSS33
VSS32
VSS31
VSS30
VSS29
VSS28
VSS27
VSS26
VSS25
VSS24
VSS23
VSS22
VSS21
VSS20
VSS19
VSS18
VSS17
VSS16
VSS15
VSS14
VSS13
VSS12
VSS11
VSS10
VSS9
VSS8
VSS7
VSS6
VSS5
VSS4
VSS3
VSS2
VSS1
VSS0
21
2
1
2
1
2
1
2
1
CAD NOTE:
SHEETDATE
DEPARTMENT
SIZE
PROJECT DOCUMENT NUMBER REV
REVIEWER
DESIGNER
123
7 3 2 1 6 5 4
E
A
B
C
E
D
C
B
A
7 6 5 4
D
ININ
BI
OUTOUT
OUT
IN
ININ
ININ
ININ
IN
OUTOUT
IN
BI
OUTOUT
IN
BI
BI
BI
IN
IN
IN
C67C66C65
R47
C



20210728 MODIFY FOR GT
Fri Aug 25 14:01:24 2023N/AN/AN/AN/AV05104 OF 312P3V3_AUX P12V_S3_AUX_CPU1_NVDIMM
P12V_S3_AUX_CPU1_NVDIMMP3V3_AUX
DDR5 - CPU1 CHD DIMM1(YELLOW)1045410423098991001011021031055410513010210310523098991001011021031051145410554105541055410554545454545454541055410554 1055410554105541055410554 105
PD_CHD_CPU1_DIMM1_SAAM_D_CPU1_SA_RSP<0>TP_CHD_CPU1_DIMM1_FRU_2TP_CHD_CPU1_DIMM1_FRU_5PD_CHD_CPU1_DIMM1_SAAI3C_SPD_DDRABCD_CPU1_LVC1_SDAI3C_SPD_DDRABCD_CPU1_LVC1_SCL_R7M_D_CPU1_ALERT_NRST_M_CD_CPU1_FPGA_NI3C_SPD_DDRABCD_CPU1_LVC1_SCLCHIP49.9PWRGD_CHD_CPU1_DIMM1TP_CHD_CPU1_DIMM1_FRU_6M_D_CPU1_SA_DQS_DP<9:0>M_D_CPU1_SA_DQS_DN<9:0>M_D_CPU1_SB_DQS_DN<9:0>M_D_CPU1_SB_DQS_DP<9:0>SCONN288_ADR50017-P130CCSCONN288_ADR50017-P130CCSMLF SMLFSMLFSCONN288_ADR50017-P130CCIOM_D_CPU1_CLK_DN<0>M_D_CPU1_CLK_DP<0>M_D_CPU1_SA_CS_N<0>M_D_CPU1_SB_CS_N<0>M_D_CPU1_SA_CS_N<1>M_D_CPU1_SB_CS_N<1>M_D_CPU1_SB_RSP<0>M_D_CPU1_SA_PARM_D_CPU1_SB_PARTP_CHD_CPU1_DIMM1_FRU_4TP_CHD_CPU1_DIMM1_FRU_3TP_CHD_CPU1_DIMM1_FRU_1TP_CHD_CPU1_DIMM1_FRU_0
IOIO
CHIP0402LF1/16W1%127KX6S10UF10%16VC0805X6S10%16VC080510UFM_D_CPU1_SB_DQ<31:0>M_D_CPU1_SB_CA<6:0>M_D_CPU1_SA_CA<6:0>M_D_CPU1_SB_CB<7:0>M_D_CPU1_SA_CB<7:0>M_D_CPU1_SA_DQ<31:0>
PLACE THE BYPASS CAPS CLOSE TO DIMMC040220%X6S2.2UF6.3V
DQS7_A_c||TDQS7_A_c
DQS6_A_t||TDQS6_A_t
DQS8_B_t||TDQS8_B_t
DQS8_B_c||TDQS8_B_c
DQS7_B_t||TDQS7_B_t
DQS0_A_c
DQS0_A_t
DQS0_B_c
DQS0_B_t
DQS1_A_c
DQS1_A_t
DQS1_B_c
DQS1_B_t
DQS2_A_c
DQS2_A_t
DQS2_B_c
DQS2_B_t
DQS3_A_c
DQS3_A_t
DQS3_B_c
DQS3_B_t
DQS4_A_c
DQS4_A_t
DQS4_B_c
DQS4_B_t
DQS5_A_c||TDQS5_A_c||DQS5_A_t||TDQS5_A_t
DQS5_A_t||TDQS5_A_t
DQS5_B_c||TDQS5_B_c
DQS5_B_t||TDQS5_B_t
DQS6_A_c||TDQS6_A_c||DQS6_A_t||TDQS6_A_t
DQS6_B_c||TDQS6_B_c
DQS6_B_t||TDQS6_B_t
DQS7_A_t||TDQS7_A_t
DQS7_B_c||TDQS7_B_c
DQS8_A_c||TDQS8_A_c
DQS8_A_t||TDQS8_A_t
DQS9_A_c||TDQS9_A_c
DQS9_A_t||TDQS9_A_t
DQS9_B_c||TDQS9_B_c
DQS9_B_t||TDQS9_B_t||DBI4_B_n
R3897
93
94
201
200
283
282
190
189
272
271
179
178
261
260
168
167
250
249
157
156
239
238
55
56
137
138
44
45
126
127
33
34
115
116
22
23
104
105
11
12
288
286
284
281
279
277
275
273
270
268
266
264
262
259
257
255
253
251
248
246
244
242
240
237
235
233
230
228
226
224
222
219
216
214
212
210
208
206
204
202
199
197
195
193
191
188
186
184
182
180
177
175
173
171
169
166
164
162
160
158
155
153
151
143
141
139
136
134
132
130
128
125
123
121
119
117
114
112
110
108
106
103
101
99
97
95
92
90
88
85
83
81
79
77
75
73
71
69
67
65
63
61
59
57
54
52
50
48
46
43
41
39
37
35
32
30
28
26
24
21
19
17
15
13
10
8
6
146
145
1
G3
G2
G1
3
232
231
220
150
149
144
2
207
147
227
74
87
86
5
4
148
287
194
285
192
142
49
140
47
280
187
278
185
135
42
133
40
276
183
274
181
131
38
129
36
269
176
267
174
124
31
122
29
265
172
263
170
120
27
118
25
258
165
256
163
113
20
111
18
254
161
252
159
109
16
107
14
247
154
245
152
102
9
100
7
229
209
84
64
217
218
236
205
234
203
91
60
89
58
243
198
241
196
98
53
96
51
82
72
225
215
80
70
223
213
78
68
221
211
76
66
62
8
9
7
6
5
3
4
2
1
0
9
8
7
6
5
4
3
2
1
0
9
8
7
6
5
4
3
2
1
0
9
8
7
6
5
4
3
2
0
1
15
17
16
14
15
20
214
31
30
2
11
10
9
8
7
4
6
5
2
3
0
1
27
29
28
24
25
26
4
5
6
3
2
5
0
1
6
3
1
0
7
6
5
3
4
1
2
0
4
5
7
6
19
21
20
22
23
18
16
14
9
11
10
12
13
8
7
4
5
6
1
0
3
2
0
1
3
2
30
31
28
29
27
25
26
24
23
22
18
19
17
12
13
J23 J23J23
1/3
DQ31_A
CB7_A
CB4_A
CB1_A
CB7_B
ALERT_n
CA0_A
CA0_B
CA1_A
CA1_B
CA2_A
CA2_B
CA3_A
CA3_B
CA4_A
CA4_B
CA5_A
CA5_B
CA6_A
CA6_B
CB6_A
CB5_A
CB3_A
CB2_A
CB0_A
CB6_B
CB5_B
CB4_B
CB3_B
CB2_B
CB1_B
CB0_B
CK_c
CK_t
CS0_A_n
CS0_B_n
CS1_A_n
CS1_B_n
DQ30_A
DQ29_A
DQ28_A
DQ27_A
DQ26_A
DQ25_A
DQ24_A
DQ23_A
DQ22_A
DQ21_A
DQ20_A
DQ19_A
DQ18_A
DQ17_A
DQ16_A
DQ15_A
DQ14_A
DQ13_A
DQ12_A
DQ11_A
DQ10_A
DQ9_A
DQ8_A
DQ7_A
DQ6_A
DQ5_A
DQ4_A
DQ3_A
DQ2_A
DQ1_A
DQ0_A
DQ31_B
DQ30_B
DQ29_B
DQ28_B
DQ27_B
DQ26_B
DQ25_B
DQ24_B
DQ23_B
DQ22_B
DQ21_B
DQ20_B
DQ19_B
DQ18_B
DQ17_B
DQ16_B
DQ15_B
DQ14_B
DQ13_B
DQ12_B
DQ11_B
DQ10_B
DQ9_B
DQ8_B
DQ7_B
DQ6_B
DQ5_B
DQ4_B
DQ3_B
DQ2_B
DQ1_B
DQ0_B
HSA
HSCL
HSDA
LBD||RSP_A_n
LBS||RSP_B_n
PAR_A
PAR_B
PWR_GOOD||FAIL_n
RESET_n
RFU6
RFU5
RFU4
RFU3
RFU2
RFU1
RFU0
VIN_MGMT
2/3 3/3
G3
G2
G1
VSS62
VSS61
VSS60
VSS58
VSS104
VSS102
VSS100
VIN_BULK2
VIN_BULK1
VIN_BULK0
VSS126
VSS125
VSS124
VSS123
VSS122
VSS121
VSS120
VSS119
VSS118
VSS117
VSS116
VSS115
VSS114
VSS113
VSS112
VSS111
VSS110
VSS109
VSS108
VSS107
VSS106
VSS105
VSS103
VSS101
VSS99
VSS98
VSS97
VSS96
VSS95
VSS94
VSS93
VSS92
VSS91
VSS90
VSS89
VSS88
VSS87
VSS86
VSS85
VSS84
VSS83
VSS82
VSS81
VSS80
VSS79
VSS78
VSS77
VSS76
VSS75
VSS74
VSS73
VSS72
VSS71
VSS70
VSS69
VSS68
VSS67
VSS66
VSS65
VSS64
VSS63
VSS59
VSS57
VSS56
VSS55
VSS54
VSS53
VSS52
VSS51
VSS50
VSS49
VSS48
VSS47
VSS46
VSS45
VSS44
VSS43
VSS42
VSS41
VSS40
VSS39
VSS38
VSS37
VSS36
VSS35
VSS34
VSS33
VSS32
VSS31
VSS30
VSS29
VSS28
VSS27
VSS26
VSS25
VSS24
VSS23
VSS22
VSS21
VSS20
VSS19
VSS18
VSS17
VSS16
VSS15
VSS14
VSS13
VSS12
VSS11
VSS10
VSS9
VSS8
VSS7
VSS6
VSS5
VSS4
VSS3
VSS2
VSS1
VSS0
21
2
1
2
1
2
1
2
1
CAD NOTE:
SHEETDATE
DEPARTMENT
SIZE
PROJECT DOCUMENT NUMBER REV
REVIEWER
DESIGNER
123
7 3 2 1 6 5 4
E
A
B
C
E
D
C
B
A
7 6 5 4
D
ININ
BI
OUTOUT
OUT
IN
IN
ININ
ININ
IN
IN
OUTOUT
OUTOUTIN
IN
BI
IN
BI
BI
BI
IN
IN
C70C69C68
R48
C



20210728 MODIFY FOR GT
Fri Aug 25 14:01:25 2023N/AN/AN/AN/AV05105 OF 312P3V3_AUX P12V_S3_AUX_CPU1_NVDIMM
P12V_S3_AUX_CPU1_NVDIMMP3V3_AUX
DDR5 - CPU1 CHD DIMM2(BLACK)2309899100101102103104105230989910010110210310454104130102103104114541045410454104541045410454545454545454545410454104
10554 10454104541045410454 104
PLACE THE BYPASS CAPS CLOSE TO DIMM2.2UFC0402X6SI3C_SPD_DDRABCD_CPU1_LVC1_SCLPD_CHD_CPU1_DIMM2_SAAI3C_SPD_DDRABCD_CPU1_LVC1_SDAI3C_SPD_DDRABCD_CPU1_LVC1_SCL_R8M_D_CPU1_ALERT_NRST_M_CD_CPU1_FPGA_N49.9CHIPPWRGD_CHD_CPU1_DIMM2M_D_CPU1_SA_DQS_DP<9:0>M_D_CPU1_SA_DQS_DN<9:0>M_D_CPU1_SB_DQS_DP<9:0>M_D_CPU1_SB_DQS_DN<9:0>M_D_CPU1_SA_CA<6:0>SMLFSCONN288_ADR50017-P087CCSCONN288_ADR50017-P087CCSCONN288_ADR50017-P087CCIOM_D_CPU1_CLK_DN<1>M_D_CPU1_CLK_DP<1>M_D_CPU1_SA_CS_N<2>M_D_CPU1_SB_CS_N<2>M_D_CPU1_SA_CS_N<3>M_D_CPU1_SB_CS_N<3>M_D_CPU1_SA_RSP<1>M_D_CPU1_SB_RSP<1>M_D_CPU1_SA_PARM_D_CPU1_SB_PARTP_CHD_CPU1_DIMM2_FRU_6TP_CHD_CPU1_DIMM2_FRU_5TP_CHD_CPU1_DIMM2_FRU_4TP_CHD_CPU1_DIMM2_FRU_3TP_CHD_CPU1_DIMM2_FRU_2TP_CHD_CPU1_DIMM2_FRU_1TP_CHD_CPU1_DIMM2_FRU_0
IO SMLFIOSMLF
196K0402LF1/16W1%CHIPX6S10UFC080516V10%X6SC080510%10UF16VPD_CHD_CPU1_DIMM2_SAAM_D_CPU1_SB_DQ<31:0>M_D_CPU1_SB_CA<6:0>M_D_CPU1_SB_CB<7:0>M_D_CPU1_SA_CB<7:0>M_D_CPU1_SA_DQ<31:0>
6.3V20%
DQS7_A_c||TDQS7_A_c
DQS6_A_t||TDQS6_A_t
DQS8_B_t||TDQS8_B_t
DQS8_B_c||TDQS8_B_c
DQS7_B_t||TDQS7_B_t
DQS0_A_c
DQS0_A_t
DQS0_B_c
DQS0_B_t
DQS1_A_c
DQS1_A_t
DQS1_B_c
DQS1_B_t
DQS2_A_c
DQS2_A_t
DQS2_B_c
DQS2_B_t
DQS3_A_c
DQS3_A_t
DQS3_B_c
DQS3_B_t
DQS4_A_c
DQS4_A_t
DQS4_B_c
DQS4_B_t
DQS5_A_c||TDQS5_A_c||DQS5_A_t||TDQS5_A_t
DQS5_A_t||TDQS5_A_t
DQS5_B_c||TDQS5_B_c
DQS5_B_t||TDQS5_B_t
DQS6_A_c||TDQS6_A_c||DQS6_A_t||TDQS6_A_t
DQS6_B_c||TDQS6_B_c
DQS6_B_t||TDQS6_B_t
DQS7_A_t||TDQS7_A_t
DQS7_B_c||TDQS7_B_c
DQS8_A_c||TDQS8_A_c
DQS8_A_t||TDQS8_A_t
DQS9_A_c||TDQS9_A_c
DQS9_A_t||TDQS9_A_t
DQS9_B_c||TDQS9_B_c
DQS9_B_t||TDQS9_B_t||DBI4_B_n
R3898
93
94
201
200
283
282
190
189
272
271
179
178
261
260
168
167
250
249
157
156
239
238
55
56
137
138
44
45
126
127
33
34
115
116
22
23
104
105
11
12
288
286
284
281
279
277
275
273
270
268
266
264
262
259
257
255
253
251
248
246
244
242
240
237
235
233
230
228
226
224
222
219
216
214
212
210
208
206
204
202
199
197
195
193
191
188
186
184
182
180
177
175
173
171
169
166
164
162
160
158
155
153
151
143
141
139
136
134
132
130
128
125
123
121
119
117
114
112
110
108
106
103
101
99
97
95
92
90
88
85
83
81
79
77
75
73
71
69
67
65
63
61
59
57
54
52
50
48
46
43
41
39
37
35
32
30
28
26
24
21
19
17
15
13
10
8
6
146
145
1
G3
G2
G1
3
232
231
220
150
149
144
2
207
147
227
74
87
86
5
4
148
287
194
285
192
142
49
140
47
280
187
278
185
135
42
133
40
276
183
274
181
131
38
129
36
269
176
267
174
124
31
122
29
265
172
263
170
120
27
118
25
258
165
256
163
113
20
111
18
254
161
252
159
109
16
107
14
247
154
245
152
102
9
100
7
229
209
84
64
217
218
236
205
234
203
91
60
89
58
243
198
241
196
98
53
96
51
82
72
225
215
80
70
223
213
78
68
221
211
76
66
62
9
8
6
7
4
5
3
1
2
0
8
9
7
6
5
4
3
2
1
0
9
8
7
8
0
9
1
2
3
4
5
6
0
1
3
2
4
5
6
7
19
10
11
4
16
14
13
12
9
6
8
7
5
3
1
2
0
31
30
29
28
27
25
26
24
23
22
21
20
19
18
16
17
15
14
13
12
11
10
9
7
8
6
5
4
2
3
1
0
3
2
1
0
5
6
4
3
2
1
0
7
5
6
4
3
2
0
1
7
6
5
4
3
2
1
0
29
30
316
4
5
28
27
26
24
25
23
22
21
20
18
17
15
J24
J24J24
2/3 3/3
G3
G2
G1
VSS62
VSS61
VSS60
VSS58
VSS104
VSS102
VSS100
VIN_BULK2
VIN_BULK1
VIN_BULK0
VSS126
VSS125
VSS124
VSS123
VSS122
VSS121
VSS120
VSS119
VSS118
VSS117
VSS116
VSS115
VSS114
VSS113
VSS112
VSS111
VSS110
VSS109
VSS108
VSS107
VSS106
VSS105
VSS103
VSS101
VSS99
VSS98
VSS97
VSS96
VSS95
VSS94
VSS93
VSS92
VSS91
VSS90
VSS89
VSS88
VSS87
VSS86
VSS85
VSS84
VSS83
VSS82
VSS81
VSS80
VSS79
VSS78
VSS77
VSS76
VSS75
VSS74
VSS73
VSS72
VSS71
VSS70
VSS69
VSS68
VSS67
VSS66
VSS65
VSS64
VSS63
VSS59
VSS57
VSS56
VSS55
VSS54
VSS53
VSS52
VSS51
VSS50
VSS49
VSS48
VSS47
VSS46
VSS45
VSS44
VSS43
VSS42
VSS41
VSS40
VSS39
VSS38
VSS37
VSS36
VSS35
VSS34
VSS33
VSS32
VSS31
VSS30
VSS29
VSS28
VSS27
VSS26
VSS25
VSS24
VSS23
VSS22
VSS21
VSS20
VSS19
VSS18
VSS17
VSS16
VSS15
VSS14
VSS13
VSS12
VSS11
VSS10
VSS9
VSS8
VSS7
VSS6
VSS5
VSS4
VSS3
VSS2
VSS1
VSS0
1/3
DQ31_A
CB7_A
CB4_A
CB1_A
CB7_B
ALERT_n
CA0_A
CA0_B
CA1_A
CA1_B
CA2_A
CA2_B
CA3_A
CA3_B
CA4_A
CA4_B
CA5_A
CA5_B
CA6_A
CA6_B
CB6_A
CB5_A
CB3_A
CB2_A
CB0_A
CB6_B
CB5_B
CB4_B
CB3_B
CB2_B
CB1_B
CB0_B
CK_c
CK_t
CS0_A_n
CS0_B_n
CS1_A_n
CS1_B_n
DQ30_A
DQ29_A
DQ28_A
DQ27_A
DQ26_A
DQ25_A
DQ24_A
DQ23_A
DQ22_A
DQ21_A
DQ20_A
DQ19_A
DQ18_A
DQ17_A
DQ16_A
DQ15_A
DQ14_A
DQ13_A
DQ12_A
DQ11_A
DQ10_A
DQ9_A
DQ8_A
DQ7_A
DQ6_A
DQ5_A
DQ4_A
DQ3_A
DQ2_A
DQ1_A
DQ0_A
DQ31_B
DQ30_B
DQ29_B
DQ28_B
DQ27_B
DQ26_B
DQ25_B
DQ24_B
DQ23_B
DQ22_B
DQ21_B
DQ20_B
DQ19_B
DQ18_B
DQ17_B
DQ16_B
DQ15_B
DQ14_B
DQ13_B
DQ12_B
DQ11_B
DQ10_B
DQ9_B
DQ8_B
DQ7_B
DQ6_B
DQ5_B
DQ4_B
DQ3_B
DQ2_B
DQ1_B
DQ0_B
HSA
HSCL
HSDA
LBD||RSP_A_n
LBS||RSP_B_n
PAR_A
PAR_B
PWR_GOOD||FAIL_n
RESET_n
RFU6
RFU5
RFU4
RFU3
RFU2
RFU1
RFU0
VIN_MGMT
21
2
1
2
1
2
1
2
1
CAD NOTE:
SHEETDATE
DEPARTMENT
SIZE
PROJECT DOCUMENT NUMBER REV
REVIEWER
DESIGNER
123
7 3 2 1 6 5 4
E
A
B
C
E
D
C
B
A
7 6 5 4
D
ININ
BI
OUTOUT
OUT
IN
ININ
ININ
ININ
IN
IN
OUTOUTBI
IN
OUTOUT
BI
BI
BI
IN
IN
IN
C98C97C96
R80
C



20210728 MODIFY FOR GT
N/AN/AN/AFri Aug 25 14:01:26 2023N/A106 OF 312V05P3V3_AUX P12V_S3_AUX_CPU1_NVDIMM
P12V_S3_AUX_CPU1_NVDIMMP3V3_AUX
DDR5 - CPU1 CHE DIMM1(YELLOW)
23010710810911011111211310655107130107108109230107108109110111112113551075510755107551071145510755107 55 10755 1075555555555555555551075510755107106
55107I3C_SPD_DDREFGH_CPU1_LVC1_SCL_R1I3C_SPD_DDREFGH_CPU1_LVC1_SDAPD_CHE_CPU1_DIMM1_SAAM_E_CPU1_ALERT_NRST_M_EF_CPU1_FPGA_NCHIPI3C_SPD_DDREFGH_CPU1_LVC1_SCLM_E_CPU1_SA_DQS_DP<9:0>M_E_CPU1_SA_DQS_DN<9:0>M_E_CPU1_SB_DQS_DN<9:0>M_E_CPU1_SB_DQS_DP<9:0>49.9TP_CHE_CPU1_DIMM1_FRU_6TP_CHE_CPU1_DIMM1_FRU_5TP_CHE_CPU1_DIMM1_FRU_4PWRGD_CHE_CPU1_DIMM1TP_CHE_CPU1_DIMM1_FRU_3TP_CHE_CPU1_DIMM1_FRU_2TP_CHE_CPU1_DIMM1_FRU_1M_E_CPU1_SB_CB<7:0>M_E_CPU1_SA_CA<6:0>SCONN288_ADR50017-P130CCIOSCONN288_ADR50017-P130CCSMLF SMLFSMLFSCONN288_ADR50017-P130CCM_E_CPU1_SA_DQ<31:0>M_E_CPU1_SB_DQ<31:0>M_E_CPU1_CLK_DN<0>M_E_CPU1_CLK_DP<0>M_E_CPU1_SA_CS_N<0>M_E_CPU1_SB_CS_N<0>M_E_CPU1_SA_CS_N<1>M_E_CPU1_SB_CS_N<1>M_E_CPU1_SA_RSP<0>M_E_CPU1_SB_RSP<0>M_E_CPU1_SA_PARM_E_CPU1_SB_PARTP_CHE_CPU1_DIMM1_FRU_0
IOIOM_E_CPU1_SA_CB<7:0>0402LFCHIP1/16W1%10KX6SC080516V10%10UFX6S16V10UF10%C0805PD_CHE_CPU1_DIMM1_SAA
M_E_CPU1_SB_CA<6:0>
PLACE THE BYPASS CAPS CLOSE TO DIMM20%2.2UF6.3VX6SC0402
DQS7_A_c||TDQS7_A_c
DQS6_A_t||TDQS6_A_t
DQS8_B_t||TDQS8_B_t
DQS8_B_c||TDQS8_B_c
DQS7_B_t||TDQS7_B_t
DQS0_A_c
DQS0_A_t
DQS0_B_c
DQS0_B_t
DQS1_A_c
DQS1_A_t
DQS1_B_c
DQS1_B_t
DQS2_A_c
DQS2_A_t
DQS2_B_c
DQS2_B_t
DQS3_A_c
DQS3_A_t
DQS3_B_c
DQS3_B_t
DQS4_A_c
DQS4_A_t
DQS4_B_c
DQS4_B_t
DQS5_A_c||TDQS5_A_c||DQS5_A_t||TDQS5_A_t
DQS5_A_t||TDQS5_A_t
DQS5_B_c||TDQS5_B_c
DQS5_B_t||TDQS5_B_t
DQS6_A_c||TDQS6_A_c||DQS6_A_t||TDQS6_A_t
DQS6_B_c||TDQS6_B_c
DQS6_B_t||TDQS6_B_t
DQS7_A_t||TDQS7_A_t
DQS7_B_c||TDQS7_B_c
DQS8_A_c||TDQS8_A_c
DQS8_A_t||TDQS8_A_t
DQS9_A_c||TDQS9_A_c
DQS9_A_t||TDQS9_A_t
DQS9_B_c||TDQS9_B_c
DQS9_B_t||TDQS9_B_t||DBI4_B_n
R3899
93
94
201
200
283
282
190
189
272
271
179
178
261
260
168
167
250
249
157
156
239
238
55
56
137
138
44
45
126
127
33
34
115
116
22
23
104
105
11
12
3
232
231
220
150
149
144
2
207
147
227
74
87
86
5
4
148
287
194
285
192
142
49
140
47
280
187
278
185
135
42
133
40
276
183
274
181
131
38
129
36
269
176
267
174
124
31
122
29
265
172
263
170
120
27
118
25
258
165
256
163
113
20
111
18
254
161
252
159
109
16
107
14
247
154
245
152
102
9
100
7
229
209
84
64
217
218
236
205
234
203
91
60
89
58
243
198
241
196
98
53
96
51
82
72
225
215
80
70
223
213
78
68
221
211
76
66
62
288
286
284
281
279
277
275
273
270
268
266
264
262
259
257
255
253
251
248
246
244
242
240
237
235
233
230
228
226
224
222
219
216
214
212
210
208
206
204
202
199
197
195
193
191
188
186
184
182
180
177
175
173
171
169
166
164
162
160
158
155
153
151
143
141
139
136
134
132
130
128
125
123
121
119
117
114
112
110
108
106
103
101
99
97
95
92
90
88
85
83
81
79
77
75
73
71
69
67
65
63
61
59
57
54
52
50
48
46
43
41
39
37
35
32
30
28
26
24
21
19
17
15
13
10
8
6
146
145
1
G3
G2
G1
5
9
8
7
6
5
4
3
2
1
0
9
8
7
6
4
3
1
2
0
9
8
7
6
5
4
3
2
1
0
9
8
7
6
5
4
3
2
1
0
3
28
24
5
11
10
8
7
9
5
6
2
4
1
0
30
31
29
25
26
27
6
5
4
3
2
0
1
6
5
4
3
2
1
0
6
7
4
3
2
1
7
0
5
6
23
22
21
20
17
18
19
15
16
12
13
14
10
11
7
8
9
6
5
4
3
2
0
1
4
1
0
2
3
31
30
28
29
25
26
27
23
24
20
21
22
18
19
16
15
17
13
14
12
J25J25 J25
2/31/3
DQ31_A
CB7_A
CB4_A
CB1_A
CB7_B
ALERT_n
CA0_A
CA0_B
CA1_A
CA1_B
CA2_A
CA2_B
CA3_A
CA3_B
CA4_A
CA4_B
CA5_A
CA5_B
CA6_A
CA6_B
CB6_A
CB5_A
CB3_A
CB2_A
CB0_A
CB6_B
CB5_B
CB4_B
CB3_B
CB2_B
CB1_B
CB0_B
CK_c
CK_t
CS0_A_n
CS0_B_n
CS1_A_n
CS1_B_n
DQ30_A
DQ29_A
DQ28_A
DQ27_A
DQ26_A
DQ25_A
DQ24_A
DQ23_A
DQ22_A
DQ21_A
DQ20_A
DQ19_A
DQ18_A
DQ17_A
DQ16_A
DQ15_A
DQ14_A
DQ13_A
DQ12_A
DQ11_A
DQ10_A
DQ9_A
DQ8_A
DQ7_A
DQ6_A
DQ5_A
DQ4_A
DQ3_A
DQ2_A
DQ1_A
DQ0_A
DQ31_B
DQ30_B
DQ29_B
DQ28_B
DQ27_B
DQ26_B
DQ25_B
DQ24_B
DQ23_B
DQ22_B
DQ21_B
DQ20_B
DQ19_B
DQ18_B
DQ17_B
DQ16_B
DQ15_B
DQ14_B
DQ13_B
DQ12_B
DQ11_B
DQ10_B
DQ9_B
DQ8_B
DQ7_B
DQ6_B
DQ5_B
DQ4_B
DQ3_B
DQ2_B
DQ1_B
DQ0_B
HSA
HSCL
HSDA
LBD||RSP_A_n
LBS||RSP_B_n
PAR_A
PAR_B
PWR_GOOD||FAIL_n
RESET_n
RFU6
RFU5
RFU4
RFU3
RFU2
RFU1
RFU0
VIN_MGMT
3/3
G3
G2
G1
VSS62
VSS61
VSS60
VSS58
VSS104
VSS102
VSS100
VIN_BULK2
VIN_BULK1
VIN_BULK0
VSS126
VSS125
VSS124
VSS123
VSS122
VSS121
VSS120
VSS119
VSS118
VSS117
VSS116
VSS115
VSS114
VSS113
VSS112
VSS111
VSS110
VSS109
VSS108
VSS107
VSS106
VSS105
VSS103
VSS101
VSS99
VSS98
VSS97
VSS96
VSS95
VSS94
VSS93
VSS92
VSS91
VSS90
VSS89
VSS88
VSS87
VSS86
VSS85
VSS84
VSS83
VSS82
VSS81
VSS80
VSS79
VSS78
VSS77
VSS76
VSS75
VSS74
VSS73
VSS72
VSS71
VSS70
VSS69
VSS68
VSS67
VSS66
VSS65
VSS64
VSS63
VSS59
VSS57
VSS56
VSS55
VSS54
VSS53
VSS52
VSS51
VSS50
VSS49
VSS48
VSS47
VSS46
VSS45
VSS44
VSS43
VSS42
VSS41
VSS40
VSS39
VSS38
VSS37
VSS36
VSS35
VSS34
VSS33
VSS32
VSS31
VSS30
VSS29
VSS28
VSS27
VSS26
VSS25
VSS24
VSS23
VSS22
VSS21
VSS20
VSS19
VSS18
VSS17
VSS16
VSS15
VSS14
VSS13
VSS12
VSS11
VSS10
VSS9
VSS8
VSS7
VSS6
VSS5
VSS4
VSS3
VSS2
VSS1
VSS0
21
2
1
2
1
2
1
2
1
CAD NOTE:
SHEETDATE
DEPARTMENT
SIZE
PROJECT DOCUMENT NUMBER REV
REVIEWER
DESIGNER
123
7 3 2 1 6 5 4
E
A
B
C
E
D
C
B
A
7 6 5 4
D
ININ
BI
OUTOUT
OUT
IN
IN
ININ
ININ
IN
IN
OUTOUT
OUTOUTIN
BI
ININ
BI
BI
BI
IN
IN
C95C94C93
R79
C



20210728 MODIFY FOR GT
Fri Aug 25 14:01:27 2023N/AN/AN/AN/AV05107 OF 312
P3V3_AUXP3V3_AUX
P12V_S3_AUX_CPU1_NVDIMM
P12V_S3_AUX_CPU1_NVDIMMDDR5 - CPU1 CHE DIMM2(BLACK)
23010610810911011111211310755106130106108109230106108109110111112113114551065510655106551065510655555555555555555510655106
10755 10655106551065510655 106
PLACE THE BYPASS CAPS CLOSE TO DIMM10UFI3C_SPD_DDREFGH_CPU1_LVC1_SCL_R2CHIPI3C_SPD_DDREFGH_CPU1_LVC1_SDAPD_CHE_CPU1_DIMM2_SAAM_E_CPU1_ALERT_NRST_M_EF_CPU1_FPGA_N49.9I3C_SPD_DDREFGH_CPU1_LVC1_SCLPWRGD_CHE_CPU1_DIMM2M_E_CPU1_SA_DQS_DP<9:0>M_E_CPU1_SA_DQS_DN<9:0>M_E_CPU1_SB_DQS_DP<9:0>M_E_CPU1_SB_DQS_DN<9:0>TP_CHE_CPU1_DIMM2_FRU_6TP_CHE_CPU1_DIMM2_FRU_5TP_CHE_CPU1_DIMM2_FRU_4TP_CHE_CPU1_DIMM2_FRU_3TP_CHE_CPU1_DIMM2_FRU_2TP_CHE_CPU1_DIMM2_FRU_0
M_E_CPU1_SA_CA<6:0>SMLFSCONN288_ADR50017-P087CC SCONN288_ADR50017-P087CCSMLFIOM_E_CPU1_CLK_DN<1>M_E_CPU1_CLK_DP<1>M_E_CPU1_SA_CS_N<2>M_E_CPU1_SB_CS_N<2>M_E_CPU1_SA_CS_N<3>M_E_CPU1_SB_CS_N<3>M_E_CPU1_SA_RSP<1>M_E_CPU1_SB_RSP<1>M_E_CPU1_SA_PARM_E_CPU1_SB_PARTP_CHE_CPU1_DIMM2_FRU_1
IOSCONN288_ADR50017-P087CCIOSMLF
15.4K1%CHIP1/16W0402LFX6S16V10%10UFC0805X6S10%C080516VPD_CHE_CPU1_DIMM2_SAAM_E_CPU1_SB_DQ<31:0>M_E_CPU1_SB_CA<6:0>M_E_CPU1_SB_CB<7:0>M_E_CPU1_SA_CB<7:0>M_E_CPU1_SA_DQ<31:0>
C04022.2UF20%X6S6.3V
DQS7_A_c||TDQS7_A_c
DQS6_A_t||TDQS6_A_t
DQS8_B_t||TDQS8_B_t
DQS8_B_c||TDQS8_B_c
DQS7_B_t||TDQS7_B_t
DQS0_A_c
DQS0_A_t
DQS0_B_c
DQS0_B_t
DQS1_A_c
DQS1_A_t
DQS1_B_c
DQS1_B_t
DQS2_A_c
DQS2_A_t
DQS2_B_c
DQS2_B_t
DQS3_A_c
DQS3_A_t
DQS3_B_c
DQS3_B_t
DQS4_A_c
DQS4_A_t
DQS4_B_c
DQS4_B_t
DQS5_A_c||TDQS5_A_c||DQS5_A_t||TDQS5_A_t
DQS5_A_t||TDQS5_A_t
DQS5_B_c||TDQS5_B_c
DQS5_B_t||TDQS5_B_t
DQS6_A_c||TDQS6_A_c||DQS6_A_t||TDQS6_A_t
DQS6_B_c||TDQS6_B_c
DQS6_B_t||TDQS6_B_t
DQS7_A_t||TDQS7_A_t
DQS7_B_c||TDQS7_B_c
DQS8_A_c||TDQS8_A_c
DQS8_A_t||TDQS8_A_t
DQS9_A_c||TDQS9_A_c
DQS9_A_t||TDQS9_A_t
DQS9_B_c||TDQS9_B_c
DQS9_B_t||TDQS9_B_t||DBI4_B_n
R3900
93
94
201
200
283
282
190
189
272
271
179
178
261
260
168
167
250
249
157
156
239
238
55
56
137
138
44
45
126
127
33
34
115
116
22
23
104
105
11
12
3
232
231
220
150
149
144
2
207
147
227
74
87
86
5
4
148
287
194
285
192
142
49
140
47
280
187
278
185
135
42
133
40
276
183
274
181
131
38
129
36
269
176
267
174
124
31
122
29
265
172
263
170
120
27
118
25
258
165
256
163
113
20
111
18
254
161
252
159
109
16
107
14
247
154
245
152
102
9
100
7
229
209
84
64
217
218
236
205
234
203
91
60
89
58
243
198
241
196
98
53
96
51
82
72
225
215
80
70
223
213
78
68
221
211
76
66
62
288
286
284
281
279
277
275
273
270
268
266
264
262
259
257
255
253
251
248
246
244
242
240
237
235
233
230
228
226
224
222
219
216
214
212
210
208
206
204
202
199
197
195
193
191
188
186
184
182
180
177
175
173
171
169
166
164
162
160
158
155
153
151
143
141
139
136
134
132
130
128
125
123
121
119
117
114
112
110
108
106
103
101
99
97
95
92
90
88
85
83
81
79
77
75
73
71
69
67
65
63
61
59
57
54
52
50
48
46
43
41
39
37
35
32
30
28
26
24
21
19
17
15
13
10
8
6
146
145
1
G3
G2
G1
2
9
8
7
6
5
3
4
2
1
0
9
8
7
6
5
4
3
1
0
9
8
7
6
5
4
3
2
1
0
9
8
7
6
5
4
3
2
1
0
15
12
11
10
5
7
8
6
9
3
4
1
2
0
28
29
30
31
24
26
25
27
23
5
3
4
2
1
0
4
5
6
3
0
1
2
4
6
7
5
1
2
3
0
6
7
5
4
3
18
19
20
21
22
17
16
15
14
13
8
9
10
11
12
5
6
7
3
2
4
1
0
2
1
0
316
29
30
28
27
26
24
25
23
22
21
16
20
19
18
17
14
13
J26
J26 J26
2/31/3
DQ31_A
CB7_A
CB4_A
CB1_A
CB7_B
ALERT_n
CA0_A
CA0_B
CA1_A
CA1_B
CA2_A
CA2_B
CA3_A
CA3_B
CA4_A
CA4_B
CA5_A
CA5_B
CA6_A
CA6_B
CB6_A
CB5_A
CB3_A
CB2_A
CB0_A
CB6_B
CB5_B
CB4_B
CB3_B
CB2_B
CB1_B
CB0_B
CK_c
CK_t
CS0_A_n
CS0_B_n
CS1_A_n
CS1_B_n
DQ30_A
DQ29_A
DQ28_A
DQ27_A
DQ26_A
DQ25_A
DQ24_A
DQ23_A
DQ22_A
DQ21_A
DQ20_A
DQ19_A
DQ18_A
DQ17_A
DQ16_A
DQ15_A
DQ14_A
DQ13_A
DQ12_A
DQ11_A
DQ10_A
DQ9_A
DQ8_A
DQ7_A
DQ6_A
DQ5_A
DQ4_A
DQ3_A
DQ2_A
DQ1_A
DQ0_A
DQ31_B
DQ30_B
DQ29_B
DQ28_B
DQ27_B
DQ26_B
DQ25_B
DQ24_B
DQ23_B
DQ22_B
DQ21_B
DQ20_B
DQ19_B
DQ18_B
DQ17_B
DQ16_B
DQ15_B
DQ14_B
DQ13_B
DQ12_B
DQ11_B
DQ10_B
DQ9_B
DQ8_B
DQ7_B
DQ6_B
DQ5_B
DQ4_B
DQ3_B
DQ2_B
DQ1_B
DQ0_B
HSA
HSCL
HSDA
LBD||RSP_A_n
LBS||RSP_B_n
PAR_A
PAR_B
PWR_GOOD||FAIL_n
RESET_n
RFU6
RFU5
RFU4
RFU3
RFU2
RFU1
RFU0
VIN_MGMT
3/3
G3
G2
G1
VSS62
VSS61
VSS60
VSS58
VSS104
VSS102
VSS100
VIN_BULK2
VIN_BULK1
VIN_BULK0
VSS126
VSS125
VSS124
VSS123
VSS122
VSS121
VSS120
VSS119
VSS118
VSS117
VSS116
VSS115
VSS114
VSS113
VSS112
VSS111
VSS110
VSS109
VSS108
VSS107
VSS106
VSS105
VSS103
VSS101
VSS99
VSS98
VSS97
VSS96
VSS95
VSS94
VSS93
VSS92
VSS91
VSS90
VSS89
VSS88
VSS87
VSS86
VSS85
VSS84
VSS83
VSS82
VSS81
VSS80
VSS79
VSS78
VSS77
VSS76
VSS75
VSS74
VSS73
VSS72
VSS71
VSS70
VSS69
VSS68
VSS67
VSS66
VSS65
VSS64
VSS63
VSS59
VSS57
VSS56
VSS55
VSS54
VSS53
VSS52
VSS51
VSS50
VSS49
VSS48
VSS47
VSS46
VSS45
VSS44
VSS43
VSS42
VSS41
VSS40
VSS39
VSS38
VSS37
VSS36
VSS35
VSS34
VSS33
VSS32
VSS31
VSS30
VSS29
VSS28
VSS27
VSS26
VSS25
VSS24
VSS23
VSS22
VSS21
VSS20
VSS19
VSS18
VSS17
VSS16
VSS15
VSS14
VSS13
VSS12
VSS11
VSS10
VSS9
VSS8
VSS7
VSS6
VSS5
VSS4
VSS3
VSS2
VSS1
VSS0
21
2
1
2
1
2
1
2
1
CAD NOTE:
SHEETDATE
DEPARTMENT
SIZE
PROJECT DOCUMENT NUMBER REV
REVIEWER
DESIGNER
123
7 3 2 1 6 5 4
E
A
B
C
E
D
C
B
A
7 6 5 4
D
ININ
BI
OUTOUT
OUT
IN
IN
ININ
IN
IN
IN
OUTBI OUT
IN
OUTOUT
IN
IN
BI
BI
BI
IN
IN
IN
R78
C92C91C90
C



20210728 MODIFY FOR GT
108 OF 312V05N/AN/AN/AN/AFri Aug 25 14:01:29 2023P3V3_AUX P12V_S3_AUX_CPU1_NVDIMM
P12V_S3_AUX_CPU1_NVDIMMP3V3_AUX
DDR5 - CPU1 CHF DIMM1(YELLOW)
108230106107109110111112113130106107109561092301061071091101111121131145610956109561095610956 10956565656565656565610956109
108
5610956109561095610956 109I3C_SPD_DDREFGH_CPU1_LVC1_SCL_R3PD_CHF_CPU1_DIMM1_SAAI3C_SPD_DDREFGH_CPU1_LVC1_SDARST_M_EF_CPU1_FPGA_NM_F_CPU1_ALERT_NI3C_SPD_DDREFGH_CPU1_LVC1_SCL49.9CHIPPWRGD_CHF_CPU1_DIMM11% M_F_CPU1_SA_DQS_DP<9:0>M_F_CPU1_SA_DQS_DN<9:0>M_F_CPU1_SB_DQS_DP<9:0>M_F_CPU1_SB_DQS_DN<9:0>M_F_CPU1_SB_DQ<31:0>TP_CHF_CPU1_DIMM1_FRU_6TP_CHF_CPU1_DIMM1_FRU_1M_F_CPU1_SA_RSP<0>TP_CHF_CPU1_DIMM1_FRU_2TP_CHF_CPU1_DIMM1_FRU_3
SCONN288_ADR50017-P130CCSCONN288_ADR50017-P130CCSMLFSCONN288_ADR50017-P130CCSMLF SMLFIOM_F_CPU1_CLK_DN<0>M_F_CPU1_CLK_DP<0>M_F_CPU1_SA_CS_N<0>M_F_CPU1_SB_CS_N<0>M_F_CPU1_SA_CS_N<1>M_F_CPU1_SB_CS_N<1>M_F_CPU1_SB_RSP<0>M_F_CPU1_SA_PARM_F_CPU1_SB_PARTP_CHF_CPU1_DIMM1_FRU_5TP_CHF_CPU1_DIMM1_FRU_4TP_CHF_CPU1_DIMM1_FRU_0
IOIO
1%0402LFCHIP1/16W23.2KX6S16V10%C080510UFX6S10UF16V10%C0805PD_CHF_CPU1_DIMM1_SAA
M_F_CPU1_SB_CA<6:0>M_F_CPU1_SA_CA<6:0>M_F_CPU1_SB_CB<7:0>M_F_CPU1_SA_CB<7:0>M_F_CPU1_SA_DQ<31:0>
PLACE THE BYPASS CAPS CLOSE TO DIMMX6S6.3V20%C04022.2UF
DQS7_A_c||TDQS7_A_c
DQS6_A_t||TDQS6_A_t
DQS8_B_t||TDQS8_B_t
DQS8_B_c||TDQS8_B_c
DQS7_B_t||TDQS7_B_t
DQS0_A_c
DQS0_A_t
DQS0_B_c
DQS0_B_t
DQS1_A_c
DQS1_A_t
DQS1_B_c
DQS1_B_t
DQS2_A_c
DQS2_A_t
DQS2_B_c
DQS2_B_t
DQS3_A_c
DQS3_A_t
DQS3_B_c
DQS3_B_t
DQS4_A_c
DQS4_A_t
DQS4_B_c
DQS4_B_t
DQS5_A_c||TDQS5_A_c||DQS5_A_t||TDQS5_A_t
DQS5_A_t||TDQS5_A_t
DQS5_B_c||TDQS5_B_c
DQS5_B_t||TDQS5_B_t
DQS6_A_c||TDQS6_A_c||DQS6_A_t||TDQS6_A_t
DQS6_B_c||TDQS6_B_c
DQS6_B_t||TDQS6_B_t
DQS7_A_t||TDQS7_A_t
DQS7_B_c||TDQS7_B_c
DQS8_A_c||TDQS8_A_c
DQS8_A_t||TDQS8_A_t
DQS9_A_c||TDQS9_A_c
DQS9_A_t||TDQS9_A_t
DQS9_B_c||TDQS9_B_c
DQS9_B_t||TDQS9_B_t||DBI4_B_n
R3901
93
94
201
200
283
282
190
189
272
271
179
178
261
260
168
167
250
249
157
156
239
238
55
56
137
138
44
45
126
127
33
34
115
116
22
23
104
105
11
12
3
232
231
220
150
149
144
2
207
147
227
74
87
86
5
4
148
287
194
285
192
142
49
140
47
280
187
278
185
135
42
133
40
276
183
274
181
131
38
129
36
269
176
267
174
124
31
122
29
265
172
263
170
120
27
118
25
258
165
256
163
113
20
111
18
254
161
252
159
109
16
107
14
247
154
245
152
102
9
100
7
229
209
84
64
217
218
236
205
234
203
91
60
89
58
243
198
241
196
98
53
96
51
82
72
225
215
80
70
223
213
78
68
221
211
76
66
62
288
286
284
281
279
277
275
273
270
268
266
264
262
259
257
255
253
251
248
246
244
242
240
237
235
233
230
228
226
224
222
219
216
214
212
210
208
206
204
202
199
197
195
193
191
188
186
184
182
180
177
175
173
171
169
166
164
162
160
158
155
153
151
143
141
139
136
134
132
130
128
125
123
121
119
117
114
112
110
108
106
103
101
99
97
95
92
90
88
85
83
81
79
77
75
73
71
69
67
65
63
61
59
57
54
52
50
48
46
43
41
39
37
35
32
30
28
26
24
21
19
17
15
13
10
8
6
146
145
1
G3
G2
G1
9
8
7
6
5
4
3
0
1
2
9
8
7
6
5
4
3
0
2
1
7
8
9
5
6
4
3
2
0
1
9
8
7
6
5
4
3
2
0
1
27
16
31
21
20
18
19
17
16
15
13
14
12
11
10
8
9
7
5
6
4
2
3
1
0
30
28
29
27
26
25
23
24
21
22
20
19
18
17
15
14
13
10
11
9
8
7
5
6
3
4
2
0
1
6
5
4
3
2
1
0
6
7
4
5
3
2
1
0
7
5
6
4
3
2
1
0
12
31
29
30
28
26
25
6
5
4
3
2
0
1
23
24
22
J27J27 J27
2/31/3
DQ31_A
CB7_A
CB4_A
CB1_A
CB7_B
ALERT_n
CA0_A
CA0_B
CA1_A
CA1_B
CA2_A
CA2_B
CA3_A
CA3_B
CA4_A
CA4_B
CA5_A
CA5_B
CA6_A
CA6_B
CB6_A
CB5_A
CB3_A
CB2_A
CB0_A
CB6_B
CB5_B
CB4_B
CB3_B
CB2_B
CB1_B
CB0_B
CK_c
CK_t
CS0_A_n
CS0_B_n
CS1_A_n
CS1_B_n
DQ30_A
DQ29_A
DQ28_A
DQ27_A
DQ26_A
DQ25_A
DQ24_A
DQ23_A
DQ22_A
DQ21_A
DQ20_A
DQ19_A
DQ18_A
DQ17_A
DQ16_A
DQ15_A
DQ14_A
DQ13_A
DQ12_A
DQ11_A
DQ10_A
DQ9_A
DQ8_A
DQ7_A
DQ6_A
DQ5_A
DQ4_A
DQ3_A
DQ2_A
DQ1_A
DQ0_A
DQ31_B
DQ30_B
DQ29_B
DQ28_B
DQ27_B
DQ26_B
DQ25_B
DQ24_B
DQ23_B
DQ22_B
DQ21_B
DQ20_B
DQ19_B
DQ18_B
DQ17_B
DQ16_B
DQ15_B
DQ14_B
DQ13_B
DQ12_B
DQ11_B
DQ10_B
DQ9_B
DQ8_B
DQ7_B
DQ6_B
DQ5_B
DQ4_B
DQ3_B
DQ2_B
DQ1_B
DQ0_B
HSA
HSCL
HSDA
LBD||RSP_A_n
LBS||RSP_B_n
PAR_A
PAR_B
PWR_GOOD||FAIL_n
RESET_n
RFU6
RFU5
RFU4
RFU3
RFU2
RFU1
RFU0
VIN_MGMT
3/3
G3
G2
G1
VSS62
VSS61
VSS60
VSS58
VSS104
VSS102
VSS100
VIN_BULK2
VIN_BULK1
VIN_BULK0
VSS126
VSS125
VSS124
VSS123
VSS122
VSS121
VSS120
VSS119
VSS118
VSS117
VSS116
VSS115
VSS114
VSS113
VSS112
VSS111
VSS110
VSS109
VSS108
VSS107
VSS106
VSS105
VSS103
VSS101
VSS99
VSS98
VSS97
VSS96
VSS95
VSS94
VSS93
VSS92
VSS91
VSS90
VSS89
VSS88
VSS87
VSS86
VSS85
VSS84
VSS83
VSS82
VSS81
VSS80
VSS79
VSS78
VSS77
VSS76
VSS75
VSS74
VSS73
VSS72
VSS71
VSS70
VSS69
VSS68
VSS67
VSS66
VSS65
VSS64
VSS63
VSS59
VSS57
VSS56
VSS55
VSS54
VSS53
VSS52
VSS51
VSS50
VSS49
VSS48
VSS47
VSS46
VSS45
VSS44
VSS43
VSS42
VSS41
VSS40
VSS39
VSS38
VSS37
VSS36
VSS35
VSS34
VSS33
VSS32
VSS31
VSS30
VSS29
VSS28
VSS27
VSS26
VSS25
VSS24
VSS23
VSS22
VSS21
VSS20
VSS19
VSS18
VSS17
VSS16
VSS15
VSS14
VSS13
VSS12
VSS11
VSS10
VSS9
VSS8
VSS7
VSS6
VSS5
VSS4
VSS3
VSS2
VSS1
VSS0
21
2
1
2
1
2
1
2
1
CAD NOTE:
SHEETDATE
DEPARTMENT
SIZE
PROJECT DOCUMENT NUMBER REV
REVIEWER
DESIGNER
123
7 3 2 1 6 5 4
E
A
B
C
E
D
C
B
A
7 6 5 4
D
IN
ININ
BI
OUT
IN
IN
ININ
OUT
IN
IN
IN
OUTOUT
IN
OUTOUT
IN
IN
BI
BI
BI
IN
IN
BI
OUT
C89C88C87
R77
C



20210728 MODIFY FOR GT
Fri Aug 25 14:01:30 2023N/AN/AN/AN/AV05109 OF 312P3V3_AUX P12V_S3_AUX_CPU1_NVDIMM
P12V_S3_AUX_CPU1_NVDIMMP3V3_AUX
DDR5 - CPU1 CHF DIMM2(BLACK)
1092301061071081101111121132301061071081101111121135610813010610710811456108561085610856108561085656561085656565656565610856108
10956 1085610856108 56 108
PLACE THE BYPASS CAPS CLOSE TO DIMM6.3VPD_CHF_CPU1_DIMM2_SAAI3C_SPD_DDREFGH_CPU1_LVC1_SDAI3C_SPD_DDREFGH_CPU1_LVC1_SCL_R4I3C_SPD_DDREFGH_CPU1_LVC1_SCLM_F_CPU1_ALERT_NRST_M_EF_CPU1_FPGA_NCHIPPWRGD_CHF_CPU1_DIMM2TP_CHF_CPU1_DIMM2_FRU_5TP_CHF_CPU1_DIMM2_FRU_6M_F_CPU1_SB_CB<7:0>M_F_CPU1_SA_DQS_DP<9:0>M_F_CPU1_SA_DQS_DN<9:0>M_F_CPU1_SB_DQS_DP<9:0>M_F_CPU1_SB_DQS_DN<9:0>49.9
SMLFSCONN288_ADR50017-P087CC SCONN288_ADR50017-P087CCM_F_CPU1_CLK_DN<1>M_F_CPU1_CLK_DP<1>M_F_CPU1_SA_CB<7:0>M_F_CPU1_SA_CS_N<2>M_F_CPU1_SB_CS_N<2>M_F_CPU1_SA_CS_N<3>M_F_CPU1_SB_CS_N<3>M_F_CPU1_SA_RSP<1>M_F_CPU1_SB_RSP<1>M_F_CPU1_SA_PARM_F_CPU1_SB_PARTP_CHF_CPU1_DIMM2_FRU_4TP_CHF_CPU1_DIMM2_FRU_3TP_CHF_CPU1_DIMM2_FRU_2TP_CHF_CPU1_DIMM2_FRU_1TP_CHF_CPU1_DIMM2_FRU_0
IO SMLFIOSCONN288_ADR50017-P087CCIOSMLF
1/16W1%CHIP0402LF35.7KX6SC080510UF16V10%X6S10%16V10UFC0805PD_CHF_CPU1_DIMM2_SAAM_F_CPU1_SB_DQ<31:0>M_F_CPU1_SB_CA<6:0>M_F_CPU1_SA_CA<6:0> M_F_CPU1_SA_DQ<31:0>
2.2UFX6S20%C0402
DQS7_A_c||TDQS7_A_c
DQS6_A_t||TDQS6_A_t
DQS8_B_t||TDQS8_B_t
DQS8_B_c||TDQS8_B_c
DQS7_B_t||TDQS7_B_t
DQS0_A_c
DQS0_A_t
DQS0_B_c
DQS0_B_t
DQS1_A_c
DQS1_A_t
DQS1_B_c
DQS1_B_t
DQS2_A_c
DQS2_A_t
DQS2_B_c
DQS2_B_t
DQS3_A_c
DQS3_A_t
DQS3_B_c
DQS3_B_t
DQS4_A_c
DQS4_A_t
DQS4_B_c
DQS4_B_t
DQS5_A_c||TDQS5_A_c||DQS5_A_t||TDQS5_A_t
DQS5_A_t||TDQS5_A_t
DQS5_B_c||TDQS5_B_c
DQS5_B_t||TDQS5_B_t
DQS6_A_c||TDQS6_A_c||DQS6_A_t||TDQS6_A_t
DQS6_B_c||TDQS6_B_c
DQS6_B_t||TDQS6_B_t
DQS7_A_t||TDQS7_A_t
DQS7_B_c||TDQS7_B_c
DQS8_A_c||TDQS8_A_c
DQS8_A_t||TDQS8_A_t
DQS9_A_c||TDQS9_A_c
DQS9_A_t||TDQS9_A_t
DQS9_B_c||TDQS9_B_c
DQS9_B_t||TDQS9_B_t||DBI4_B_n
R3902
93
94
201
200
283
282
190
189
272
271
179
178
261
260
168
167
250
249
157
156
239
238
55
56
137
138
44
45
126
127
33
34
115
116
22
23
104
105
11
12
288
286
284
281
279
277
275
273
270
268
266
264
262
259
257
255
253
251
248
246
244
242
240
237
235
233
230
228
226
224
222
219
216
214
212
210
208
206
204
202
199
197
195
193
191
188
186
184
182
180
177
175
173
171
169
166
164
162
160
158
155
153
151
143
141
139
136
134
132
130
128
125
123
121
119
117
114
112
110
108
106
103
101
99
97
95
92
90
88
85
83
81
79
77
75
73
71
69
67
65
63
61
59
57
54
52
50
48
46
43
41
39
37
35
32
30
28
26
24
21
19
17
15
13
10
8
6
146
145
1
G3
G2
G1
3
232
231
220
150
149
144
2
207
147
227
74
87
86
5
4
148
287
194
285
192
142
49
140
47
280
187
278
185
135
42
133
40
276
183
274
181
131
38
129
36
269
176
267
174
124
31
122
29
265
172
263
170
120
27
118
25
258
165
256
163
113
20
111
18
254
161
252
159
109
16
107
14
247
154
245
152
102
9
100
7
229
209
84
64
217
218
236
205
234
203
91
60
89
58
243
198
241
196
98
53
96
51
82
72
225
215
80
70
223
213
78
68
221
211
76
66
62
9
8
7
6
5
4
3
2
1
0
9
8
7
5
6
4
3
2
1
0
8
9
6
7
3
4
5
1
2
9
0
8
6
7
4
5
3
1
2
0
27
3
9
23
4
17
18
19
15
16
13
14
12
11
10
8
7
6
5
4
2
3
1
0
31
30
28
29
26
25
22
24
20
21
17
18
19
16
15
14
12
13
11
10
9
7
8
4
5
6
3
2
0
1
5
6
4
3
2
1
0
6
7
5
4
3
1
2
7
0
6
5
2
0
1
31
30
27
29
28
25
26
5
6
3
4
2
0
1
24
23
22
20
21
J28
J28J28
1/3
DQ31_A
CB7_A
CB4_A
CB1_A
CB7_B
ALERT_n
CA0_A
CA0_B
CA1_A
CA1_B
CA2_A
CA2_B
CA3_A
CA3_B
CA4_A
CA4_B
CA5_A
CA5_B
CA6_A
CA6_B
CB6_A
CB5_A
CB3_A
CB2_A
CB0_A
CB6_B
CB5_B
CB4_B
CB3_B
CB2_B
CB1_B
CB0_B
CK_c
CK_t
CS0_A_n
CS0_B_n
CS1_A_n
CS1_B_n
DQ30_A
DQ29_A
DQ28_A
DQ27_A
DQ26_A
DQ25_A
DQ24_A
DQ23_A
DQ22_A
DQ21_A
DQ20_A
DQ19_A
DQ18_A
DQ17_A
DQ16_A
DQ15_A
DQ14_A
DQ13_A
DQ12_A
DQ11_A
DQ10_A
DQ9_A
DQ8_A
DQ7_A
DQ6_A
DQ5_A
DQ4_A
DQ3_A
DQ2_A
DQ1_A
DQ0_A
DQ31_B
DQ30_B
DQ29_B
DQ28_B
DQ27_B
DQ26_B
DQ25_B
DQ24_B
DQ23_B
DQ22_B
DQ21_B
DQ20_B
DQ19_B
DQ18_B
DQ17_B
DQ16_B
DQ15_B
DQ14_B
DQ13_B
DQ12_B
DQ11_B
DQ10_B
DQ9_B
DQ8_B
DQ7_B
DQ6_B
DQ5_B
DQ4_B
DQ3_B
DQ2_B
DQ1_B
DQ0_B
HSA
HSCL
HSDA
LBD||RSP_A_n
LBS||RSP_B_n
PAR_A
PAR_B
PWR_GOOD||FAIL_n
RESET_n
RFU6
RFU5
RFU4
RFU3
RFU2
RFU1
RFU0
VIN_MGMT
2/3 3/3
G3
G2
G1
VSS62
VSS61
VSS60
VSS58
VSS104
VSS102
VSS100
VIN_BULK2
VIN_BULK1
VIN_BULK0
VSS126
VSS125
VSS124
VSS123
VSS122
VSS121
VSS120
VSS119
VSS118
VSS117
VSS116
VSS115
VSS114
VSS113
VSS112
VSS111
VSS110
VSS109
VSS108
VSS107
VSS106
VSS105
VSS103
VSS101
VSS99
VSS98
VSS97
VSS96
VSS95
VSS94
VSS93
VSS92
VSS91
VSS90
VSS89
VSS88
VSS87
VSS86
VSS85
VSS84
VSS83
VSS82
VSS81
VSS80
VSS79
VSS78
VSS77
VSS76
VSS75
VSS74
VSS73
VSS72
VSS71
VSS70
VSS69
VSS68
VSS67
VSS66
VSS65
VSS64
VSS63
VSS59
VSS57
VSS56
VSS55
VSS54
VSS53
VSS52
VSS51
VSS50
VSS49
VSS48
VSS47
VSS46
VSS45
VSS44
VSS43
VSS42
VSS41
VSS40
VSS39
VSS38
VSS37
VSS36
VSS35
VSS34
VSS33
VSS32
VSS31
VSS30
VSS29
VSS28
VSS27
VSS26
VSS25
VSS24
VSS23
VSS22
VSS21
VSS20
VSS19
VSS18
VSS17
VSS16
VSS15
VSS14
VSS13
VSS12
VSS11
VSS10
VSS9
VSS8
VSS7
VSS6
VSS5
VSS4
VSS3
VSS2
VSS1
VSS0
21
2
1
2
1
2
1
2
1
CAD NOTE:
SHEETDATE
DEPARTMENT
SIZE
PROJECT DOCUMENT NUMBER REV
REVIEWER
DESIGNER
123
7 3 2 1 6 5 4
E
A
B
C
E
D
C
B
A
7 6 5 4
D
IN
IN
ININ
BI
OUT
IN
OUT
ININ
IN
OUTOUT
IN
BI
OUTOUT
IN
IN
ININ
BI
IN
BI
IN
BI
OUT
C86C85C84
R76
C



20210728 MODIFY FOR GT
N/AN/AN/AN/AFri Aug 25 14:01:31 2023V05110 OF 312P3V3_AUX P12V_S3_AUX_CPU1_NVDIMM
P12V_S3_AUX_CPU1_NVDIMMP3V3_AUX
DDR5 - CPU1 CHG DIMM1(YELLOW)
230106107108109111112113571111101301111121132301061071081091111121131145711157 11157 11157 11157 1115757575757575757571115711157111110571115711157111 57111I3C_SPD_DDREFGH_CPU1_LVC1_SDAM_G_CPU1_ALERT_NPD_CHG_CPU1_DIMM1_SAARST_M_GH_CPU1_FPGA_NI3C_SPD_DDREFGH_CPU1_LVC1_SCL49.9I3C_SPD_DDREFGH_CPU1_LVC1_SCL_R5CHIPPWRGD_CHG_CPU1_DIMM1TP_CHG_CPU1_DIMM1_FRU_6M_G_CPU1_SA_CB<7:0>M_G_CPU1_SA_DQS_DP<9:0>M_G_CPU1_SA_DQS_DN<9:0>M_G_CPU1_SB_DQS_DP<9:0>M_G_CPU1_SB_DQS_DN<9:0>TP_CHG_CPU1_DIMM1_FRU_0TP_CHG_CPU1_DIMM1_FRU_1TP_CHG_CPU1_DIMM1_FRU_2TP_CHG_CPU1_DIMM1_FRU_3TP_CHG_CPU1_DIMM1_FRU_4TP_CHG_CPU1_DIMM1_FRU_5
SCONN288_ADR50017-P130CCSMLFSCONN288_ADR50017-P130CCM_G_CPU1_CLK_DN<0>M_G_CPU1_CLK_DP<0>M_G_CPU1_SA_CS_N<0>M_G_CPU1_SB_CS_N<0>M_G_CPU1_SA_CS_N<1>M_G_CPU1_SB_CS_N<1>M_G_CPU1_SA_RSP<0>M_G_CPU1_SB_RSP<0>M_G_CPU1_SA_PARM_G_CPU1_SB_PARIOM_G_CPU1_SB_CB<7:0>SMLFIOSMLFSCONN288_ADR50017-P130CCIO
0402LF1%CHIP1/16W54.9KX6S10UF16VC080510%X6S16V10%C080510UFPD_CHG_CPU1_DIMM1_SAAM_G_CPU1_SB_DQ<31:0>M_G_CPU1_SB_CA<6:0>M_G_CPU1_SA_CA<6:0> M_G_CPU1_SA_DQ<31:0>
PLACE THE BYPASS CAPS CLOSE TO DIMMX6S6.3V2.2UF20%C0402
DQS7_A_c||TDQS7_A_c
DQS6_A_t||TDQS6_A_t
DQS8_B_t||TDQS8_B_t
DQS8_B_c||TDQS8_B_c
DQS7_B_t||TDQS7_B_t
DQS0_A_c
DQS0_A_t
DQS0_B_c
DQS0_B_t
DQS1_A_c
DQS1_A_t
DQS1_B_c
DQS1_B_t
DQS2_A_c
DQS2_A_t
DQS2_B_c
DQS2_B_t
DQS3_A_c
DQS3_A_t
DQS3_B_c
DQS3_B_t
DQS4_A_c
DQS4_A_t
DQS4_B_c
DQS4_B_t
DQS5_A_c||TDQS5_A_c||DQS5_A_t||TDQS5_A_t
DQS5_A_t||TDQS5_A_t
DQS5_B_c||TDQS5_B_c
DQS5_B_t||TDQS5_B_t
DQS6_A_c||TDQS6_A_c||DQS6_A_t||TDQS6_A_t
DQS6_B_c||TDQS6_B_c
DQS6_B_t||TDQS6_B_t
DQS7_A_t||TDQS7_A_t
DQS7_B_c||TDQS7_B_c
DQS8_A_c||TDQS8_A_c
DQS8_A_t||TDQS8_A_t
DQS9_A_c||TDQS9_A_c
DQS9_A_t||TDQS9_A_t
DQS9_B_c||TDQS9_B_c
DQS9_B_t||TDQS9_B_t||DBI4_B_n
R3903
93
94
201
200
283
282
190
189
272
271
179
178
261
260
168
167
250
249
157
156
239
238
55
56
137
138
44
45
126
127
33
34
115
116
22
23
104
105
11
12
3
232
231
220
150
149
144
2
207
147
227
74
87
86
5
4
148
287
194
285
192
142
49
140
47
280
187
278
185
135
42
133
40
276
183
274
181
131
38
129
36
269
176
267
174
124
31
122
29
265
172
263
170
120
27
118
25
258
165
256
163
113
20
111
18
254
161
252
159
109
16
107
14
247
154
245
152
102
9
100
7
229
209
84
64
217
218
236
205
234
203
91
60
89
58
243
198
241
196
98
53
96
51
82
72
225
215
80
70
223
213
78
68
221
211
76
66
62
288
286
284
281
279
277
275
273
270
268
266
264
262
259
257
255
253
251
248
246
244
242
240
237
235
233
230
228
226
224
222
219
216
214
212
210
208
206
204
202
199
197
195
193
191
188
186
184
182
180
177
175
173
171
169
166
164
162
160
158
155
153
151
143
141
139
136
134
132
130
128
125
123
121
119
117
114
112
110
108
106
103
101
99
97
95
92
90
88
85
83
81
79
77
75
73
71
69
67
65
63
61
59
57
54
52
50
48
46
43
41
39
37
35
32
30
28
26
24
21
19
17
15
13
10
8
6
146
145
1
G3
G2
G1
0
9
6
8
7
5
4
3
2
1
9
0
8
7
6
5
4
1
3
2
0
6
7
8
9
1
2
3
4
5
0
6
7
8
9
1
2
4
3
5
0
16
19
17
18
14
15
12
13
11
9
10
8
6
7
5
3
4
1
2
31
0
30
29
27
28
26
25
24
22
23
21
20
19
18
17
16
15
14
13
12
11
10
9
8
6
7
5
4
3
1
2
0
0
6
5
4
0
3
2
1
5
6
7
4
0
1
3
2
7
6
5
4
3
2
1
31
30
29
28
27
26
6
4
5
3
2
1
25
24
23
22
21
20
J29J29 J29
2/31/3
DQ31_A
CB7_A
CB4_A
CB1_A
CB7_B
ALERT_n
CA0_A
CA0_B
CA1_A
CA1_B
CA2_A
CA2_B
CA3_A
CA3_B
CA4_A
CA4_B
CA5_A
CA5_B
CA6_A
CA6_B
CB6_A
CB5_A
CB3_A
CB2_A
CB0_A
CB6_B
CB5_B
CB4_B
CB3_B
CB2_B
CB1_B
CB0_B
CK_c
CK_t
CS0_A_n
CS0_B_n
CS1_A_n
CS1_B_n
DQ30_A
DQ29_A
DQ28_A
DQ27_A
DQ26_A
DQ25_A
DQ24_A
DQ23_A
DQ22_A
DQ21_A
DQ20_A
DQ19_A
DQ18_A
DQ17_A
DQ16_A
DQ15_A
DQ14_A
DQ13_A
DQ12_A
DQ11_A
DQ10_A
DQ9_A
DQ8_A
DQ7_A
DQ6_A
DQ5_A
DQ4_A
DQ3_A
DQ2_A
DQ1_A
DQ0_A
DQ31_B
DQ30_B
DQ29_B
DQ28_B
DQ27_B
DQ26_B
DQ25_B
DQ24_B
DQ23_B
DQ22_B
DQ21_B
DQ20_B
DQ19_B
DQ18_B
DQ17_B
DQ16_B
DQ15_B
DQ14_B
DQ13_B
DQ12_B
DQ11_B
DQ10_B
DQ9_B
DQ8_B
DQ7_B
DQ6_B
DQ5_B
DQ4_B
DQ3_B
DQ2_B
DQ1_B
DQ0_B
HSA
HSCL
HSDA
LBD||RSP_A_n
LBS||RSP_B_n
PAR_A
PAR_B
PWR_GOOD||FAIL_n
RESET_n
RFU6
RFU5
RFU4
RFU3
RFU2
RFU1
RFU0
VIN_MGMT
3/3
G3
G2
G1
VSS62
VSS61
VSS60
VSS58
VSS104
VSS102
VSS100
VIN_BULK2
VIN_BULK1
VIN_BULK0
VSS126
VSS125
VSS124
VSS123
VSS122
VSS121
VSS120
VSS119
VSS118
VSS117
VSS116
VSS115
VSS114
VSS113
VSS112
VSS111
VSS110
VSS109
VSS108
VSS107
VSS106
VSS105
VSS103
VSS101
VSS99
VSS98
VSS97
VSS96
VSS95
VSS94
VSS93
VSS92
VSS91
VSS90
VSS89
VSS88
VSS87
VSS86
VSS85
VSS84
VSS83
VSS82
VSS81
VSS80
VSS79
VSS78
VSS77
VSS76
VSS75
VSS74
VSS73
VSS72
VSS71
VSS70
VSS69
VSS68
VSS67
VSS66
VSS65
VSS64
VSS63
VSS59
VSS57
VSS56
VSS55
VSS54
VSS53
VSS52
VSS51
VSS50
VSS49
VSS48
VSS47
VSS46
VSS45
VSS44
VSS43
VSS42
VSS41
VSS40
VSS39
VSS38
VSS37
VSS36
VSS35
VSS34
VSS33
VSS32
VSS31
VSS30
VSS29
VSS28
VSS27
VSS26
VSS25
VSS24
VSS23
VSS22
VSS21
VSS20
VSS19
VSS18
VSS17
VSS16
VSS15
VSS14
VSS13
VSS12
VSS11
VSS10
VSS9
VSS8
VSS7
VSS6
VSS5
VSS4
VSS3
VSS2
VSS1
VSS0
21
2
1
2
1
2
1
2
1
CAD NOTE:
SHEETDATE
DEPARTMENT
SIZE
PROJECT DOCUMENT NUMBER REV
REVIEWER
DESIGNER
123
7 3 2 1 6 5 4
E
A
B
C
E
D
C
B
A
7 6 5 4
D
IN
IN
IN
BI
OUTOUT
IN
IN
OUT
IN
IN
IN
OUTOUT
IN
BI
OUTOUT
ININ
ININ
BI
BI
BI
IN
IN
C83C82C81
R75
C



20210728 MODIFY FOR GT
Fri Aug 25 14:01:32 2023N/AN/AN/AN/AV05111 OF 312P12V_S3_AUX_CPU1_NVDIMMP3V3_AUX
P12V_S3_AUX_CPU1_NVDIMMP3V3_AUX
DDR5 - CPU1 CHG DIMM2(BLACK)230106107108109110112113230106107108109110112113111571101301101121135711057110571105711011457 11057110571105711057 1101115711057110571105757575757575757
PLACE THE BYPASS CAPS CLOSE TO DIMM2.2UFI3C_SPD_DDREFGH_CPU1_LVC1_SCLI3C_SPD_DDREFGH_CPU1_LVC1_SDAI3C_SPD_DDREFGH_CPU1_LVC1_SCL_R6PD_CHG_CPU1_DIMM2_SAAM_G_CPU1_ALERT_NRST_M_GH_CPU1_FPGA_NCHIP49.9TP_CHG_CPU1_DIMM2_FRU_6M_G_CPU1_SA_DQS_DN<9:0>M_G_CPU1_SA_DQS_DP<9:0>M_G_CPU1_SB_DQS_DN<9:0>M_G_CPU1_SB_DQS_DP<9:0>PWRGD_CHG_CPU1_DIMM2TP_CHG_CPU1_DIMM2_FRU_5
IOSCONN288_ADR50017-P087CCSMLFSCONN288_ADR50017-P087CCIO
X6SC040220%6.3V
M_G_CPU1_SA_DQ<31:0>M_G_CPU1_SB_CB<7:0>M_G_CPU1_SA_CA<6:0>M_G_CPU1_SB_CA<6:0>M_G_CPU1_SB_DQ<31:0>PD_CHG_CPU1_DIMM2_SAA10%16VC080510UFX6SC080510UF10%16VX6S84.5K0402LF1%CHIP1/16WM_G_CPU1_SA_CB<7:0>SCONN288_ADR50017-P087CCSMLFIOSMLF
TP_CHG_CPU1_DIMM2_FRU_0TP_CHG_CPU1_DIMM2_FRU_1TP_CHG_CPU1_DIMM2_FRU_2TP_CHG_CPU1_DIMM2_FRU_3TP_CHG_CPU1_DIMM2_FRU_4M_G_CPU1_SB_PARM_G_CPU1_SA_PARM_G_CPU1_SB_RSP<1>M_G_CPU1_SA_RSP<1>M_G_CPU1_SB_CS_N<3>M_G_CPU1_SB_CS_N<2>M_G_CPU1_SA_CS_N<2>M_G_CPU1_CLK_DP<1>M_G_CPU1_CLK_DN<1>M_G_CPU1_SA_CS_N<3>
DQS7_A_c||TDQS7_A_c
DQS6_A_t||TDQS6_A_t
DQS8_B_t||TDQS8_B_t
DQS8_B_c||TDQS8_B_c
DQS7_B_t||TDQS7_B_t
DQS0_A_c
DQS0_A_t
DQS0_B_c
DQS0_B_t
DQS1_A_c
DQS1_A_t
DQS1_B_c
DQS1_B_t
DQS2_A_c
DQS2_A_t
DQS2_B_c
DQS2_B_t
DQS3_A_c
DQS3_A_t
DQS3_B_c
DQS3_B_t
DQS4_A_c
DQS4_A_t
DQS4_B_c
DQS4_B_t
DQS5_A_c||TDQS5_A_c||DQS5_A_t||TDQS5_A_t
DQS5_A_t||TDQS5_A_t
DQS5_B_c||TDQS5_B_c
DQS5_B_t||TDQS5_B_t
DQS6_A_c||TDQS6_A_c||DQS6_A_t||TDQS6_A_t
DQS6_B_c||TDQS6_B_c
DQS6_B_t||TDQS6_B_t
DQS7_A_t||TDQS7_A_t
DQS7_B_c||TDQS7_B_c
DQS8_A_c||TDQS8_A_c
DQS8_A_t||TDQS8_A_t
DQS9_A_c||TDQS9_A_c
DQS9_A_t||TDQS9_A_t
DQS9_B_c||TDQS9_B_c
DQS9_B_t||TDQS9_B_t||DBI4_B_n
R3904
93
94
201
200
283
282
190
189
272
271
179
178
261
260
168
167
250
249
157
156
239
238
55
56
137
138
44
45
126
127
33
34
115
116
22
23
104
105
11
12
3
232
231
220
150
149
144
2
207
147
227
74
87
86
5
4
148
287
194
285
192
142
49
140
47
280
187
278
185
135
42
133
40
276
183
274
181
131
38
129
36
269
176
267
174
124
31
122
29
265
172
263
170
120
27
118
25
258
165
256
163
113
20
111
18
254
161
252
159
109
16
107
14
247
154
245
152
102
9
100
7
229
209
84
64
217
218
236
205
234
203
91
60
89
58
243
198
241
196
98
53
96
51
82
72
225
215
80
70
223
213
78
68
221
211
76
66
62
288
286
284
281
279
277
275
273
270
268
266
264
262
259
257
255
253
251
248
246
244
242
240
237
235
233
230
228
226
224
222
219
216
214
212
210
208
206
204
202
199
197
195
193
191
188
186
184
182
180
177
175
173
171
169
166
164
162
160
158
155
153
151
143
141
139
136
134
132
130
128
125
123
121
119
117
114
112
110
108
106
103
101
99
97
95
92
90
88
85
83
81
79
77
75
73
71
69
67
65
63
61
59
57
54
52
50
48
46
43
41
39
37
35
32
30
28
26
24
21
19
17
15
13
10
8
6
146
145
1
G3
G2
G1
5
5
9
8
7
6
5
4
3
2
1
0
9
8
7
6
3
4
2
1
0
9
8
7
6
5
4
3
2
1
0
9
8
7
6
4
3
2
1
0
23
3
8
7
6
10
9
13
12
11
14
15
17
16
19
20
23
22
24
25
26
27
28
31
30
29
0
1
2
3
5
6
7
1
0
2
3
4
5
6
7
1
0
2
3
4
5
6
0
1
2
3
5
4
6
0
2
1
4
5
3
7
6
10
9
8
12
14
13
16
17
19
20
18
22
21
24
25
26
28
27
30
29
0
31
2
1
4
5
4
11
15
21
18
J30
J30 J30
2/31/3
DQ31_A
CB7_A
CB4_A
CB1_A
CB7_B
ALERT_n
CA0_A
CA0_B
CA1_A
CA1_B
CA2_A
CA2_B
CA3_A
CA3_B
CA4_A
CA4_B
CA5_A
CA5_B
CA6_A
CA6_B
CB6_A
CB5_A
CB3_A
CB2_A
CB0_A
CB6_B
CB5_B
CB4_B
CB3_B
CB2_B
CB1_B
CB0_B
CK_c
CK_t
CS0_A_n
CS0_B_n
CS1_A_n
CS1_B_n
DQ30_A
DQ29_A
DQ28_A
DQ27_A
DQ26_A
DQ25_A
DQ24_A
DQ23_A
DQ22_A
DQ21_A
DQ20_A
DQ19_A
DQ18_A
DQ17_A
DQ16_A
DQ15_A
DQ14_A
DQ13_A
DQ12_A
DQ11_A
DQ10_A
DQ9_A
DQ8_A
DQ7_A
DQ6_A
DQ5_A
DQ4_A
DQ3_A
DQ2_A
DQ1_A
DQ0_A
DQ31_B
DQ30_B
DQ29_B
DQ28_B
DQ27_B
DQ26_B
DQ25_B
DQ24_B
DQ23_B
DQ22_B
DQ21_B
DQ20_B
DQ19_B
DQ18_B
DQ17_B
DQ16_B
DQ15_B
DQ14_B
DQ13_B
DQ12_B
DQ11_B
DQ10_B
DQ9_B
DQ8_B
DQ7_B
DQ6_B
DQ5_B
DQ4_B
DQ3_B
DQ2_B
DQ1_B
DQ0_B
HSA
HSCL
HSDA
LBD||RSP_A_n
LBS||RSP_B_n
PAR_A
PAR_B
PWR_GOOD||FAIL_n
RESET_n
RFU6
RFU5
RFU4
RFU3
RFU2
RFU1
RFU0
VIN_MGMT
3/3
G3
G2
G1
VSS62
VSS61
VSS60
VSS58
VSS104
VSS102
VSS100
VIN_BULK2
VIN_BULK1
VIN_BULK0
VSS126
VSS125
VSS124
VSS123
VSS122
VSS121
VSS120
VSS119
VSS118
VSS117
VSS116
VSS115
VSS114
VSS113
VSS112
VSS111
VSS110
VSS109
VSS108
VSS107
VSS106
VSS105
VSS103
VSS101
VSS99
VSS98
VSS97
VSS96
VSS95
VSS94
VSS93
VSS92
VSS91
VSS90
VSS89
VSS88
VSS87
VSS86
VSS85
VSS84
VSS83
VSS82
VSS81
VSS80
VSS79
VSS78
VSS77
VSS76
VSS75
VSS74
VSS73
VSS72
VSS71
VSS70
VSS69
VSS68
VSS67
VSS66
VSS65
VSS64
VSS63
VSS59
VSS57
VSS56
VSS55
VSS54
VSS53
VSS52
VSS51
VSS50
VSS49
VSS48
VSS47
VSS46
VSS45
VSS44
VSS43
VSS42
VSS41
VSS40
VSS39
VSS38
VSS37
VSS36
VSS35
VSS34
VSS33
VSS32
VSS31
VSS30
VSS29
VSS28
VSS27
VSS26
VSS25
VSS24
VSS23
VSS22
VSS21
VSS20
VSS19
VSS18
VSS17
VSS16
VSS15
VSS14
VSS13
VSS12
VSS11
VSS10
VSS9
VSS8
VSS7
VSS6
VSS5
VSS4
VSS3
VSS2
VSS1
VSS0
21
2
1
2
1
2
1
2
1
CAD NOTE:
SHEETDATE
DEPARTMENT
SIZE
PROJECT DOCUMENT NUMBER REV
REVIEWER
DESIGNER
123
7 3 2 1 6 5 4
E
A
B
C
E
D
C
B
A
7 6 5 4
D
ININ
BI
OUT
IN
IN
OUT
IN
IN
IN
ININ
OUTOUT
OUTOUT
IN
IN
ININ
BI
BI
BI
IN
BI
IN
OUT
C80C79C78
R74
C



20210728 MODIFY FOR GT
Fri Aug 25 14:01:33 2023112 OF 312N/AN/AN/AN/AV05P3V3_AUX
P12V_S3_AUX_CPU1_NVDIMMP3V3_AUXP12V_S3_AUX_CPU1_NVDIMMDDR5 - CPU1 CHH DIMM1(YELLOW)11423010610710810911011111323010610710810911011111311258113130110111113581135811358113581135811358 1135858585858585858581135811358 113112
581135811358113PWRGD_CHH_CPU1_DIMM1TP_CHH_CPU1_DIMM1_FRU_6TP_CHH_CPU1_DIMM1_FRU_5TP_CHH_CPU1_DIMM1_FRU_4TP_CHH_CPU1_DIMM1_FRU_3TP_CHH_CPU1_DIMM1_FRU_2TP_CHH_CPU1_DIMM1_FRU_1I3C_SPD_DDREFGH_CPU1_LVC1_SCLI3C_SPD_DDREFGH_CPU1_LVC1_SCL_R7I3C_SPD_DDREFGH_CPU1_LVC1_SDAPD_CHH_CPU1_DIMM1_SAAM_H_CPU1_ALERT_NRST_M_GH_CPU1_FPGA_NTP_CHH_CPU1_DIMM1_FRU_0M_H_CPU1_SB_CB<7:0>CHIP49.9M_H_CPU1_SA_DQS_DP<9:0>M_H_CPU1_SA_DQS_DN<9:0>M_H_CPU1_SB_DQS_DP<9:0>M_H_CPU1_SB_DQS_DN<9:0>SMLFSCONN288_ADR50017-P130CCIOSCONN288_ADR50017-P130CCSMLFM_H_CPU1_SA_DQ<31:0>IOM_H_CPU1_CLK_DN<0>M_H_CPU1_CLK_DP<0>M_H_CPU1_SA_CS_N<0>M_H_CPU1_SB_CS_N<0>M_H_CPU1_SA_CS_N<1>M_H_CPU1_SB_CS_N<1>M_H_CPU1_SA_RSP<0>M_H_CPU1_SB_RSP<0>M_H_CPU1_SA_PARM_H_CPU1_SB_PARIOSCONN288_ADR50017-P130CCSMLFM_H_CPU1_SB_DQ<31:0>CHIP1/16W1%0402LF127KX6SC080510UF10%16VX6S10UF10%C080516VPD_CHH_CPU1_DIMM1_SAA
M_H_CPU1_SB_CA<6:0>M_H_CPU1_SA_CA<6:0>M_H_CPU1_SA_CB<7:0>
PLACE THE BYPASS CAPS CLOSE TO DIMMC0402X6S2.2UF20%6.3V
DQS7_A_c||TDQS7_A_c
DQS6_A_t||TDQS6_A_t
DQS8_B_t||TDQS8_B_t
DQS8_B_c||TDQS8_B_c
DQS7_B_t||TDQS7_B_t
DQS0_A_c
DQS0_A_t
DQS0_B_c
DQS0_B_t
DQS1_A_c
DQS1_A_t
DQS1_B_c
DQS1_B_t
DQS2_A_c
DQS2_A_t
DQS2_B_c
DQS2_B_t
DQS3_A_c
DQS3_A_t
DQS3_B_c
DQS3_B_t
DQS4_A_c
DQS4_A_t
DQS4_B_c
DQS4_B_t
DQS5_A_c||TDQS5_A_c||DQS5_A_t||TDQS5_A_t
DQS5_A_t||TDQS5_A_t
DQS5_B_c||TDQS5_B_c
DQS5_B_t||TDQS5_B_t
DQS6_A_c||TDQS6_A_c||DQS6_A_t||TDQS6_A_t
DQS6_B_c||TDQS6_B_c
DQS6_B_t||TDQS6_B_t
DQS7_A_t||TDQS7_A_t
DQS7_B_c||TDQS7_B_c
DQS8_A_c||TDQS8_A_c
DQS8_A_t||TDQS8_A_t
DQS9_A_c||TDQS9_A_c
DQS9_A_t||TDQS9_A_t
DQS9_B_c||TDQS9_B_c
DQS9_B_t||TDQS9_B_t||DBI4_B_n
R3905
93
94
201
200
283
282
190
189
272
271
179
178
261
260
168
167
250
249
157
156
239
238
55
56
137
138
44
45
126
127
33
34
115
116
22
23
104
105
11
12
3
232
231
220
150
149
144
2
207
147
227
74
87
86
5
4
148
287
194
285
192
142
49
140
47
280
187
278
185
135
42
133
40
276
183
274
181
131
38
129
36
269
176
267
174
124
31
122
29
265
172
263
170
120
27
118
25
258
165
256
163
113
20
111
18
254
161
252
159
109
16
107
14
247
154
245
152
102
9
100
7
229
209
84
64
217
218
236
205
234
203
91
60
89
58
243
198
241
196
98
53
96
51
82
72
225
215
80
70
223
213
78
68
221
211
76
66
62
288
286
284
281
279
277
275
273
270
268
266
264
262
259
257
255
253
251
248
246
244
242
240
237
235
233
230
228
226
224
222
219
216
214
212
210
208
206
204
202
199
197
195
193
191
188
186
184
182
180
177
175
173
171
169
166
164
162
160
158
155
153
151
143
141
139
136
134
132
130
128
125
123
121
119
117
114
112
110
108
106
103
101
99
97
95
92
90
88
85
83
81
79
77
75
73
71
69
67
65
63
61
59
57
54
52
50
48
46
43
41
39
37
35
32
30
28
26
24
21
19
17
15
13
10
8
6
146
145
1
G3
G2
G1
9
8
7
6
5
4
3
2
1
0
9
8
7
6
4
5
3
2
1
0
9
8
7
6
5
4
3
2
1
0
9
8
7
6
5
4
3
2
1
0
6
4
28
6
11
10
8
9
6
7
5
3
4
1
31
0
2
30
29
26
27
25
24
23
21
22
20
18
19
17
16
15
14
13
12
11
10
9
8
7
5
6
4
3
1
0
2
6
5
4
3
1
2
0
5
3
2
0
1
7
6
5
4
3
2
1
0
7
5
4
3
2
1
0
30
29
31
28
26
27
25
24
23
22
21
20
19
18
17
16
15
13
14
12
J31J31 J31
2/31/3
DQ31_A
CB7_A
CB4_A
CB1_A
CB7_B
ALERT_n
CA0_A
CA0_B
CA1_A
CA1_B
CA2_A
CA2_B
CA3_A
CA3_B
CA4_A
CA4_B
CA5_A
CA5_B
CA6_A
CA6_B
CB6_A
CB5_A
CB3_A
CB2_A
CB0_A
CB6_B
CB5_B
CB4_B
CB3_B
CB2_B
CB1_B
CB0_B
CK_c
CK_t
CS0_A_n
CS0_B_n
CS1_A_n
CS1_B_n
DQ30_A
DQ29_A
DQ28_A
DQ27_A
DQ26_A
DQ25_A
DQ24_A
DQ23_A
DQ22_A
DQ21_A
DQ20_A
DQ19_A
DQ18_A
DQ17_A
DQ16_A
DQ15_A
DQ14_A
DQ13_A
DQ12_A
DQ11_A
DQ10_A
DQ9_A
DQ8_A
DQ7_A
DQ6_A
DQ5_A
DQ4_A
DQ3_A
DQ2_A
DQ1_A
DQ0_A
DQ31_B
DQ30_B
DQ29_B
DQ28_B
DQ27_B
DQ26_B
DQ25_B
DQ24_B
DQ23_B
DQ22_B
DQ21_B
DQ20_B
DQ19_B
DQ18_B
DQ17_B
DQ16_B
DQ15_B
DQ14_B
DQ13_B
DQ12_B
DQ11_B
DQ10_B
DQ9_B
DQ8_B
DQ7_B
DQ6_B
DQ5_B
DQ4_B
DQ3_B
DQ2_B
DQ1_B
DQ0_B
HSA
HSCL
HSDA
LBD||RSP_A_n
LBS||RSP_B_n
PAR_A
PAR_B
PWR_GOOD||FAIL_n
RESET_n
RFU6
RFU5
RFU4
RFU3
RFU2
RFU1
RFU0
VIN_MGMT
3/3
G3
G2
G1
VSS62
VSS61
VSS60
VSS58
VSS104
VSS102
VSS100
VIN_BULK2
VIN_BULK1
VIN_BULK0
VSS126
VSS125
VSS124
VSS123
VSS122
VSS121
VSS120
VSS119
VSS118
VSS117
VSS116
VSS115
VSS114
VSS113
VSS112
VSS111
VSS110
VSS109
VSS108
VSS107
VSS106
VSS105
VSS103
VSS101
VSS99
VSS98
VSS97
VSS96
VSS95
VSS94
VSS93
VSS92
VSS91
VSS90
VSS89
VSS88
VSS87
VSS86
VSS85
VSS84
VSS83
VSS82
VSS81
VSS80
VSS79
VSS78
VSS77
VSS76
VSS75
VSS74
VSS73
VSS72
VSS71
VSS70
VSS69
VSS68
VSS67
VSS66
VSS65
VSS64
VSS63
VSS59
VSS57
VSS56
VSS55
VSS54
VSS53
VSS52
VSS51
VSS50
VSS49
VSS48
VSS47
VSS46
VSS45
VSS44
VSS43
VSS42
VSS41
VSS40
VSS39
VSS38
VSS37
VSS36
VSS35
VSS34
VSS33
VSS32
VSS31
VSS30
VSS29
VSS28
VSS27
VSS26
VSS25
VSS24
VSS23
VSS22
VSS21
VSS20
VSS19
VSS18
VSS17
VSS16
VSS15
VSS14
VSS13
VSS12
VSS11
VSS10
VSS9
VSS8
VSS7
VSS6
VSS5
VSS4
VSS3
VSS2
VSS1
VSS0
21
2
1
2
1
2
1
2
1
CAD NOTE:
SHEETDATE
DEPARTMENT
SIZE
PROJECT DOCUMENT NUMBER REV
REVIEWER
DESIGNER
123
7 3 2 1 6 5 4
E
A
B
C
E
D
C
B
A
7 6 5 4
D
ININ
BI
OUTOUT
IN
IN
ININ
ININ
ININ
ININ
BI
BI
IN
OUTOUT
OUTOUT
BI
IN
BI
IN
OUT
C77C76C75
R73
C



20210728 MODIFY FOR GT
Fri Aug 25 14:01:34 2023N/AN/AN/AN/AV05113 OF 312
P12V_S3_AUX_CPU1_NVDIMM
P12V_S3_AUX_CPU1_NVDIMMP3V3_AUXP3V3_AUX
DDR5 - CPU1 CHH DIMM2(BLACK)1142301061071081091101111121135811213011011111223010610710810911011111258 11258112581125811258 11258112
113
58112581125858585858585858 58112581125811258112
PLACE THE BYPASS CAPS CLOSE TO DIMMC0805X6STP_CHH_CPU1_DIMM2_FRU_5PWRGD_CHH_CPU1_DIMM2I3C_SPD_DDREFGH_CPU1_LVC1_SDAI3C_SPD_DDREFGH_CPU1_LVC1_SCL_R8PD_CHH_CPU1_DIMM2_SAAM_H_CPU1_ALERT_NRST_M_GH_CPU1_FPGA_NI3C_SPD_DDREFGH_CPU1_LVC1_SCLCHIP49.9M_H_CPU1_SB_DQ<31:0>M_H_CPU1_SA_CB<7:0>M_H_CPU1_SB_CB<7:0>TP_CHH_CPU1_DIMM2_FRU_6TP_CHH_CPU1_DIMM2_FRU_4TP_CHH_CPU1_DIMM2_FRU_3TP_CHH_CPU1_DIMM2_FRU_2TP_CHH_CPU1_DIMM2_FRU_1M_H_CPU1_SB_CA<6:0>SMLFSCONN288_ADR50017-P087CC SCONN288_ADR50017-P087CCSMLFM_H_CPU1_SA_DQ<31:0>
6.3V20%X6SC04022.2UF
M_H_CPU1_SA_CA<6:0>
PD_CHH_CPU1_DIMM2_SAA10%16V10UFC0805X6S10UF16V10%196K1%1/16W0402LFCHIP
SMLFIOSCONN288_ADR50017-P087CCIO
TP_CHH_CPU1_DIMM2_FRU_0M_H_CPU1_SB_PARM_H_CPU1_SA_PARM_H_CPU1_SB_RSP<1>M_H_CPU1_SA_RSP<1>M_H_CPU1_SA_CS_N<3>M_H_CPU1_SB_CS_N<2>M_H_CPU1_CLK_DP<1>M_H_CPU1_CLK_DN<1>IOM_H_CPU1_SB_CS_N<3>M_H_CPU1_SA_CS_N<2>M_H_CPU1_SB_DQS_DP<9:0>M_H_CPU1_SB_DQS_DN<9:0>M_H_CPU1_SA_DQS_DN<9:0>M_H_CPU1_SA_DQS_DP<9:0>
DQS7_A_c||TDQS7_A_c
DQS6_A_t||TDQS6_A_t
DQS8_B_t||TDQS8_B_t
DQS8_B_c||TDQS8_B_c
DQS7_B_t||TDQS7_B_t
DQS0_A_c
DQS0_A_t
DQS0_B_c
DQS0_B_t
DQS1_A_c
DQS1_A_t
DQS1_B_c
DQS1_B_t
DQS2_A_c
DQS2_A_t
DQS2_B_c
DQS2_B_t
DQS3_A_c
DQS3_A_t
DQS3_B_c
DQS3_B_t
DQS4_A_c
DQS4_A_t
DQS4_B_c
DQS4_B_t
DQS5_A_c||TDQS5_A_c||DQS5_A_t||TDQS5_A_t
DQS5_A_t||TDQS5_A_t
DQS5_B_c||TDQS5_B_c
DQS5_B_t||TDQS5_B_t
DQS6_A_c||TDQS6_A_c||DQS6_A_t||TDQS6_A_t
DQS6_B_c||TDQS6_B_c
DQS6_B_t||TDQS6_B_t
DQS7_A_t||TDQS7_A_t
DQS7_B_c||TDQS7_B_c
DQS8_A_c||TDQS8_A_c
DQS8_A_t||TDQS8_A_t
DQS9_A_c||TDQS9_A_c
DQS9_A_t||TDQS9_A_t
DQS9_B_c||TDQS9_B_c
DQS9_B_t||TDQS9_B_t||DBI4_B_n
R3906
93
94
201
200
283
282
190
189
272
271
179
178
261
260
168
167
250
249
157
156
239
238
55
56
137
138
44
45
126
127
33
34
115
116
22
23
104
105
11
12
3
232
231
220
150
149
144
2
207
147
227
74
87
86
5
4
148
287
194
285
192
142
49
140
47
280
187
278
185
135
42
133
40
276
183
274
181
131
38
129
36
269
176
267
174
124
31
122
29
265
172
263
170
120
27
118
25
258
165
256
163
113
20
111
18
254
161
252
159
109
16
107
14
247
154
245
152
102
9
100
7
229
209
84
64
217
218
236
205
234
203
91
60
89
58
243
198
241
196
98
53
96
51
82
72
225
215
80
70
223
213
78
68
221
211
76
66
62
288
286
284
281
279
277
275
273
270
268
266
264
262
259
257
255
253
251
248
246
244
242
240
237
235
233
230
228
226
224
222
219
216
214
212
210
208
206
204
202
199
197
195
193
191
188
186
184
182
180
177
175
173
171
169
166
164
162
160
158
155
153
151
143
141
139
136
134
132
130
128
125
123
121
119
117
114
112
110
108
106
103
101
99
97
95
92
90
88
85
83
81
79
77
75
73
71
69
67
65
63
61
59
57
54
52
50
48
46
43
41
39
37
35
32
30
28
26
24
21
19
17
15
13
10
8
6
146
145
1
G3
G2
G1
29
1
31
5
27
23
24
22
20
28
29
26
25
6
5 30
31
0
4
1
2
6
2
1
0
7
4
3
5
0
1
2
4
3
6
5
3
2
1
0
0
1
2
3
6
4
5
8
10
11
9
7
13
15
16
14
12
19
20
21
18
17
4
25
26
24
23
22
30
27
28
0
3
1
6
8
4
10
9
11
12
14
13
18
17
19
16
15
21
6
5
7
2
7
3
0
1
2
3
4
5
6
7
8
9
0
1
2
3
4
5
6
7
8
9
1
0
2
3
5
6
7
8
9
0
2
3
4
5
7
6
8
9
4
J32
J32 J32
2/31/3
DQ31_A
CB7_A
CB4_A
CB1_A
CB7_B
ALERT_n
CA0_A
CA0_B
CA1_A
CA1_B
CA2_A
CA2_B
CA3_A
CA3_B
CA4_A
CA4_B
CA5_A
CA5_B
CA6_A
CA6_B
CB6_A
CB5_A
CB3_A
CB2_A
CB0_A
CB6_B
CB5_B
CB4_B
CB3_B
CB2_B
CB1_B
CB0_B
CK_c
CK_t
CS0_A_n
CS0_B_n
CS1_A_n
CS1_B_n
DQ30_A
DQ29_A
DQ28_A
DQ27_A
DQ26_A
DQ25_A
DQ24_A
DQ23_A
DQ22_A
DQ21_A
DQ20_A
DQ19_A
DQ18_A
DQ17_A
DQ16_A
DQ15_A
DQ14_A
DQ13_A
DQ12_A
DQ11_A
DQ10_A
DQ9_A
DQ8_A
DQ7_A
DQ6_A
DQ5_A
DQ4_A
DQ3_A
DQ2_A
DQ1_A
DQ0_A
DQ31_B
DQ30_B
DQ29_B
DQ28_B
DQ27_B
DQ26_B
DQ25_B
DQ24_B
DQ23_B
DQ22_B
DQ21_B
DQ20_B
DQ19_B
DQ18_B
DQ17_B
DQ16_B
DQ15_B
DQ14_B
DQ13_B
DQ12_B
DQ11_B
DQ10_B
DQ9_B
DQ8_B
DQ7_B
DQ6_B
DQ5_B
DQ4_B
DQ3_B
DQ2_B
DQ1_B
DQ0_B
HSA
HSCL
HSDA
LBD||RSP_A_n
LBS||RSP_B_n
PAR_A
PAR_B
PWR_GOOD||FAIL_n
RESET_n
RFU6
RFU5
RFU4
RFU3
RFU2
RFU1
RFU0
VIN_MGMT
3/3
G3
G2
G1
VSS62
VSS61
VSS60
VSS58
VSS104
VSS102
VSS100
VIN_BULK2
VIN_BULK1
VIN_BULK0
VSS126
VSS125
VSS124
VSS123
VSS122
VSS121
VSS120
VSS119
VSS118
VSS117
VSS116
VSS115
VSS114
VSS113
VSS112
VSS111
VSS110
VSS109
VSS108
VSS107
VSS106
VSS105
VSS103
VSS101
VSS99
VSS98
VSS97
VSS96
VSS95
VSS94
VSS93
VSS92
VSS91
VSS90
VSS89
VSS88
VSS87
VSS86
VSS85
VSS84
VSS83
VSS82
VSS81
VSS80
VSS79
VSS78
VSS77
VSS76
VSS75
VSS74
VSS73
VSS72
VSS71
VSS70
VSS69
VSS68
VSS67
VSS66
VSS65
VSS64
VSS63
VSS59
VSS57
VSS56
VSS55
VSS54
VSS53
VSS52
VSS51
VSS50
VSS49
VSS48
VSS47
VSS46
VSS45
VSS44
VSS43
VSS42
VSS41
VSS40
VSS39
VSS38
VSS37
VSS36
VSS35
VSS34
VSS33
VSS32
VSS31
VSS30
VSS29
VSS28
VSS27
VSS26
VSS25
VSS24
VSS23
VSS22
VSS21
VSS20
VSS19
VSS18
VSS17
VSS16
VSS15
VSS14
VSS13
VSS12
VSS11
VSS10
VSS9
VSS8
VSS7
VSS6
VSS5
VSS4
VSS3
VSS2
VSS1
VSS0
21
2
1
2
1
2
1
2
1
CAD NOTE:
SHEETDATE
DEPARTMENT
SIZE
PROJECT DOCUMENT NUMBER REV
REVIEWER
DESIGNER
123
7 3 2 1 6 5 4
E
A
B
C
E
D
C
B
A
7 6 5 4
D
OUT
IN
IN
ININ
BI
IN
IN
IN
IN
IN
ININ
BI
IN
OUTOUTBI
OUTOUTININ
BI
BI
OUT
IN
OUT
C74C73C72
R72
C



CPU0 DDR CPU1 DDR20211206 MODIFY FOR GT
Fri Aug 25 14:01:35 2023114 OF 312V05N/AN/AN/AN/ADDR5 - PWRGD
909192931151151158987 1151061041051158485 10110011511598991071081091101111121131158382889786959496103102PWRGD_CHE_CPU0_DIMM1PWRGD_CHE_CPU0_DIMM2PWRGD_CHF_CPU0_DIMM1PWRGD_CHF_CPU0_DIMM20402LF 1/16WPWRGD_FAIL_CPU0_GH1%PWRGD_FAIL_CPU0_EFPWRGD_FAIL_CPU0_CD1%33.2PWRGD_CHD_CPU0_DIMM2PWRGD_CHC_CPU0_DIMM21%PWRGD_FAIL_CPU1_GH1/16W1%1%33.2CHIPPWRGD_CHE_CPU1_DIMM1PWRGD_CHD_CPU1_DIMM1PWRGD_CHD_CPU1_DIMM2CHIP33.21%PWRGD_FAIL_CPU1_EF1%1%PWRGD_CHB_CPU0_DIMM1PWRGD_CHB_CPU0_DIMM20402LF 1/16W1/16W1%33.21%PWRGD_CHB_CPU1_DIMM2PWRGD_CHB_CPU1_DIMM1PWRGD_FAIL_CPU1_AB1/16W1%PWRGD_FAIL_CPU1_CDCHIP 0402LFCHIP 0402LF0402LF0402LFCHIP 0402LFCHIP 0402LFCHIP0402LFCHIPCHIPCHIP1/16W0402LFCHIP0402LFCHIPCHIP0402LFCHIPPWRGD_CHA_CPU1_DIMM1PWRGD_CHA_CPU1_DIMM2PWRGD_CHE_CPU1_DIMM2PWRGD_CHF_CPU1_DIMM1PWRGD_CHF_CPU1_DIMM2PWRGD_CHG_CPU1_DIMM1PWRGD_CHG_CPU1_DIMM2PWRGD_CHH_CPU1_DIMM1PWRGD_CHH_CPU1_DIMM2PWRGD_FAIL_CPU0_ABPWRGD_CHA_CPU0_DIMM2PWRGD_CHA_CPU0_DIMM1PWRGD_CHD_CPU0_DIMM1PWRGD_CHH_CPU0_DIMM2PWRGD_CHC_CPU0_DIMM1PWRGD_CHG_CPU0_DIMM2PWRGD_CHG_CPU0_DIMM1PWRGD_CHH_CPU0_DIMM10402LF 1/16W0402LF1%33.21%1%1%33.233.233.233.21/16W33.21%33.233.21/16W33.233.233.233.233.21%1%33.21%1%1/16W33.233.21%1%1/16W33.21%1%1%33.233.233.21/16W1/16W33.21%1%33.233.21%1%1/16W0402LFCHIP33.21/16W1%33.233.21%0402LFCHIP1%33.21/16W33.2PWRGD_CHC_CPU1_DIMM2PWRGD_CHC_CPU1_DIMM1
R2726
R2728
R2731
R2732
R2729
R2733
R2734
R2735
R2736
R893
R894
R895
R898
R899
R2727
R2730
R896
R897
R900
R901
R903
R905
R907
R908
R880
R884
R885
R886
R889
R890
R902
R906
21 21
21
21
21
21 21
21
21
21
21
21
21
21
21
21
21
21 21
21
21
21
21 21
21
21 21
21 21
21
21
21
SHEETDATE
DEPARTMENT
SIZE
PROJECT DOCUMENT NUMBER REV
REVIEWER
DESIGNER
123
7 3 2 1 6 5 4
E
A
B
C
E
D
C
B
A
7 6 5 4
D
IN
OUT
IN
OUT
OUT
OUT
IN
IN
ININOUT
ININ
IN
IN
IN
IN
ININ
IN
IN
ININ
IN
IN
IN
IN
OUT
OUT
OUTIN
IN
ININ
ININ
ININ
IN
IN
C



20211206 MODIFY FOR GT
Fri Aug 25 14:01:36 2023N/AN/AN/AN/AV05115 OF 312P3V3_AUXP3V3_AUXP3V3_AUXP3V3_AUXP3V3_AUXP3V3_AUXP3V3_AUXP3V3_AUXP3V3_AUXP3V3_AUX
P3V3_AUXP3V3_AUXP3V3_AUXP3V3_AUXP3V3_AUXP3V3_AUX
DDR5 - PWRGD
214214214214
21421421421411411411411411411411411410KCHIP0402LF
B0530WS7F1/16WPWRGD_FAIL_CPU1_EF_R1B0530WS7FPWRGD_FAIL_CPU0_GH_RPWRGD_FAIL_CPU0_EF_RPWRGD_FAIL_CPU0_CD_RPWRGD_FAIL_CPU0_AB_R1%33.2ICICICICICICICIC
SMLFB0530WS7F1%B0530WS7FSMLFB0530WS7F1%B0530WS7FSMLFB0530WS7F33.233.2SMLFSMLFPWRGD_FAIL_CPU1_AB_R1
B0530WS7FSMLFSMLFSMLF33.2PWRGD_FAIL_CPU1_GH_R1%PWRGD_FAIL_CPU1_EF_R1%PWRGD_FAIL_CPU1_CD_R1%PWRGD_FAIL_CPU1_AB_R1%33.233.21%33.233.2PWRGD_FAIL_CPU0_EF_R1PWRGD_FAIL_CPU0_CD_R1PWRGD_FAIL_CPU0_AB_R1
PWRGD_FAIL_CPU1_GH_R10402LFCHIP1%10K1/16W1%1K0402LFCHIP1/16W0402LFCHIP1%10K1/16WCHIP1%1/16W1K0402LF1/16W10K1/16W1KCHIP1%10K0402LFCHIP1%CHIP0402LF1K1%CHIP0402LF1/16W1%0402LFCHIP1%1KCHIP1%10K0402LF1/16WPWRGD_FAIL_CPU0_EF1/16W0402LFCHIP1K1/16W1%1%0402LF1/16W0402LFCHIP1/16W0402LF1%10KCHIP1/16W0402LF1%1K0402LF1/16W CHIP1%10K1%1KCHIP1/16W
PWRGD_FAIL_CPU1_CDPWRGD_FAIL_CPU1_GHPWRGD_FAIL_CPU1_EFPWRGD_FAIL_CPU1_ABPWRGD_FAIL_CPU0_GHPWRGD_FAIL_CPU0_CDPWRGD_FAIL_CPU0_AB
PWRGD_FAIL_CPU1_CD_R1PWRGD_FAIL_CPU0_GH_R1
D44
D45
D46
D42
D43
D47
D48
D49
21
21
21
21
21
21
21
21
CA
CA
CA
CA
CA
CA
CA
CA
21
21
21
21
21
21
21
21
21R2492
21R942
21R943
21R2494
21R940
21
21R2491
21R2493
21R944
21R2495
21R945
21R946
21R2496
21R947
21R2497
21R2490 R2498
R2499
R2500
R2501
R2502
R2503
R2504
R2505
SHEETDATE
DEPARTMENT
SIZE
PROJECT DOCUMENT NUMBER REV
REVIEWER
DESIGNER
123
7 3 2 1 6 5 4
E
A
B
C
E
D
C
B
A
7 6 5 4
D
IN
IN
OUT
OUT
OUT
OUT
IN
IN
IN OUT
OUT
OUT
OUT
IN
IN
IN
R941
C



THIS PAGE WAS INTENTIONALLY LEFT BLANK
116 OF 312V05N/AN/AN/AN/AThu Aug 24 16:13:36 2023BLANK
SHEETDATE
DEPARTMENT
SIZE
PROJECT DOCUMENT NUMBER REV
REVIEWER
DESIGNER
123
7 3 2 1 6 5 4
E
A
B
C
E
D
C
B
A
7 6 5 4
D
C



Fri Aug 25 14:01:37 2023N/A117 OF 312V05N/AN/AN/A
PVNN_TERM_CPU0 PVNN_TERM_CPU1
SPR CPU0 & 1 - SVID/MISC/UART
16471445H_CPU_PM_FAST_WAKE_NH_PMAX_TRIGGER_IO_CPU0H_PMAX_TRIGGER_IO_CPU1CHIP 1/16W05%0402LFH_CPU0_PM_FAST_WAKE_N0402LF5%01/16WCHIPH_CPU1_PM_FAST_WAKE_N3011/16W1%0402LFCHIP1%0402LF1/16WCHIP3011%1/16W2490402LFCHIP0402LF249CHIP1%1/16W
R3023R1240
2
1
2
1
2
1
2
1
2121
SHEETDATE
DEPARTMENT
SIZE
PROJECT DOCUMENT NUMBER REV
REVIEWER
DESIGNER
123
7 3 2 1 6 5 4
E
A
B
C
E
D
C
B
A
7 6 5 4
D
OUT
OUT
BIBI
R1243R1241
R1244R1242
C



20211129 R302,R304 CHANGE TO 0 OHM118 OF 312V05N/AN/AN/AN/AFri Aug 25 14:01:38 2023
PVNN_TERM_CPU1PVNN_TERM_CPU0PVNN_TERM_CPU1PVNN_TERM_CPU0
SPR CPU0 & 1 - CATERR/RMCA18214471622245226226PWRGD_CPUPWRGD_GTLH_CPU0_CATERR_LVC1_R_N1/16W5%33.21%H_CPU1_RMCA_LVC1_R_NH_CPU0_RMCA_LVC1_R_N1%0402LF3010402LF5%1/16W1/16W1/16W30100402LF1/16WCHIPCHIP0402LF 1/16W0402LF5%0CHIPPWRGD_CPUPWRGD_LVC1_RCHIPCHIP1%0402LF1/16W1%CHIP301CHIP3010402LF1%1/16WH_CPU1_CATERR_LVC1_R_NCHIP00402LF0402LF1/16W05%CHIPH_CPU_RMCA_LVC1_R_NH_CPU_CATERR_LVC1_R_N
R304
R302
R315
R303
R301
R298
R296
R299
R297
21
21
21
21
21
21
21
21
21
SHEETDATE
DEPARTMENT
SIZE
PROJECT DOCUMENT NUMBER REV
REVIEWER
DESIGNER
123
7 3 2 1 6 5 4
E
A
B
C
E
D
C
B
A
7 6 5 4
D
OUT
IN
IN
IN
IN
OUT
IN
OUT
C



(DEFAULT) (DEFAULT)CPU1PUINTERNAL20220725 DEPOP R292SPR PIN NAMEPDPDPUPDPDPDPUPDCPU1 HW STRAPS2-3 ENABLE (DEFAULT)1-2 DISABLE20220725 DEPOP R28801CPU02-3 ENABLE BIST (DEFAULT)PU/PDDESCRIPTION
20211201 CHANGE TXT,BIST TO ENABLEDMIMODE_OVERRIDE
1-2 DISABLE BISTSAFE MODE BOOT (DISABLES CLOCK GATING)1: SAFE MODE BOOT ENABLEDTXT AGENT (DRIVES TXT TRANSACTIONS)0: CPU IS NOT A TXT AGENTNON-LEGACY CPUS = 01 OR 10 OR 11SERVICE PROCESSOR BOOT MODE0: NON-LEGACY. DMI3 IS NOT INITIALIZED1: F/W IS LOCAL TO THIS SOCKET'S PCH2-3 ENABLE BIST (DEFAULT)000BUILT IN SELF TEST1: BIST ENABLED0: BIST DISABLED0: SAFE MODE BOOT DISABLED1: CPU IS TXT AGENTTXT ENABLE1: TXT ENABLEDCPU DMI PORT MODE1: DMI MODE0: PCIE MODESOCKET IDENTIFIERLEGACY CPU = 000: NORMAL BOOT FLOW1: F/W IS LOCAL TO THIS SOCKET'S PCHBOOT MODE OPERATION0: NON-LEGACY. DMI3 IS NOT INITIALIZED11DMI MODE1-2 DISABLE BISTFRMAGENTSOCKET_ID[2:0]110: TXT DISABLED1: CPU HAULTS UNTIL BMC RELEASES BOOT1CPU0 STRAPPING
BMCINITTXT_PLTEN011FLOW00TXT_AGENTBIST_ENABLECPU0 HW STRAPSSAFE_MODE_BOOT0000100
1-2 DISABLE
LEGACY_SKT
2-3 ENABLE (DEFAULT)CPU1 STRAPPING20211201 CHANGE TXT,BIST TO ENABLE
20220729 DEPOP R4262
20220729 DEPOP R4262
N/AN/AV05119 OF 312N/AN/AFri Aug 25 14:01:39 2023PVNN_TERM_CPU0
PVNN_TERM_CPU0PVNN_TERM_CPU0PVNN_TERM_CPU0PVNN_TERM_CPU1PVNN_TERM_CPU1
P3V3_AUXP3V3_AUXPVNN_TERM_CPU0PVNN_TERM_CPU0SPR CPU0 & 1- HW STRAPS
13
44
13
44
13131313214132141321413214442144421444214442144421445444444444544131313131191311913119131313
44119 44119 4444119 44
1413119134444132141444119 44
PD_CPU0_BIST_ENABLE
PD_CPU1_BIST_ENABLEEMPTY2401%1/16W0402LF
EMPTY1/16W0402LF2401%SW3 BIT2: CPU0 BUILT IN SELF TESTEMPTY1/16WEMPTYEMPTYPD_CPU0_TXT_PLTEN
SW4 BIT1: CPU1 TXT_PLT ENABLEPD_CPU1_TXT_PLTEN
1%2401/16W0402LF
2401/16WEMPTY1%0402LFSW4 BIT2: CPU1 BUILT IN SELF TEST
0402LF1/16W
1/16W2401%EMPTY0402LFEMPTY1%2401/16W0402LF
0402LF2401%1%0402LF240EMPTYPU_CPU0_FRMAGENTH_CPU0_BMCINIT_LVC1PU_CPU0_TXT_AGENTJP12: CPU0 TXT_PLT ENABLE150 OHM FOR 4S/8S PLATFORM240 OHM FOR 2S
150 OHM FOR 4S/8S PLATFORM240 OHM FOR 2S1%0402LF10KCHIP1/16WFM_CPU0_PKGID010K1%CHIPFM_CPU0_PKGID1CHIP1%10KFM_CPU0_PKGID2CHIP10K1%FM_CPU0_PROC_ID010K1%CHIPCHIP1%10KFM_CPU1_PKGID210K1%CHIPFM_CPU1_PKGID110K1/16W1%0402LFCHIPFM_CPU1_PKGID010K1%CHIPFM_CPU1_PROC_ID110K1%CHIPFM_CPU1_PROC_ID0
1K 1%EMPTY0402LF
0402LF1K1/16W1%EMPTYPU_TAP_ODT_CPU1_EN1%EMPTY2401%240 CHIPPU_CPU1_SOCKET_ID0240EMPTY1%H_CPU1_BMCINIT_LVC1EMPTY1%240PU_CPU1_SAFE_MODE_BOOT1%EMPTY1/16W0402LFPU_CPU1_TXT_AGENTEMPTY1%PD_CPU1_ENH_MCECC_DIS1%EMPTY240PU_CPU1_FRMAGENTCHIP1%240EMPTY1%PU_CPU0_SOCKET_ID12401%EMPTYPU_CPU0_SOCKET_ID21%240EMPTY2401%CHIP2401%PU_CPU0_SAFE_MODE_BOOTCHIP1%1/16W2401%EMPTYPD_CPU0_DMIMODE_OVERRIDEEMPTY1%2401%EMPTY240PUD_XTAL_CPU0_MODE02401%EMPTYPUD_XTAL_CPU0_MODE11%EMPTY2401%240EMPTY1%240EMPTYPUD_XTAL_CPU0_MODE1240 CHIP1%PU_CPU0_LEGACY_SKT1%240EMPTYPU_CPU0_SOCKET_ID0
1%240EMPTYPU_CPU1_LEGACY_SKTEMPTY1%240240EMPTY1%PUD_XTAL_CPU1_MODE0240EMPTY1%PUD_XTAL_CPU1_MODE12401%PD_EXT_CLK_SEL_CPU11%EMPTY240EMPTY2401%PUD_XTAL_CPU1_MODE1
PD_CPU0_ENH_MCECC_DISPD_EXT_CLK_SEL_CPU0PUD_XTAL_CPU0_MODE0240PU_CPU1_SOCKET_ID1PU_CPU1_SOCKET_ID2FM_CPU0_PROC_ID1PU_TAP_ODT_CPU0_EN1/16W240PD_CPU1_DMIMODE_OVERRIDEPUD_XTAL_CPU1_MODE0EMPTY240240
R289
R288
R4261
R4260
R4263
R4262
R293
R292
2
1
2
1
2
1
2
1
2
1
2
1
2
1
2
1
21R1236
21R1235
21R3024
21R1230
21R1229
21R1239
21R1238
21R1237
21R1233
21R1232
21R287
21R286
21R285
21R284
21R283
21R1008
21
21R29021R263
21R291
21R261
21R262
21R264
21R265
21R266
21R267
21R268
21R270
21R271
21R272
21R273
21R274
21R295
21R294
21R275
21R276
21R277
21R278
21R281
21R280
21R279
21R282
DESIGN NOTE:
DESIGN NOTE:
DESIGN NOTE:
DESIGN NOTE:
R1009
SHEETDATE
DEPARTMENT
SIZE
PROJECT DOCUMENT NUMBER REV
REVIEWER
DESIGNER
123
7 3 2 1 6 5 4
E
A
B
C
E
D
C
B
A
7 6 5 4
D
OUT
OUT
OUT
OUT
OUT
OUT
OUT
OUT
OUT
OUT
OUT OUT
OUT OUT
OUT
OUT
OUT
OUT
OUT
OUT
OUT
OUT
OUT
OUT
OUT
IN
IN
IN
IN
IN
OUT
IN
OUT
OUT
OUT
OUT
OUT
OUT
OUT
OUT
OUT
OUT
IN
IN
IN
IN
C



CPU0 S3M STRAPSPU: SPR HCC0: BIST DISABLEDPU/PDPUBOOT MODE1: BIST ENABLEDPD1: CPU BOOT MODEGPIO2/3INTERNALSPR GPIOGPIO0/1PD: SPR XCCDESCRIPTIONCPU1 S3M STRAPSGPIO4PD0: PCH BOOT MODE20221028 POP R259,R26020221028 POP R253,R25420211126 DEPOP R253,R25420211126 POP R1391,R139220221028 DEPOP R1391,R139220211126 POP R1393,R139420221028 DEPOP R1393,R139420211126 DEPOP R259,R260Fri Aug 25 14:01:40 2023N/AN/AN/AN/AV05120 OF 312
PVNN_TERM_CPU0PVNN_TERM_CPU1
SPR CPU0 & 1 SIDE BAND-GPIO
1%0402LF15CHIP2401%CHIP1%24015FM_S3M_CPU0_LVC1_GPIO_3120EMPTY240EMPTY1/16W2401%
FM_S3M_CPU1_LVC1_GPIO_3FM_S3M_CPU1_LVC1_GPIO_2PUD_PCH_BOOT_MODE_CPU1FM_S3M_CPU1_LVC1_GPIO_4CHIPCHIP1%240EMPTY1%EMPTY2401/16W1%0402LFFM_S3M_CPU1_LVC1_GPIO_246120461201512015120151512046120464646461515FM_S3M_CPU1_LVC1_GPIO_3PUD_PCH_BOOT_MODE_CPU0FM_S3M_CPU0_LVC1_GPIO_3FM_S3M_CPU0_LVC1_GPIO_2FM_S3M_CPU0_LVC1_GPIO_4FM_S3M_CPU0_LVC1_GPIO_2CHIP1%240FM_S3M_CPU1_LVC1_GPIO_0EMPTY1/16W0402LFEMPTYCHIP1%2401%2401%2401/16W0402LFEMPTYFM_S3M_CPU0_LVC1_GPIO_02401%EMPTY1%240FM_S3M_CPU0_LVC1_GPIO_11%240EMPTY120461%2402401%EMPTY240FM_S3M_CPU1_LVC1_GPIO_1
R1394
R1393
R1392
R1391
21
21
21
21
21
21R260
21R259
21R258
21R257
21
21R254
21R253
21R252
21
21R251
21
R256
R255
R250
R249
SHEETDATE
DEPARTMENT
SIZE
PROJECT DOCUMENT NUMBER REV
REVIEWER
DESIGNER
123
7 3 2 1 6 5 4
E
A
B
C
E
D
C
B
A
7 6 5 4
D
OUT
OUT
OUT
OUT
OUT
OUT
OUT
OUT
OUT
OUT
OUT
OUT
OUT
OUT
OUT
OUT
C



CPLDCPLDCPU0CPU120221208 CHANGE Q138,Q139 TO BA00847002620211206 MODIFY FOR GT
20210907 MODIFY FOR GTCPU0CPU1CPLDCPLDFri Aug 25 14:01:41 2023121 OF 312V05N/AN/AN/AN/A
PVNN_TERM_CPU1PVNN_TERM_CPU1PVNN_TERM_CPU0PVNN_TERM_CPU0
PVNN_TERM_CPU1PVNN_TERM_CPU0P3V3P3V3
SPR CPU0 & 1- PROCHOT/THERMTRIP
H_CPU1_THERMTRIP_LVC1_R_NH_CPU0_PROCHOT_LVC1_R_NH_CPU1_PROCHOT_LVC1_R_NH_CPU1_THERMTRIP_VT_R_NH_CPU1_THERMTRIP_NH_CPU0_THERMTRIP_LVC1_R_NH_CPU0_THERMTRIP_VT_R_NH_CPU0_THERMTRIP_NH_CPU1_THERMTRIP_R_NH_CPU1_THERMTRIP_VT_NH_CPU1_PROCHOT_LVC1_NH_CPU0_PROCHOT_LVC1_NH_CPU1_THERMTRIP_LVC1_NH_CPU0_THERMTRIP_R_NH_CPU0_THERMTRIP_VT_N H_CPU0_THERMTRIP_LVC1_N
216216450402LF1/16WCHIP1%1001/16W00402LFCHIP5%1/16W CHIP1%1.5K0402LF05%0402LF1/16WCHIPSMLFICBC847BPN0402LFCHIP1.5K140402LFCHIP1%1001/16W0402LFCHIP1%1/16W1.5K1.5K0402LFCHIPSMLFICBC847BPN
CHIP1/16W1%1000402LFICSMLFBC847BPNCHIP1/16W1001%0402LF0402LF4.75K1%CHIP1/16W45141/16W1%CHIP0402LF33.2216SMLFICBC847BPN0402LF4.75K1%CHIP1/16WCHIP0402LF1/16W1%33.2216
B2
B1
B1
B2
E2C2E1C1E1C1E2C2
R4399
R4397
R237
R4395
R4398
R239
R240
2
2
5
5
16164343
Q138
Q139
Q138
Q139
21
2
1
R241
21R4400
2
1
2
1
2
1
21
21
2
1
21
21
21R238
21
2
1R4396
SHEETDATE
DEPARTMENT
SIZE
PROJECT DOCUMENT NUMBER REV
REVIEWER
DESIGNER
123
7 3 2 1 6 5 4
E
A
B
C
E
D
C
B
A
7 6 5 4
D
OUT
OUT
IN
OUT
OUT
IN
IN
IN
R242
R243
R244
C



CPLDCPU0CPU1
CPLD20221208 CHANGE Q142,Q143 TO BA008470026
MEMHOT INCPLDCPLDCPU1CPU020210907 MODIFY FOR GT20211206 MODIFY FOR GT
Fri Aug 25 14:01:42 2023N/AN/AN/AN/AV05122 OF 312PVNN_TERM_CPU1PVNN_TERM_CPU1PVNN_TERM_CPU0PVNN_TERM_CPU0P3V3P3V3PVNN_TERM_CPU1PVNN_TERM_CPU0
SPR CPU0 & 1- MEMHOT
H_CPU1_MEMHOT_IN_LVC1_R_NH_CPU1_MEMHOT_OUT_LVC1_R_N
H_CPU0_MEMHOT_IN_LVC1_R_NH_CPU0_MEMHOT_OUT_LVC1_R_NH_CPU1_MEMHOT_OUT_VT_R_NH_CPU0_MEMHOT_OUT_VT_R_NH_CPU1_MEMHOT_OUTH_CPU0_MEMHOT_OUTH_CPU1_MEMHOT_OUT_VT_N H_CPU1_MEMHOT_OUT_LVC1_NH_CPU1_MEMHOT_OUT_RH_CPU0_MEMHOT_OUT_RH_CPU0_MEMHOT_OUT_VT_NH_CPU1_MEMHOT_IN_LVC1_R1_NH_CPU0_MEMHOT_IN_LVC1_R1_NH_CPU0_MEMHOT_OUT_LVC1_NH_CPU0_MEMHOT_IN_LVC1_NH_CPU1_MEMHOT_IN_LVC1_N1445216216
CHIP0402LF1001/16W1%1.5K0402LF1/16W CHIP1%1%CHIP0402LF1001/16W1.5K1/16W CHIP1%0402LFBC847BPNICSMLFSMLFICBC847BPNCHIP05%1/16W0402LF01/16WCHIP5%0402LF
ICSMLFBC847BPN1/16W1%CHIP0402LF33.22161.5K0402LFCHIPCHIP1.5K0402LFICSMLFBC847BPN1/16W1%4.75K0402LFCHIPCHIP1/16W1%4.75K0402LFCHIP1/16W0402LF1%1000402LF1%33.21/16W CHIP2161/16W0402LFCHIP1%1000402LFCHIP1%1001/16W45141001%1/16WCHIP0402LF
B1
B1
B2
B2
E1C1E1C1E2C2E2C2
R4293
R4294
R4407
R4403
R4404
R208
R210
R203
R4401
2
2
5
5
16164343
Q143
Q142
Q143
Q142
2
1
21
21
21
2
1
2
1
R4405
2
1
21
21
21R4408
21
21
21
2
1
21R204
2
1R4402
SHEETDATE
DEPARTMENT
SIZE
PROJECT DOCUMENT NUMBER REV
REVIEWER
DESIGNER
123
7 3 2 1 6 5 4
E
A
B
C
E
D
C
B
A
7 6 5 4
D
IN OUT
OUT
OUT
IN
IN
OUT
IN
R219
R220
R4406
C



CPLDCPLD
CPU0CPU120220725 CHANGE R197,R198 TO 301 OHM20221208 CHANGE Q140,Q141 TO BA00847002620211206 MODIFY FOR GTCPU0
CPLDCPU1
Fri Aug 25 14:01:43 2023N/AV05N/A123 OF 312N/AN/A
PVNN_TERM_CPU1PVNN_TERM_CPU1PVNN_TERM_CPU0PVNN_TERM_CPU0
PVNN_TERM_CPU1PVNN_TERM_CPU0P3V3P3V3
SPR CPU0 & 1- MEMTRIP/NMI
H_CPU0_MEMTRIP_LVC1_R_NH_CPU1_MEMTRIP_LVC1_R_NH_CPU_NMI_LVC1_R_N H_CPU_NMI_LVC1_NH_CPU1_MEMTRIP_OUT_VT_R_NH_CPU0_MEMTRIP_OUT_VT_R_NH_CPU1_MEMTRIPH_CPU0_MEMTRIP H_CPU0_MEMTRIP_RH_CPU1_MEMTRIP_RH_CPU1_MEMTRIP_VT_NH_CPU0_MEMTRIP_VT_N
H_CPU1_NMI_LVC1_NH_CPU0_NMI_LVC1_NH_CPU1_MEMTRIP_LVC1_NH_CPU0_MEMTRIP_LVC1_N4514
2160402LFCHIP 1/16W05%0402LF49.91/16W1%CHIPCHIP0402LF 1/16W49.91%1/16W1%CHIP1000402LFCHIP0402LF1%1.5K1/16W1/16W1%1.5K0402LFCHIPBC847BPNSMLFICBC847BPNICSMLF1.5K0402LFCHIPCHIP1.5K0402LFBC847BPNICSMLFBC847BPNICSMLF0402LF1/16WCHIP1%100
1%3010402LFCHIP1/16W45141%CHIP1/16W3010402LF0402LFCHIP4.75K1%1/16W1%33.21/16W0402LFCHIP0402LF1%1/16W4.75KCHIP0402LFCHIP1/16W33.21%216216
B1
B1
B2
B2
E1C1E1C1E2C2E2C2
R4413
R200
R4409
R4410
R205
R188
2
2
5
5
16164343
Q141
Q140
Q141
Q140
21
2
1
R4411
21R4414
2
1
2
1
2
1
2
1
21
21
21
2
1R202
21R195
21R196
21
21R206
SHEETDATE
DEPARTMENT
SIZE
PROJECT DOCUMENT NUMBER REV
REVIEWER
DESIGNER
123
7 3 2 1 6 5 4
E
A
B
C
E
D
C
B
A
7 6 5 4
D
OUT
OUT
IN OUT
OUT
IN
IN R4412
R197
R198
C



CPLDCPLDCPLDCPLD
CPLD20210907 MODIFY FOR GTCPLD
20211129 R186 CHANGE TO 100 OHM20211129 R184 CHANGE TO 100 OHM20211206 ADD R4295,R4296,R4297,R4298N/AFri Aug 25 14:01:44 2023N/A124 OF 312V05N/AN/A
PVCCD_HV_CPU0PVCCD_HV_CPU0PVNN_TERM_CPU0PVCCD_HV_CPU0PVCCD_HV_CPU0
PVNN_TERM_CPU0SPR CPU0 & 1 - CPU0 PWRGDS/RESET
14141414
1414
216219216219216219216219216219216219PWRGD_DRAMPWRGD_CPU0_GH_LVC1_RCHIP1001/16W1001/16WCHIPCHIPCHIP1%CHIPPWRGD_DRAMPWRGD_CPU0_EF_LVC1_RPWRGD_DRAMPWRGD_CPU0_AB_LVC1_R21001/16W0402LF1%CHIP1%1%PWRGD_DRAMPWRGD_CPU0_CD_LVC1_RPWRGD_DRAMPWRGD_CPU0_AB_LVC1_R1/16W1001%CHIP0402LF0402LF1/16W1001%CHIP0402LF1001/16WPWRGD_DRAMPWRGD_CPU0_CD_LVC1_R2PWRGD_DRAMPWRGD_CPU0_EF_LVC1_R21/16W0402LF0402LF0402LFPWRGD_DRAMPWRGD_CPU0_GH_LVC1_R2100CHIP1%RST_CPU0_BUF_R_N RST_CPU0_LVC1_NCHIP0402LF 1/16W1%100PWRGD_CPU0_LVC10402LF0402LF
1001/16WCHIP 1/16WPWRGD_DRAMPWRGD_CPU0_AB_R_LVC10402LF5%CHIP1%0402LF1%PWRGD_DRAMPWRGD_CPU0_EF_R_LVC1PWRGD_DRAMPWRGD_CPU0_CD_R_LVC11%0402LF1001/16W1/16W100PWRGD_CPU0_BUF_R0402LF05%
0402LFPWRGD_CPU0_LVC1_R
1/16W
0 CHIP1001/16W1%0RST_CPU0_LVC1_R_N5%0402LF1/16WCHIP5%CHIP 1/16WPWRGD_DRAMPWRGD_CPU0_GH_R_LVC1CHIP01/16W5%0402LF5%CHIP 1/16W0CHIP00402LF
R4295
R4296
R4297
R4298
R186
R184
R175
R177
R179
R181
R183
R185
R171
R168
R166
R164
R162
R160 21
21
21
21
21
21
21
21
21
21
21
21
21
21
21
21
21
21
SHEETDATE
DEPARTMENT
SIZE
PROJECT DOCUMENT NUMBER REV
REVIEWER
DESIGNER
123
7 3 2 1 6 5 4
E
A
B
C
E
D
C
B
A
7 6 5 4
D
OUT
OUT
OUT
OUT
OUT
OUT
IN
IN
IN
IN
IN
IN
C



20211206 ADD R4299,R4300,R4301,R430220211129 R156 CHANGE TO 100 OHM20211129 R158 CHANGE TO 100 OHM
CPLDCPLDCPLDCPLDCPLD
CPLD20210907 MODIFY FOR GT
Fri Aug 25 14:01:45 2023N/AV05125 OF 312N/AN/AN/APVNN_TERM_CPU1PVCCD_HV_CPU1PVCCD_HV_CPU1PVCCD_HV_CPU1
PVNN_TERM_CPU1PVCCD_HV_CPU1
SPR CPU0 & 1 - CPU1 PWRGDS/RESET454545
216219216219216219216219216219216219 454545PWRGD_CPU1_LVC1CHIPPWRGD_DRAMPWRGD_CPU1_GH_LVC1_R1001/16W1%CHIPPWRGD_DRAMPWRGD_CPU1_GH_LVC1_R21/16WPWRGD_DRAMPWRGD_CPU1_EF_LVC1_R21%1/16W1%1/16W1001001/16W100CHIP1%1/16W1/16WCHIP1%1001/16W1/16WPWRGD_DRAMPWRGD_CPU1_AB_LVC1_R0402LF1/16W0402LF5%0CHIPRST_CPU1_LVC1_R_N0402LF5%01/16WCHIPPWRGD_CPU1_LVC1_R0402LF1/16WCHIP5%0PWRGD_DRAMPWRGD_CPU1_GH_R_LVC10402LF05%CHIP05%1/16WCHIPPWRGD_DRAMPWRGD_CPU1_CD_R_LVC1CHIP0402LFPWRGD_DRAMPWRGD_CPU1_AB_R_LVC1PWRGD_DRAMPWRGD_CPU1_EF_R_LVC1RST_CPU1_BUF_R_N1%CHIP0402LF1000402LF0402LF1001/16W1%0402LF5%01/16WCHIPCHIP1000402LFRST_CPU1_LVC1_N1%1/16W0402LFCHIP1/16W100CHIPPWRGD_CPU1_BUF_R0402LF0402LF1%CHIP0402LF1%0402LF100PWRGD_DRAMPWRGD_CPU1_CD_LVC1_R2PWRGD_DRAMPWRGD_CPU1_EF_LVC1_R1%CHIP0402LF1001%1/16WCHIP0402LF100PWRGD_DRAMPWRGD_CPU1_AB_LVC1_R2PWRGD_DRAMPWRGD_CPU1_CD_LVC1_R
R4299
R4300
R4301
R4302
R158
R156
R135
R137
R151
R153
R155
R157
R122
R124
R126
R128
R130
R132
21
21
21
21
21
21
21
21
21
21
21
21
21
21
21
21
21
21
SHEETDATE
DEPARTMENT
SIZE
PROJECT DOCUMENT NUMBER REV
REVIEWER
DESIGNER
123
7 3 2 1 6 5 4
E
A
B
C
E
D
C
B
A
7 6 5 4
D
IN
IN
OUT
OUT
OUT
OUT
OUT
OUTIN
IN
IN
IN
C



CPU1 UPICPU0 UPIN/AN/AN/AN/AV05126 OF 312Fri Aug 25 14:01:46 2023PVNN_TERM_CPU0PVNN_TERM_CPU1SPR CPU0 & 1- MONF/FIST1919191950505050PU_CPU0_UPI0_AC_COUPLINGPU_CPU0_UPI1_AC_COUPLINGPU_CPU0_UPI2_AC_COUPLINGPU_CPU0_UPI3_AC_COUPLINGPU_CPU1_UPI3_AC_COUPLING1%EMPTY2401/16W0402LFPU_CPU1_UPI2_AC_COUPLINGEMPTY1%2401/16W0402LFPU_CPU1_UPI1_AC_COUPLINGEMPTY1%2401/16W0402LFPU_CPU1_UPI0_AC_COUPLING0402LF 1/16W240EMPTY1%1%EMPTY2400402LF 1/16W1/16W2401%0402LFEMPTY1/16W2401%0402LFEMPTYEMPTY1/16W0402LF1%240
21R93
21R92
21R91
21R90
21R97
21R94
21R95
21R96
SHEETDATE
DEPARTMENT
SIZE
PROJECT DOCUMENT NUMBER REV
REVIEWER
DESIGNER
123
7 3 2 1 6 5 4
E
A
B
C
E
D
C
B
A
7 6 5 4
D
OUT
OUT
OUT
OUT
OUT
OUT
OUT
OUT
C



CPU1 ADDR: 001CPU0 ADDR: 000
Fri Aug 25 14:01:47 2023N/AN/AN/AN/AV05127 OF 312
P3V3_AUXP3V3_AUXP3V3_AUXP3V3_AUX
SPR CPU0 & 1 - PIROM
1445141445454514CHIP1K1/16W1%0402LFCHIP1%1/16W1K0402LF1K0402LF1/16W1%EMPTYEMPTY1%1/16W1K0402LF1%1/16W1KEMPTY0402LF1%1K1/16WCHIP0402LF0402LF1/16W1%EMPTY1KEMPTY0402LF1/16W1%1KEMPTY10K1%0402LF1/16W0402LF10K1%1/16WCHIPEMPTY0402LF1%1/16W10K10KCHIP1/16W1%0402LFCHIP0402LF1%1/16W10K0402LF1%10KCHIP1/16W0402LF10KCHIP1/16W1%1%0402LF1/16WEMPTY10KPD_PIROM_CPU0_ADDR0PU_PIROM_CPU1_SM_WPPD_PIROM_CPU0_ADDR2PD_PIROM_CPU0_ADDR1PD_PIROM_CPU1_ADDR2PU_PIROM_CPU1_ADDR0PD_PIROM_CPU1_ADDR1PU_PIROM_CPU0_SM_WP
2
1
2
1
2
1
2
1
2
1
2
1
2
1
2
1
2
1
2
1
2
1
2
1
2
1
2
1
2
1
2
1
SHEETDATE
DEPARTMENT
SIZE
PROJECT DOCUMENT NUMBER REV
REVIEWER
DESIGNER
123
7 3 2 1 6 5 4
E
A
B
C
E
D
C
B
A
7 6 5 4
D
OUT
OUT
OUT
OUT
OUT
OUT
OUT
OUT
R1005
R1004R650
R997
R626
R625
R332
R331
R628 R630
R627 R629
R515
R333 R335
R334
C



N/AFri Aug 25 14:01:48 2023N/A128 OF 312V05N/AN/ASPR CPU0 & 1 - DDR RESET CPU TO PLD
22513 22513 22513 22544 22544 22544 22544 22513
0402LF1/16W1%CHIP10K0402LF1%CHIP1/16W10KCHIP1%0402LF1/16W10K10KCHIP1%1/16W0402LF0402LF1/16W1%CHIP10KCHIP1%1/16W0402LF10KCHIP1%1/16W0402LF10K0402LF1/16W1%CHIP10KRST_CPU0_DRAM_CD_PLD_NRST_CPU0_DRAM_CD_N5%0 RST_CPU0_DRAM_EF_PLD_NRST_CPU0_DRAM_EF_N5%0 RST_CPU0_DRAM_GH_PLD_NRST_CPU0_DRAM_GH_N5%0 RST_CPU1_DRAM_CD_PLD_NRST_CPU1_DRAM_CD_N05%RST_CPU1_DRAM_AB_PLD_NRST_CPU1_DRAM_AB_N1/16W5%00402LFCHIPRST_CPU1_DRAM_GH_PLD_NRST_CPU1_DRAM_GH_N05%RST_CPU1_DRAM_EF_PLD_NRST_CPU1_DRAM_EF_N05%RST_CPU0_DRAM_AB_PLD_NRST_CPU0_DRAM_AB_NCHIP 1/16W 0402LF05%
R2969
R860
R859
R861
R851
R852
R853
R854
2
1
2
1
2
1
2
1
2
1
2
1
2
1
2
1
21 21
21 21
21 21 21 21
SHEETDATE
DEPARTMENT
SIZE
PROJECT DOCUMENT NUMBER REV
REVIEWER
DESIGNER
123
7 3 2 1 6 5 4
E
A
B
C
E
D
C
B
A
7 6 5 4
D
OUTOUT
OUTOUTININ
ININ
IN OUT
OUTOUT
OUT
INININ
R935 R937 R939R933
R932 R934 R936 R938
C



20210907 MODIFY FOR GT
Fri Aug 25 14:01:49 2023N/A129 OF 312N/AN/AN/AV05PVCCD_HV_CPU0PVCCD_HV_CPU0PVCCD_HV_CPU0PVCCD_HV_CPU0
SPR CPU0 - DDR RESET PLD TO DIMM909192 93
82 83 84 8521625621625621625621625694 95 96 97
86 87 88 891%1/16WEMPTYCHIP5%CHIP1/16W1/16WCHIPCHIP1/16W1/16W1K0402LF1%1K0402LFRST_M_EF_CPU0_FPGA_N0402LF1K1%1K1%0402LFRST_M_AB_CPU0_FPGA_N10%0402LFC04021%
1/16W10K0402LF1%EMPTY0402LFEMPTY1%10K1/16W1%0402LF10K1/16WEMPTYEMPTY10K1/16W0402LF0CHIP 1/16W1/16W0402LF5%0CHIP
CHIP 1/16W05%0402LF0402LF05%CHIPRST_PLD_CPU0_DRAM_AB_NRST_PLD_CPU0_DRAM_CD_NRST_PLD_CPU0_DRAM_EF_NRST_PLD_CPU0_DRAM_GH_N RST_M_GH_CPU0_FPGA_N
RST_M_CD_CPU0_FPGA_N1UF25V10%C0402EMPTY25V1UFC040210%25V1UFEMPTY
EMPTY10%25V1UFC0402
R835
R838
R837
R836
2
1
2
1
2
1
2
1
2
1
2
1
2
1
2
1
2
1
2
1
2
1
2
1
21
21
21
21
SHEETDATE
DEPARTMENT
SIZE
PROJECT DOCUMENT NUMBER REV
REVIEWER
DESIGNER
123
7 3 2 1 6 5 4
E
A
B
C
E
D
C
B
A
7 6 5 4
D
IN
IN
OUT
OUT
IN OUT
OUTIN
C621
C624
C623
C622
R839
R842
R841
R840
C
R705
R708
R707
R706



20210907 MODIFY FOR GT
N/AFri Aug 25 14:01:50 2023130 OF 312N/AN/AV05N/A
PVCCD_HV_CPU1
PVCCD_HV_CPU1PVCCD_HV_CPU1PVCCD_HV_CPU1
SPR CPU1 - DDR RESET PLD TO DIMM
9899 100101102 103 104 105216256
216256
216256216256110 111 112 113106 107 108 109
CHIP0402LFRST_M_AB_CPU1_FPGA_N1/16WCHIP1/16WCHIPRST_M_CD_CPU1_FPGA_NCHIP1/16W0402LF1/16W1%1K0402LF1%1K0402LF1K1%0402LF1K1%1/16WC0402RST_PLD_CPU1_DRAM_AB_N0402LFEMPTY1%10K
EMPTY1%0402LF10K1/16W0402LF1/16W10K1%EMPTY0402LFEMPTY1/16W1%10K1/16W5%0CHIP05%0402LF1/16WCHIPCHIP 1/16W0402LF05%1/16WCHIP05%0402LFRST_PLD_CPU1_DRAM_GH_N
RST_PLD_CPU1_DRAM_CD_NRST_PLD_CPU1_DRAM_EF_NRST_M_GH_CPU1_FPGA_NRST_M_EF_CPU1_FPGA_NEMPTYC040210%25V1UF
1UF25V10%EMPTYEMPTY10%1UF25VC0402EMPTYC040210%25V1UF
R816
R817
R818
R815
2
1
2
1
2
1
2
1
2
1
2
1
2
1
2
1
2
1
2
1
2
1
2
1
21
21
21
21
SHEETDATE
DEPARTMENT
SIZE
PROJECT DOCUMENT NUMBER REV
REVIEWER
DESIGNER
123
7 3 2 1 6 5 4
E
A
B
C
E
D
C
B
A
7 6 5 4
D
OUT
OUT
OUT
OUTIN
IN
IN
IN
R703
C613
C614
C615
C616
R819
R822
R821
R820
C
R702
R704
R701



Fri Aug 25 14:01:51 2023N/AN/AN/AN/AV05131 OF 312
JTAG_TRC_PCH_PTI<0>P3V3_AUXPVNN_TERM_CPU0P3V3_AUXP1V8_PCH_AUXP1V05_PCH_AUXP3V3_AUX
SPR & PCH - DEBUG PORT (1/3)241213213241131131132132131131183183131131131132239131182183131131183183183183183183183201202183183183183183183183183131131131131131131198205185215198 185223 244182131134 1821344
203 23923913213223923913213113418213441341821322391445SMB_HOST_3V3AUX_SCL_R4SMB_HOST_3V3AUX_SDA_R40402LFCHIPNC_DBP_P24NC_DBP_P22NC_DBP_P20033.21/16W1/16WNC_DBP_P18SMB_HOST_3V3AUX_XDP_R_SDASMB_HOST_3V3AUX_XDP_R_SCLCHIPJTAG_DBP_TCK_R_TCKJTAG_DBP_CPU_HOOK9_MBP3_GTL_NJTAG_DBP_CPU_HOOK8_MBP2_GTL_NC04021%SMB_HOST_3V3AUX_XDP_R_SCLSMB_HOST_3V3AUX_XDP_R_SDAJTAG_TRC_PCH_PTI<14>JTAG_TRC_PCH_PTI<15>JTAG_DBP_POWER_BTN_NJTAG_RST_DBP_RSMRST_NNC_DBP_P54NC_DBP_P561/16WEMPTY1501/16WCHIP
33.21/16W0402LFCHIP1KNC_DBP_P46NC_DBP_P44JTAG_DBP_BOOT_HALT_NNC_DBP_P30NC_DBP_P28NC_DBP_P26CHIP49.91%0402LFJTAG_DBP_PREQ_NIOSMLFSCONN60_ASP-214108-01JTAG_DBP_TMS_RJTAG_DBP_CPU_GTL_TCK_RJTAG_DBP_TDO_RJTAG_DBP_TDI_RJTAG_RST_DBP_RST_CO_NJTAG_DBP_PMODE PD_TRST_P3NC_MIPI60_P9 JTAG_DBP_PREQ_N_RJTAG_DBP_PRDY_R1_NJTAG_TRC_PCH_PTI0_CLKJTAG_DBP_PCH_DEBUG_CONSENT_NJTAG_DBP_PRESENT_R_NJTAG_TRC_PCH_PTI<1>JTAG_TRC_PCH_PTI<2>JTAG_TRC_PCH_PTI<3>JTAG_TRC_PCH_PTI<4>JTAG_TRC_PCH_PTI<5>JTAG_TRC_PCH_PTI<6> NC_DBP_P32JTAG_TRC_PCH_PTI<7> NC_DBP_P34JTAG_TRC_PCH_PTI<8>JTAG_TRC_PCH_PTI<9>JTAG_TRC_PCH_PTI<10>JTAG_TRC_PCH_PTI<11>JTAG_TRC_PCH_PTI<12>JTAG_TRC_PCH_PTI<13>JTAG_TRC_PCH_PTI1_CLKJTAG_DBP_BOOT_HALT_NJTAG_RST_DBP_RSMRST_NJTAG_DBP_PCH_DEBUG_CONSENT_NJTAG_DBP_PRESENT_R_NJTAG_DBP_POWER_BTN_NJTAG_RST_DBP_RST_CO_NFM_ADR_MODE0FM_BMC_DBP_PRESENT_R_NFM_PCH_CONSENT_STRAP_NRST_RSMRST_PCH_NJTAG_DBP_CPU_GTL_TCKX7R25V0.1UF10%040210%X7R040225V0.1UF1/16WCHIP1%750402LF0402LF1/16W1%1K1%1K0402LF1K1%1/16WCHIP0402LFCHIP0402LF1K1%1/16W0402LF0402LFCHIP1K1%1/16W0402LF10%25V1UF1UF10%X6S0402X7R25V10%25V1UFFM_CPU_FBRK_DEBUG_N1%1/16WCHIP100402LFJTAG_DBP_TMS1%100CHIP 1/16W0402LFJTAG_DBP_TDO1/16W0402LF1%10CHIP10 1%1/16WCHIP0402LFJTAG_DBP_TDIJTAG_DBP_CPU_GTL_TCK1/16W05%CHIP0402LFJTAG_DBP_TCK_PCHCHIP 1/16W05%0402LFJTAG_DBP_PRDY_N10K1%0402LF0402LF1%CHIP1K1%1/16WFM_CPU_FBRK_DEBUG_R_NC0402X6S10%X6SC040225VCHIP1/16W1%CHIP1%0.1UF1/16WCHIP1/16WCHIP05%0402LF
R4503
R4502
R1472
R773
R771
R772
C552
R780
R764
R765
R762
R763
R777
R776
R775
7
G4G3
G2G1
6059
5857
5655
5453
5251
5049
4847
4645
4443
4241
4039
3837
3635
3433
3231
3029
2827
2625
2423
2221
2019
1817
1615
1413
1211
109
8
65
43
21
J42
G4G3
G2G1
6059
5857
5655
5453
5251
5049
4847
4645
4443
4241
4039
3837
3635
3433
3231
29 30
2827
2625
2423
2221
2019
1817
1615
1413
1211
109
87
65
43
21
21 21
21
2
1
2
1
2
1
21
21
21
2
1
2
1
2
1
2
1
2
1
2
1
2
1
2
1
2
1
21
21
21
21 21
2
1
21
21 21
SHEETDATE
DEPARTMENT
SIZE
PROJECT DOCUMENT NUMBER REV
REVIEWER
DESIGNER
123
7 3 2 1 6 5 4
E
A
B
C
E
D
C
B
A
7 6 5 4
D
OUT
OUT
OUT
BIIN
IN
IN
OUTOUT
OUTOUTOUT
OUT
IN
IN
IN
ININ
INININININININININ
ININ
ININININ
IN
OUT
OUT
OUT OUTBI BI
OUT
OUT
IN
OUT IN
OUT
OUT
OUTIN
OUTIN
OUT
IN
R774C548 C549
R767 R768R766
C551
R769
C547 C550
R779R778
C



132 OF 312V05N/AN/AN/AN/AFri Aug 25 14:01:53 2023
P3V3_AUX
P1V05_PCH_AUXPVNN_TERM_CPU0PVNN_TERM_CPU0P3V3_AUX
SPR & PCH - DEBUG PORT (2/3)182131239132182132131239182131239132182131132239182131132239134413441321312391312391321311311311322391311322392132821322531312391322132821322531344133133164716471%499CHIP0402LF1/16W1%499CHIP0402LF1/16W751/16W0402LF1%CHIP1/16W0402LFCHIP1%751/16W1501%0402LFCHIP1501%1/16WCHIP0402LFCHIP1/16W0402LF1%1501/16W1%150CHIP0402LF1501/16W0402LFCHIP1%
0402LF1/16WCHIP1201%
JTAG_DBP_TDI_PCHJTAG_DBP_TDI1%1/16WCHIP100402LFJTAG_DBP_TDO_PCHJTAG_DBP_TDO0402LF1%1/16WCHIP10JTAG_DBP_TMS_PCHJTAG_DBP_TMS101/16W1%0402LFCHIP
CHIP1/16W0402LF5%0
H_DBP_PRDY_N_PCHJTAG_DBP_PRDY_N10 1%1/16WCHIP0402LFH_DBP_PREQ_N_PCHJTAG_DBP_PREQ_N10 1%CHIP0402LF1/16WH_CPU_PRDY_QS_GTL_NH_CPU_PREQ_QS_GTL_NJTAG_DBP_TDOPD_74CB_A9JTAG_DBP_TDIJTAG_DBP_CPU_HOOK9_MBP3_GTL_NJTAG_DBP_CPU_HOOK8_MBP2_GTL_NJTAG_DBP_PRDY_NJTAG_DBP_PREQ_NPWRGD_PVNN_MAIN_CPU0JTAG_DBP_TMSPWRGD_PVNN_MAIN_CPU0JTAG_DBP_CPU_QS_GTL_TMSJTAG_MUX_QS_GTL_TDOTP_74CB_B8JTAG_QS_MUX_GTL_TDIDBP_CPU_HOOK8_MBP2_GTL_QS_NDBP_CPU_HOOK9_MBP3_GTL_QS_N1UF25V10%X6SC040274CBTLV3126PWICSMLF1UF25V10%X6SC040274CBTLV3126PWICSMLF
R756
R755
R753
R752
R754
U18
U17
VCC
4OE
4A 4B
3OE
3A
GND
1A
2B
1B
2OE
1OE
3B
2A
VCC
4OE
4A 4B
3OE
3A
GND
1A
2B
1B
2OE
1OE
3B
2A
2
1
2
1
2
1
2
1
2
1
2
1
2
1
2
1
2
1
2
1
21
21
2
1
21
21
21
2
1
2
1
14
7
13 1112
10 89
4 65
1 32
14
7
13 1112
10 89
4 65
1 32
SHEETDATE
DEPARTMENT
SIZE
PROJECT DOCUMENT NUMBER REV
REVIEWER
DESIGNER
74CBTLV3126
74CBTLV3126
123
7 3 2 1 6 5 4
E
A
B
C
E
D
C
B
A
7 6 5 4
D
OUT
OUT
IN
IN
IN
OUT IN
OUT
OUT
OUT
OUT
BI
BI
BI
BI
IN
OUT
OUT
IN
ININ
IN
OUT IN
IN
IN
R748 R749 R750 R751R747
R761R760R759R758
R757
C546
C545
R746
C



Fri Aug 25 14:01:54 2023N/AN/AN/AV05133 OF 312N/A
I58
P3V3_AUX
P3V3_AUXPVNN_TERM_CPU0 PVNN_TERM_CPU1PVNN_TERM_CPU0PVNN_TERM_CPU1P3V3_AUXP3V3_AUXP3V3_AUXSPR & PCH - DEBUG PORT (3/3)
13133441321331321313344133
133133452221422213133133441/16W33.21%0402LFFM_CPU_EN_R0402X7R0.1UF10%25V
NC7SB3157P6XNC7SB3157P6XICC0402X6S10%25V1UF0.1UF25VX7R040210%NC7SB3157P6XNC7SB3157P6XIC25VC04021UF10%X6SX7R10%25V0.1UF04020402X7R25V10%IC74LVC1G02GWJTAG_CPU0_MUX_GTL_TDOJTAG_CPU1_MUX_GTL_TDOJTAG_MUX_QS_GTL_TDOFM_CPU1_SKTOCC_NJTAG_QS_MUX_GTL_TDI JTAG_MUX_CPU0_GTL_TDIJTAG_MUX_CPU1_GTL_TDIFM_CPU0_SKTOCC_N
FM_CPU1_SKTOCC_NFM_CPU0_SKTOCC_N05%0402LFCHIP 1/16WFM_CPU1_SKTOCC_LVT3_N0402LF0CHIP5%1/16WFM_CPU0_SKTOCC_LVT3_NCHIP0402LF1/16W1%10K1%CHIP1/16W10K0402LF
CHIP0402LF1/16W1%150CHIP1%0402LF1/16W150750402LF1/16WCHIP1%0402LFCHIP1/16W751%CHIPFM_CPU_ENSMLFICJTAG_CPU0_MUX_GTL_TDOJTAG_MUX_CPU1_GTL_TDISMLF74LVC1G66GV0.1UF
R738
R737
R745
5
6
2
1
34
5
6
2
1
34
S
B0
B1
VCC GND
A
S
B0
B1
VCC GND
A
2
15
3
4
U16
U23
U22
U21
Y
A
B
VCC
E
GND
Z
Y
GND VCC
21
2
1
2
1
21
2
1
21
2
1
2
1
2
1
2
1
2
1
2
1
2
12
1
41
2
53
SHEETDATE
DEPARTMENT
SIZE
PROJECT DOCUMENT NUMBER REV
REVIEWER
DESIGNER
123
7 3 2 1 6 5 4
E
A
B
C
E
D
C
B
A
7 6 5 4
D
OUT
IN
IN
IN
OUT
IN
OUT
OUT
IN
IN
OUT
OUT
IN
IN
R739 R740
C543 C544
C540 C542
R742 R744
C539
R741 R743
C541
C



Fri Aug 25 14:01:55 2023N/AN/AN/AN/AV05134 OF 312
P1V05_PCH_AUXP3V3_AUXP3V3_AUXP3V3_AUX
SPR & PCH - JTAG
13118213441311822142392151/16W0402LFCHIP1%1K0402LFCHIP1%1/16W1K0402LF1%1K1/16WCHIP1KCHIP0402LF1/16W1%1K1/16WEMPTY0402LF1%10K1/16WCHIP0402LF1%CHIP0402LF1%1001/16WJTAG_DBP_CPU_GTL_TCKJTAG_DBP_CPU_GTL_TCK_R15%00402LFJTAG_DBP_TCK_PCHJTAG_DBP_TCK_PCH_R1/16WCHIP0402LF05%TP_JTAG_BMC_4BTP_JTAG_BMC_1BFM_JTAG_TCK_MUX_SELJTAG_BMC_DBP_TCKFM_BMC_EN_DETPD_JTAG_BMC_NTRST_NJTAG_BMC_CPU_TCKJTAG_BMC_PCH_TCKFM_REMOTE_DEBUG_DET_RFM_JTAG_TCK_MUX_SEL == LOW (DEFAULT) , BMC TO CPUFM_JTAG_TCK_MUX_SEL == HIGH , BMC TO PCHL: DISABLE BMC XDP REMOTE DEBUGH: ENABLE BMC XDP (DEFAULT)FM_BMC_EN_DETBSS138KIC10%25VX6S1UFC040210%X7R25V0.1UF0402IC74CBTLV3126PWSMLFX7R040225V0.1UF10%25V1UF10%X6SC0402NC7SB3157P6XIC
R1348
R1349
U87
5
6
2
1
34
G
S
B0
B1
VCC GND
A
S D
U85
U86
VCC
4OE
4A 4B
3OE
3A
GND
1A
2B
1B
2OE
1OE
3B
2A
2
1
2
1
2
1
2
1
2
1
2
1
2
1
2
1
2
1
2
1
2
1
21
21
DESIGN NOTE:
DESIGN NOTE:
14
7
13 1112
10 89
4 65
1 32
SHEETDATE
DEPARTMENT
SIZE
PROJECT DOCUMENT NUMBER REV
REVIEWER
DESIGNER
74CBTLV3126
123
7 3 2 1 6 5 4
E
A
B
C
E
D
C
B
A
7 6 5 4
D
OUT
OUT
OUT
IN
IN
R1365
R3026 R3027 R1374
R3025
R1370
R1375 C1293C1288 C1289
C1292
C



20211026 MODIFY FOR GTTHIS PAGE WAS INTENTIONALLY LEFT BLANK
Thu Aug 24 16:13:54 2023N/AN/AN/AN/AV05135 OF 312BLANK
SHEETDATE
DEPARTMENT
SIZE
PROJECT DOCUMENT NUMBER REV
REVIEWER
DESIGNER
123
7 3 2 1 6 5 4
E
A
B
C
E
D
C
B
A
7 6 5 4
D
C



DP/DN SWAPDP/DN SWAPDP/DN SWAPDP/DN SWAPDP/DN SWAPDP/DN SWAPDP/DN SWAPDP/DN SWAP20210527 MODIFY FOR GTDP/DN SWAPDP/DN SWAPDP/DN SWAPDP/DN SWAPDP/DN SWAPDP/DN SWAPDP/DN SWAPDP/DN SWAPDP/DN SWAPDP/DN SWAPDP/DN SWAPDP/DN SWAPDP/DN SWAPDP/DN SWAP136 OF 312N/AFri Aug 25 14:01:57 2023N/AV05N/AN/APCIE - CPU0_EXAMAX_P2/P3_X161451451451741741731731741741733030303030303030303017315130174174303017330303030149173173174174148303030303030303017417417417417317317317317317314817317317330303030174174303030147174174GPU_3V3IO_RSVD4GPU_3V3IO_RSVD3GPU_3V3IO_RSVD1P5E_CPU0_PE3_TX_C_DN<1>P5E_CPU0_PE3_TX_C_DP<1>P5E_CPU0_PE2_TX_C_DP<1>P5E_CPU0_PE2_TX_C_DN<1>P5E_CPU0_PE3_TX_C_DN<2>P5E_CPU0_PE3_TX_C_DP<2>P5E_CPU0_PE2_TX_C_DN<2>P5E_CPU0_PE3_RX_DP<7>P5E_CPU0_PE3_RX_DN<7>P5E_CPU0_PE3_RX_DN<1>P5E_CPU0_PE3_RX_DP<1>P5E_CPU0_PE2_RX_DP<1>P5E_CPU0_PE2_RX_DN<1>P5E_CPU0_PE3_RX_DN<2>P5E_CPU0_PE3_RX_DP<2>P5E_CPU0_PE2_RX_DP<2>P5E_CPU0_PE2_RX_DN<2>P5E_CPU0_PE2_TX_C_DP<2>RST_SWB_BIC_BUF_NP5E_CPU0_PE2_RX_DP<7>P5E_CPU0_PE3_TX_C_DP<5>P5E_CPU0_PE3_TX_C_DN<5>P5E_CPU0_PE2_RX_DP<5>P5E_CPU0_PE2_RX_DN<5>P5E_CPU0_PE2_TX_C_DP<5>P5E_CPU0_PE3_RX_DP<6>P5E_CPU0_PE3_RX_DN<6>P5E_CPU0_PE2_RX_DP<6>P5E_CPU0_PE2_RX_DN<6>FM_SWB_PWR_EN_R_BUFP5E_CPU0_PE2_TX_C_DN<6>P5E_CPU0_PE2_TX_C_DP<6>P5E_CPU0_PE3_TX_C_DP<6>P5E_CPU0_PE3_TX_C_DN<6>RST_BMC_FROM_SWB_NIOTHLFP5E_CPU0_PE3_RX_DP<0>P5E_CPU0_PE3_RX_DN<0>P5E_CPU0_PE3_RX_DN<3>P5E_CPU0_PE3_RX_DP<3>P5E_CPU0_PE2_RX_DP<0>P5E_CPU0_PE2_RX_DN<0>P5E_CPU0_PE2_RX_DP<3>P5E_CPU0_PE2_RX_DN<3>P5E_CPU0_PE3_TX_C_DP<0>P5E_CPU0_PE3_TX_C_DN<0>P5E_CPU0_PE3_TX_C_DN<3>P5E_CPU0_PE3_TX_C_DP<3>P5E_CPU0_PE2_TX_C_DP<0>P5E_CPU0_PE2_TX_C_DN<0>P5E_CPU0_PE2_TX_C_DP<3>P5E_CPU0_PE2_TX_C_DN<3>P5E_CPU0_PE2_TX_C_DP<4>P5E_CPU0_PE2_TX_C_DN<4>FM_SWB_BIC_READY_NP5E_CPU0_PE2_TX_C_DN<5>P5E_CPU0_PE2_TX_C_DN<7>P5E_CPU0_PE2_TX_C_DP<7>P5E_CPU0_PE2_RX_DN<4>P5E_CPU0_PE2_RX_DP<4>P5E_CPU0_PE3_RX_DN<4>P5E_CPU0_PE3_RX_DP<4>P5E_CPU0_PE3_TX_C_DP<7>P5E_CPU0_PE3_TX_C_DN<7>P5E_CPU0_PE2_RX_DN<7>P5E_CPU0_PE3_RX_DN<5>P5E_CPU0_PE3_RX_DP<5>GPU_WP_HW_CTRL_ISOP5E_CPU0_PE3_TX_C_DN<4>P5E_CPU0_PE3_TX_C_DP<4>IOTHLF
N8
N7
N6
N5
M8
M7
M6
M5
L8
L7
L6
L5
K8
K7
K6
K5
J8
J7
J6
J5
I8
I7
I6
I5
H8
H7
H6
H5
G8
G7
G6
G5
F8
F7
F6
F5
E8
E7
E6
E5
D8
D7
D6
D5
C8
C7
C6
C5
B8
B7
B6
B5
A8
A7
A6
A5
N4
N3
N2
N1
M4
M3
M2
M1
L4
L3
L2
L1
K4
K3
K2
K1
J4
J3
J2
J1
I4
I3
I2
I1
H4
H3
H2
H1
G4
G3
G2
G1
F4
F3
F2
F1
E4
E3
E2
E1
D4
D3
D2
D1
C4
C3
C2
C1
B4
B3
B2
B1
A4
A3
A2
A1
J105 J105
1/2
NM
5
LKJC D E F G H IA B
6
7
8
N8
M8
N7
M7
N6
M6
N5
M5
L5
L6
L7
L8
K5
K6
K7
K8
J5
J6
J7
J8
I5
I6
I7
I8
H5
H6
H7
H8
G5
G6
G7
G8
F5
F6
F7
F8
E5
E6
E7
E8
D5
D6
D7
D8
C5
C6
C7
C8
B5
B6
B7
B8
A5
A6
A7
A8
2/2
NM
1
LKJC D E F G H IA B
2
3
4
N4
M4
N3
M3
N2
M2
N1
M1
L1
L2
L3
L4
K1
K2
K3
K4
J1
J2
J3
J4
I1
I2
I3
I4
H1
H2
H3
H4
G1
G2
G3
G4
F1
F2
F3
F4
E1
E2
E3
E4
D1
D2
D3
D4
C1
C2
C3
C4
B1
B2
B3
B4
A1
A2
A3
A4
SHEETDATE
DEPARTMENT
SIZE
PROJECT DOCUMENT NUMBER REV
REVIEWER
DESIGNER
123
7 3 2 1 6 5 4
E
A
B
C
E
D
C
B
A
7 6 5 4
D
OUT
OUT
OUT OUT
IN
OUT
IN
OUT
IN
OUT
OUT
ININ
OUTOUT
OUTOUT
IN
OUT
IN
ININ
OUTOUT
OUTOUT
IN
IN
IN
IN
IN
OUTOUT
OUTOUT
ININ
OUTOUT
OUT
IN
OUT
ININ
ININ
OUTOUT
OUTOUT
IN
ININ
ININ
OUTOUT
OUTOUT
ININ
IN
ININ
OUTOUT
OUTOUT
ININ
ININ
C



DP/DN SWAPDP/DN SWAPDP/DN SWAPDP/DN SWAPDP/DN SWAPDP/DN SWAPDP/DN SWAPDP/DN SWAP20210527 MODIFY FOR GT
DP/DN SWAPDP/DN SWAPDP/DN SWAPDP/DN SWAPDP/DN SWAPDP/DN SWAPDP/DN SWAPDP/DN SWAPDP/DN SWAPDP/DN SWAPDP/DN SWAP
137 OF 312Fri Aug 25 14:01:58 2023N/A V05N/AN/AN/APCIE - CPU0_EXAMAX_P2/P3_X16
3030301463017417414430301743030173173174174303030301731731743017430303017317330234301483030303030301511743017417417317317317317417424030234173173173173173173303017417417430303030174P5E_CPU0_PE3_RX_DN<9>P5E_CPU0_PE3_RX_DP<9>P5E_CPU0_PE2_RX_DP<9>PRSNT_CABLE_GPU_A1_NP5E_CPU0_PE2_RX_DN<9>P5E_CPU0_PE3_TX_C_DN<9>P5E_CPU0_PE3_TX_C_DP<9>PRSNT_CABLE_SWB_B1_NP5E_CPU0_PE3_RX_DP<15>P5E_CPU0_PE3_RX_DN<15>P5E_CPU0_PE3_TX_C_DN<15>P5E_CPU0_PE2_RX_DN<15>P5E_CPU0_PE2_RX_DP<15>P5E_CPU0_PE2_TX_C_DN<14>P5E_CPU0_PE2_TX_C_DP<14>P5E_CPU0_PE3_TX_C_DP<14>P5E_CPU0_PE3_TX_C_DN<14>P5E_CPU0_PE2_RX_DN<14>P5E_CPU0_PE2_RX_DP<14>P5E_CPU0_PE3_RX_DN<14>P5E_CPU0_PE3_RX_DP<14>P5E_CPU0_PE2_TX_C_DN<13>P5E_CPU0_PE2_TX_C_DP<13>P5E_CPU0_PE3_TX_C_DN<13>P5E_CPU0_PE2_RX_DN<13>P5E_CPU0_PE3_TX_C_DP<13>P5E_CPU0_PE2_RX_DP<10>P5E_CPU0_PE3_RX_DP<10>P5E_CPU0_PE3_RX_DN<10>P5E_CPU0_PE2_TX_C_DN<9>P5E_CPU0_PE2_TX_C_DP<9>P5E_CPU0_PE2_RX_DN<10>I3C_BMC_SWB_BUF_SCLP5E_CPU0_PE3_RX_DP<13>FM_SWB_PWRGDP5E_CPU0_PE3_RX_DN<13>P5E_CPU0_PE2_RX_DP<13>P5E_CPU0_PE3_RX_DN<11>P5E_CPU0_PE3_RX_DP<11>P5E_CPU0_PE2_RX_DP<11>P5E_CPU0_PE2_RX_DN<11>NC_J106_A5UART_BMC_BIC_RXP5E_CPU0_PE3_TX_C_DN<11>P5E_CPU0_PE2_RX_DP<8>P5E_CPU0_PE3_TX_C_DN<10>P5E_CPU0_PE3_TX_C_DP<10>P5E_CPU0_PE2_TX_C_DN<10>P5E_CPU0_PE2_TX_C_DP<10>P5E_CPU0_PE2_TX_C_DN<8>P5E_CPU0_PE2_TX_C_DP<8>P5E_CPU0_PE3_TX_C_DP<8>P5E_CPU0_PE3_TX_C_DN<8>UART_BMC_BIC_TXP5E_CPU0_PE2_RX_DN<8>I3C_BMC_SWB_BUF_SDAP5E_CPU0_PE2_TX_C_DP<15>P5E_CPU0_PE2_TX_C_DN<15>P5E_CPU0_PE2_TX_C_DN<12>P5E_CPU0_PE2_TX_C_DP<12>P5E_CPU0_PE2_TX_C_DN<11>P5E_CPU0_PE2_TX_C_DP<11>P5E_CPU0_PE3_RX_DP<8>P5E_CPU0_PE3_RX_DN<8>P5E_CPU0_PE3_TX_C_DP<15>P5E_CPU0_PE3_TX_C_DP<12>P5E_CPU0_PE3_TX_C_DN<12>P5E_CPU0_PE3_RX_DN<12>P5E_CPU0_PE3_RX_DP<12>P5E_CPU0_PE2_RX_DN<12>P5E_CPU0_PE2_RX_DP<12>IOTHLF
P5E_CPU0_PE3_TX_C_DP<11>
THLFIO
N8
N7
N6
N5
M8
M7
M6
M5
L8
L7
L6
L5
K8
K7
K6
K5
J8
J7
J6
J5
I8
I7
I6
I5
H8
H7
H6
H5
G8
G7
G6
G5
F8
F7
F6
F5
E8
E7
E6
E5
D8
D7
D6
D5
C8
C7
C6
C5
B8
B7
B6
B5
A8
A7
A6
A5
N4
N3
N2
N1
M4
M3
M2
M1
L4
L3
L2
L1
K4
K3
K2
K1
J4
J3
J2
J1
I4
I3
I2
I1
H4
H3
H2
H1
G4
G3
G2
G1
F4
F3
F2
F1
E4
E3
E2
E1
D4
D3
D2
D1
C4
C3
C2
C1
B4
B3
B2
B1
A4
A3
A2
A1
J106
J106
1/2
NM
5
LKJC D E F G H IA B
6
7
8
N8
M8
N7
M7
N6
M6
N5
M5
L5
L6
L7
L8
K5
K6
K7
K8
J5
J6
J7
J8
I5
I6
I7
I8
H5
H6
H7
H8
G5
G6
G7
G8
F5
F6
F7
F8
E5
E6
E7
E8
D5
D6
D7
D8
C5
C6
C7
C8
B5
B6
B7
B8
A5
A6
A7
A8 2/2
NM
1
LKJC D E F G H IA B
2
3
4
N4
M4
N3
M3
N2
M2
N1
M1
L1
L2
L3
L4
K1
K2
K3
K4
J1
J2
J3
J4
I1
I2
I3
I4
H1
H2
H3
H4
G1
G2
G3
G4
F1
F2
F3
F4
E1
E2
E3
E4
D1
D2
D3
D4
C1
C2
C3
C4
B1
B2
B3
B4
A1
A2
A3
A4
SHEETDATE
DEPARTMENT
SIZE
PROJECT DOCUMENT NUMBER REV
REVIEWER
DESIGNER
123
7 3 2 1 6 5 4
E
A
B
C
E
D
C
B
A
7 6 5 4
D
OUT
OUT
OUT
IN
BI
OUT
IN
OUT
OUT
IN
OUTOUT
OUTOUT
OUTOUT
IN
OUT
ININ
IN
OUTOUT
OUT
ININ
OUT
IN
OUT
IN
OUTOUT
ININ
ININ
OUTOUT
IN
OUTOUT
ININ
ININ
OUT
OUTOUT
OUT
IN
IN
ININ
OUT
OUT
IN
OUT
OUT
ININ
IN
ININ
OUTOUT
OUTOUT
ININ
IN
IN
C



CPU0_PE4_TX/RX<0-15>LANE REVERSALDP/DN SWAPDP/DN SWAPDP/DN SWAPDP/DN SWAPDP/DN SWAP20210527 MODIFY FOR GTDP/DN SWAPDP/DN SWAP
Fri Aug 25 14:01:59 2023N/AN/AN/AV05N/A138 OF 312PCIE - CPU0_EXAMAX_P0/P4_X16
1442929313117317517529146145175293117317529175173311731733131175175173173313129292917317517331173173313129291751751752917317317331312917517531175175312929311731751732929PRSNT_CABLE_SWB_B2_NNC_J107_A1P5E_CPU0_PE0_RX_DN<7>P5E_CPU0_PE0_RX_DP<7>P5E_CPU0_PE4_RX_DN<8>P5E_CPU0_PE4_RX_DP<8>P5E_CPU0_PE0_TX_C_DN<7>P5E_CPU0_PE4_TX_C_DP<9>P5E_CPU0_PE4_TX_C_DN<9>P5E_CPU0_PE0_RX_DP<1>SWB_HSC_PWRGDSWB_HSC_EN_BUFP5E_CPU0_PE4_TX_C_DN<14>P5E_CPU0_PE0_RX_DP<2>P5E_CPU0_PE4_RX_DP<13>P5E_CPU0_PE0_TX_C_DP<2>P5E_CPU0_PE4_TX_C_DN<13>NC_J107_N6P5E_CPU0_PE0_RX_DP<3>P5E_CPU0_PE4_TX_C_DP<13>P5E_CPU0_PE0_TX_C_DN<2>P5E_CPU0_PE4_RX_DN<13>P5E_CPU0_PE0_TX_C_DP<1>P5E_CPU0_PE0_TX_C_DN<1>P5E_CPU0_PE4_RX_DP<14>P5E_CPU0_PE4_RX_DN<14>P5E_CPU0_PE4_TX_C_DP<15>P5E_CPU0_PE4_TX_C_DN<15>P5E_CPU0_PE0_TX_C_DP<0>P5E_CPU0_PE0_TX_C_DN<0>P5E_CPU0_PE4_RX_DN<15>P5E_CPU0_PE4_RX_DP<15>P5E_CPU0_PE0_RX_DN<0>THLFIOP5E_CPU0_PE0_RX_DP<0>P5E_CPU0_PE0_RX_DN<2>IOTHLF
P5E_CPU0_PE0_TX_C_DP<7>P5E_CPU0_PE4_TX_C_DP<10>P5E_CPU0_PE0_TX_C_DP<5>P5E_CPU0_PE4_RX_DN<10>P5E_CPU0_PE0_TX_C_DP<4>P5E_CPU0_PE0_TX_C_DN<4>P5E_CPU0_PE4_RX_DN<11>P5E_CPU0_PE4_RX_DP<11>P5E_CPU0_PE0_RX_DP<4>P5E_CPU0_PE0_RX_DN<4>P5E_CPU0_PE4_TX_C_DN<11>P5E_CPU0_PE4_TX_C_DP<11>P5E_CPU0_PE4_TX_C_DP<14>P5E_CPU0_PE0_RX_DN<1>NC_J107_A5NC_J107_N4P5E_CPU0_PE0_TX_C_DP<6>P5E_CPU0_PE0_TX_C_DP<3>P5E_CPU0_PE0_TX_C_DN<3>P5E_CPU0_PE4_RX_DP<12>P5E_CPU0_PE4_RX_DN<12>P5E_CPU0_PE0_RX_DN<3>P5E_CPU0_PE4_TX_C_DP<12>P5E_CPU0_PE4_TX_C_DN<12>P5E_CPU0_PE4_RX_DP<10>P5E_CPU0_PE4_TX_C_DP<8>P5E_CPU0_PE4_TX_C_DN<8>P5E_CPU0_PE4_RX_DP<9>P5E_CPU0_PE0_RX_DP<6>P5E_CPU0_PE0_RX_DN<6>P5E_CPU0_PE4_RX_DN<9>P5E_CPU0_PE0_TX_C_DN<6>P5E_CPU0_PE4_TX_C_DN<10>P5E_CPU0_PE0_TX_C_DN<5>P5E_CPU0_PE0_RX_DP<5>P5E_CPU0_PE0_RX_DN<5>NC_J107_A3
N4
N3
N2
N1
M4
M3
M2
M1
L4
L3
L2
L1
K4
K3
K2
K1
J4
J3
J2
J1
I4
I3
I2
I1
H4
H3
H2
H1
G4
G3
G2
G1
F4
F3
F2
F1
E4
E3
E2
E1
D4
D3
D2
D1
C4
C3
C2
C1
B4
B3
B2
B1
A4
A3
A2
A1
N8
N7
N6
N5
M8
M7
M6
M5
L8
L7
L6
L5
K8
K7
K6
K5
J8
J7
J6
J5
I8
I7
I6
I5
H8
H7
H6
H5
G8
G7
G6
G5
F8
F7
F6
F5
E8
E7
E6
E5
D8
D7
D6
D5
C8
C7
C6
C5
B8
B7
B6
B5
A8
A7
A6
A5
J107J107
2/2
NM
1
LKJC D E F G H IA B
2
3
4
N4
M4
N3
M3
N2
M2
N1
M1
L1
L2
L3
L4
K1
K2
K3
K4
J1
J2
J3
J4
I1
I2
I3
I4
H1
H2
H3
H4
G1
G2
G3
G4
F1
F2
F3
F4
E1
E2
E3
E4
D1
D2
D3
D4
C1
C2
C3
C4
B1
B2
B3
B4
A1
A2
A3
A4
1/2
NM
5
LKJC D E F G H IA B
6
7
8
N8
M8
N7
M7
N6
M6
N5
M5
L5
L6
L7
L8
K5
K6
K7
K8
J5
J6
J7
J8
I5
I6
I7
I8
H5
H6
H7
H8
G5
G6
G7
G8
F5
F6
F7
F8
E5
E6
E7
E8
D5
D6
D7
D8
C5
C6
C7
C8
B5
B6
B7
B8
A5
A6
A7
A8
SHEETDATE
DEPARTMENT
SIZE
PROJECT DOCUMENT NUMBER REV
REVIEWER
DESIGNER
123
7 3 2 1 6 5 4
E
A
B
C
E
D
C
B
A
7 6 5 4
D
OUT
IN
OUT
OUT
IN
OUTOUT
OUTOUT
IN
ININ
IN
OUTOUT
OUT
ININ
OUT
IN
OUT
IN
OUTOUT
OUT
ININ
OUT
IN
OUT
IN
OUTOUT
OUTOUT
ININ
ININ IN
OUT
OUTOUT
OUT
IN
ININ
OUT
IN
OUTOUT
IN
OUT
ININ
ININ
IN
OUTOUT
OUTOUT
ININ
IN
OUT
IN
C



DP/DN SWAPDP/DN SWAPDP/DN SWAPCPU0_PE4_TX/RX<0-15>LANE REVERSAL20210527 MODIFY FOR GT
DP/DN SWAPDP/DN SWAPDP/DN SWAP
N/AFri Aug 25 14:02:00 2023V05N/AN/AN/A139 OF 312PCIE - CPU0_EXAMAX_P0/P4_X16
1441472931173312917317517517514629293131173173175292931311731731751751753117517517517517517317317317317317331313131312929292929291461461751752917317317531175312917317331312929PRSNT_CABLE_GPU_A3_NGPU_FPGA_OVERT_NP5E_CPU0_PE0_RX_DN<9>P5E_CPU0_PE4_RX_DN<6>P5E_CPU0_PE0_TX_C_DN<9>P5E_CPU0_PE4_RX_DP<6>P5E_CPU0_PE0_RX_DP<9>P5E_CPU0_PE0_TX_C_DP<9>P5E_CPU0_PE4_TX_C_DN<6>P5E_CPU0_PE4_TX_C_DP<6>P5E_CPU0_PE4_TX_C_DP<2>PRSNT_CABLE_GPU_A2_NP5E_CPU0_PE0_RX_DN<13>P5E_CPU0_PE0_RX_DP<13>P5E_CPU0_PE4_RX_DN<2>P5E_CPU0_PE4_RX_DP<2>P5E_CPU0_PE0_TX_C_DN<13>P5E_CPU0_PE0_TX_C_DP<13>P5E_CPU0_PE4_TX_C_DN<2>P5E_CPU0_PE0_RX_DN<14>P5E_CPU0_PE0_RX_DP<14>P5E_CPU0_PE4_RX_DP<1>P5E_CPU0_PE4_RX_DN<1>P5E_CPU0_PE0_TX_C_DN<14>P5E_CPU0_PE0_TX_C_DP<14>P5E_CPU0_PE4_TX_C_DP<1>P5E_CPU0_PE4_TX_C_DN<1>NC_J108_N4NC_J108_N2NC_J108_N6P5E_CPU0_PE4_TX_C_DP<7>P5E_CPU0_PE4_RX_DP<7>P5E_CPU0_PE4_TX_C_DP<4>P5E_CPU0_PE4_TX_C_DN<4>P5E_CPU0_PE4_TX_C_DP<5>P5E_CPU0_PE4_TX_C_DN<5>P5E_CPU0_PE4_TX_C_DN<7>P5E_CPU0_PE0_TX_C_DP<11>P5E_CPU0_PE0_TX_C_DN<11>P5E_CPU0_PE0_TX_C_DP<10>P5E_CPU0_PE0_TX_C_DP<8>P5E_CPU0_PE0_TX_C_DN<10>P5E_CPU0_PE0_TX_C_DN<8>P5E_CPU0_PE4_RX_DP<4>P5E_CPU0_PE4_RX_DN<4>P5E_CPU0_PE4_RX_DN<5>P5E_CPU0_PE4_RX_DN<7>P5E_CPU0_PE4_RX_DP<5>P5E_CPU0_PE0_RX_DN<11>P5E_CPU0_PE0_RX_DP<11>P5E_CPU0_PE0_RX_DP<10>P5E_CPU0_PE0_RX_DP<8>P5E_CPU0_PE0_RX_DN<10>P5E_CPU0_PE0_RX_DN<8>GPU_3V3IO_RSVD5_FFUIOTHLFGPU_3V3IO_RSVD3_FFUP5E_CPU0_PE4_TX_C_DP<3>P5E_CPU0_PE4_TX_C_DN<3>P5E_CPU0_PE0_RX_DP<15>P5E_CPU0_PE0_TX_C_DN<15>P5E_CPU0_PE0_TX_C_DP<15>P5E_CPU0_PE4_TX_C_DN<0>P5E_CPU0_PE4_RX_DN<0>P5E_CPU0_PE4_TX_C_DP<0>P5E_CPU0_PE4_RX_DP<0>P5E_CPU0_PE0_RX_DN<15>P5E_CPU0_PE0_TX_C_DP<12>P5E_CPU0_PE0_TX_C_DN<12>P5E_CPU0_PE4_RX_DP<3>P5E_CPU0_PE4_RX_DN<3>P5E_CPU0_PE0_RX_DP<12>P5E_CPU0_PE0_RX_DN<12>IOTHLF
N8
N7
N6
N5
M8
M7
M6
M5
L8
L7
L6
L5
K8
K7
K6
K5
J8
J7
J6
J5
I8
I7
I6
I5
H8
H7
H6
H5
G8
G7
G6
G5
F8
F7
F6
F5
E8
E7
E6
E5
D8
D7
D6
D5
C8
C7
C6
C5
B8
B7
B6
B5
A8
A7
A6
A5
N4
N3
N2
N1
M4
M3
M2
M1
L4
L3
L2
L1
K4
K3
K2
K1
J4
J3
J2
J1
I4
I3
I2
I1
H4
H3
H2
H1
G4
G3
G2
G1
F4
F3
F2
F1
E4
E3
E2
E1
D4
D3
D2
D1
C4
C3
C2
C1
B4
B3
B2
B1
A4
A3
A2
A1
J108 J108
1/2
NM
5
LKJC D E F G H IA B
6
7
8
N8
M8
N7
M7
N6
M6
N5
M5
L5
L6
L7
L8
K5
K6
K7
K8
J5
J6
J7
J8
I5
I6
I7
I8
H5
H6
H7
H8
G5
G6
G7
G8
F5
F6
F7
F8
E5
E6
E7
E8
D5
D6
D7
D8
C5
C6
C7
C8
B5
B6
B7
B8
A5
A6
A7
A8
2/2
NM
1
LKJC D E F G H IA B
2
3
4
N4
M4
N3
M3
N2
M2
N1
M1
L1
L2
L3
L4
K1
K2
K3
K4
J1
J2
J3
J4
I1
I2
I3
I4
H1
H2
H3
H4
G1
G2
G3
G4
F1
F2
F3
F4
E1
E2
E3
E4
D1
D2
D3
D4
C1
C2
C3
C4
B1
B2
B3
B4
A1
A2
A3
A4
SHEETDATE
DEPARTMENT
SIZE
PROJECT DOCUMENT NUMBER REV
REVIEWER
DESIGNER
123
7 3 2 1 6 5 4
E
A
B
C
E
D
C
B
A
7 6 5 4
D
OUT
OUT
OUT
OUT
OUT
OUT
OUTOUT
OUTOUT
ININ
OUT
OUTOUT
ININ
OUTOUT
ININ
OUT
ININ
OUTOUT
OUTOUT
ININ
OUT
ININ
OUT
OUT
OUT
OUT
ININ
IN
ININ
OUTOUT
OUT
ININ
OUT
ININ
IN
OUTOUT
OUTOUT
ININ
ININ
IN
OUTOUT
OUTOUT
ININ
ININ
IN
C



DP/DN SWAPDP/DN SWAPDP/DN SWAPDP/DN SWAPDP/DN SWAPDP/DN SWAPDP/DN SWAPDP/DN SWAPDP/DN SWAPDP/DN SWAPDP/DN SWAPDP/DN SWAPDP/DN SWAPDP/DN SWAPDP/DN SWAPDP/DN SWAP20210527 MODIFY FOR GT
DP/DN SWAPDP/DN SWAPDP/DN SWAPDP/DN SWAPDP/DN SWAP140 OF 312Fri Aug 25 14:02:01 2023N/A V05N/AN/AN/APCIE - CPU1_EXAMAX_P2/P3_X16
1761771776123461146616161146177176176146234177177616161611481771761776161177176611766161611771761766161147176176177177611771771761766161176176616117717761151616117617617761616161616161P5E_CPU1_PE2_TX_C_DP<1>P5E_CPU1_PE3_TX_C_DP<1>P5E_CPU1_PE3_TX_C_DN<1>P5E_CPU1_PE2_RX_DN<1>SMB_BMC_SWB_BUF_SDAP5E_CPU1_PE3_RX_DN<1>PRSNT_CABLE_GPU_B3_NP5E_CPU1_PE3_RX_DP<1>P5E_CPU1_PE2_RX_DP<1>P5E_CPU1_PE3_RX_DN<2>GPU_3V3IO_RSVD0_FFUP5E_CPU1_PE3_TX_C_DN<2>P5E_CPU1_PE2_TX_C_DP<2>P5E_CPU1_PE2_TX_C_DN<2>GPU_3V3IO_RSVD1_FFUSMB_BMC_SWB_BUF_SCLP5E_CPU1_PE3_TX_C_DP<5>P5E_CPU1_PE3_TX_C_DN<5>P5E_CPU1_PE2_RX_DN<5>P5E_CPU1_PE2_RX_DP<5>P5E_CPU1_PE3_RX_DN<5>P5E_CPU1_PE3_RX_DP<5>BIC_MONITERP5E_CPU1_PE3_TX_C_DP<2>P5E_CPU1_PE2_TX_C_DP<0>P5E_CPU1_PE3_TX_C_DP<0>P5E_CPU1_PE2_RX_DN<0>P5E_CPU1_PE2_RX_DP<0>P5E_CPU1_PE3_TX_C_DN<0>P5E_CPU1_PE2_TX_C_DN<0>P5E_CPU1_PE3_RX_DP<0>P5E_CPU1_PE2_TX_C_DN<1>P5E_CPU1_PE3_RX_DP<2>P5E_CPU1_PE2_RX_DP<2>P5E_CPU1_PE2_RX_DN<2>P5E_CPU1_PE3_TX_C_DP<3>P5E_CPU1_PE2_TX_C_DP<3>P5E_CPU1_PE2_TX_C_DN<3>P5E_CPU1_PE2_RX_DP<3>P5E_CPU1_PE3_RX_DN<3>GPU_FPGA_EROT_FATALERR_NP5E_CPU1_PE2_TX_C_DN<6>P5E_CPU1_PE2_TX_C_DP<6>P5E_CPU1_PE3_TX_C_DP<6>P5E_CPU1_PE3_TX_C_DN<6>P5E_CPU1_PE2_RX_DN<6>P5E_CPU1_PE3_TX_C_DN<4>P5E_CPU1_PE3_TX_C_DP<4>P5E_CPU1_PE2_TX_C_DP<4>P5E_CPU1_PE2_TX_C_DN<4>P5E_CPU1_PE3_RX_DN<0>P5E_CPU1_PE3_RX_DP<3>P5E_CPU1_PE2_TX_C_DP<5>P5E_CPU1_PE2_TX_C_DN<5>P5E_CPU1_PE2_RX_DN<4>P5E_CPU1_PE3_RX_DN<4>P5E_CPU1_PE3_TX_C_DN<3>P5E_CPU1_PE3_TX_C_DN<7>P5E_CPU1_PE2_RX_DP<6>BMC_MONITER_BUFP5E_CPU1_PE3_RX_DP<7>P5E_CPU1_PE2_RX_DP<7>P5E_CPU1_PE2_TX_C_DP<7>P5E_CPU1_PE2_TX_C_DN<7>P5E_CPU1_PE3_TX_C_DP<7>P5E_CPU1_PE2_RX_DN<7>P5E_CPU1_PE3_RX_DN<7>P5E_CPU1_PE3_RX_DN<6>P5E_CPU1_PE3_RX_DP<6>P5E_CPU1_PE2_RX_DP<4>P5E_CPU1_PE3_RX_DP<4>IOTHLFIOTHLF
P5E_CPU1_PE2_RX_DN<3>
N8
N7
N6
N5
M8
M7
M6
M5
L8
L7
L6
L5
K8
K7
K6
K5
J8
J7
J6
J5
I8
I7
I6
I5
H8
H7
H6
H5
G8
G7
G6
G5
F8
F7
F6
F5
E8
E7
E6
E5
D8
D7
D6
D5
C8
C7
C6
C5
B8
B7
B6
B5
A8
A7
A6
A5
N4
N3
N2
N1
M4
M3
M2
M1
L4
L3
L2
L1
K4
K3
K2
K1
J4
J3
J2
J1
I4
I3
I2
I1
H4
H3
H2
H1
G4
G3
G2
G1
F4
F3
F2
F1
E4
E3
E2
E1
D4
D3
D2
D1
C4
C3
C2
C1
B4
B3
B2
B1
A4
A3
A2
A1
J109
J109
1/2
NM
5
LKJC D E F G H IA B
6
7
8
N8
M8
N7
M7
N6
M6
N5
M5
L5
L6
L7
L8
K5
K6
K7
K8
J5
J6
J7
J8
I5
I6
I7
I8
H5
H6
H7
H8
G5
G6
G7
G8
F5
F6
F7
F8
E5
E6
E7
E8
D5
D6
D7
D8
C5
C6
C7
C8
B5
B6
B7
B8
A5
A6
A7
A8 2/2
NM
1
LKJC D E F G H IA B
2
3
4
N4
M4
N3
M3
N2
M2
N1
M1
L1
L2
L3
L4
K1
K2
K3
K4
J1
J2
J3
J4
I1
I2
I3
I4
H1
H2
H3
H4
G1
G2
G3
G4
F1
F2
F3
F4
E1
E2
E3
E4
D1
D2
D3
D4
C1
C2
C3
C4
B1
B2
B3
B4
A1
A2
A3
A4
SHEETDATE
DEPARTMENT
SIZE
PROJECT DOCUMENT NUMBER REV
REVIEWER
DESIGNER
123
7 3 2 1 6 5 4
E
A
B
C
E
D
C
B
A
7 6 5 4
D
OUT
OUT
OUT
IN
BI
OUT
OUT
INOUT
OUTOUT
OUTOUT
IN
IN
OUT
IN
IN
OUTOUT
OUTOUT
ININ
OUT
ININ
OUTOUT
OUTOUT
ININ
OUT
ININ
OUTOUT
OUTOUT
ININ
IN
ININ
OUTOUT
OUTOUT
ININ
ININ
IN
OUTOUT
OUTOUT
IN
ININ
IN
IN
OUTOUT
OUTOUT
ININ
ININ
IN
C



DP/DN SWAPDP/DN SWAPDP/DN SWAPDP/DN SWAPDP/DN SWAPDP/DN SWAPDP/DN SWAPDP/DN SWAPDP/DN SWAPDP/DN SWAPDP/DN SWAPDP/DN SWAP20210527 MODIFY FOR GTDP/DN SWAPDP/DN SWAPDP/DN SWAPDP/DN SWAPDP/DN SWAPDP/DN SWAPDP/DN SWAP
141 OF 312Fri Aug 25 14:02:02 2023N/AN/AN/AN/AV05PCIE - CPU1_EXAMAX_P2/P3_X161476161616117761616114761177148176176177176611771761766161611761761771776161616115014917617617717761616161176176177177611776117717761611486161616161177611771771496161150176176176176176GPU_BASE_HMC_READYP5E_CPU1_PE3_RX_DN<11>P5E_CPU1_PE3_RX_DP<11>P5E_CPU1_PE2_RX_DP<11>P5E_CPU1_PE2_RX_DN<11>P5E_CPU1_PE3_TX_C_DN<11>P5E_CPU1_PE3_RX_DN<13>P5E_CPU1_PE2_RX_DP<13>P5E_CPU1_PE3_RX_DP<13>GPU_HMC_PRSNT_NP5E_CPU1_PE2_RX_DN<13>P5E_CPU1_PE3_TX_C_DN<13>FM_SMB_1_ALERT_GPU_NP5E_CPU1_PE2_TX_C_DN<12>P5E_CPU1_PE2_TX_C_DP<12>P5E_CPU1_PE3_TX_C_DP<13>P5E_CPU1_PE2_TX_C_DP<8>P5E_CPU1_PE2_RX_DP<9>P5E_CPU1_PE3_TX_C_DN<9>P5E_CPU1_PE2_TX_C_DP<9>P5E_CPU1_PE2_TX_C_DN<9>P5E_CPU1_PE3_RX_DP<12>P5E_CPU1_PE3_RX_DN<12>P5E_CPU1_PE2_RX_DP<12>P5E_CPU1_PE2_TX_C_DN<15>P5E_CPU1_PE2_TX_C_DP<15>P5E_CPU1_PE3_TX_C_DN<15>P5E_CPU1_PE3_TX_C_DP<15>P5E_CPU1_PE2_RX_DP<15>P5E_CPU1_PE2_RX_DN<15>P5E_CPU1_PE3_RX_DP<15>P5E_CPU1_PE3_RX_DN<15>GPU_FPGA_EROT_RECOV_BUF_NGPU_FPGA_BOOT_EN_BUFP5E_CPU1_PE2_TX_C_DN<14>P5E_CPU1_PE2_TX_C_DP<14>P5E_CPU1_PE3_TX_C_DP<14>P5E_CPU1_PE3_TX_C_DN<14>P5E_CPU1_PE2_RX_DN<14>P5E_CPU1_PE2_RX_DP<14>P5E_CPU1_PE3_RX_DP<14>P5E_CPU1_PE3_RX_DN<14>P5E_CPU1_PE2_TX_C_DN<13>P5E_CPU1_PE2_TX_C_DP<13>P5E_CPU1_PE3_TX_C_DP<12>P5E_CPU1_PE3_TX_C_DN<12>P5E_CPU1_PE2_RX_DN<12>IOTHLF
P5E_CPU1_PE3_TX_C_DP<11>P5E_CPU1_PE3_RX_DN<8>THLFIOP5E_CPU1_PE3_TX_C_DP<10>P5E_CPU1_PE3_TX_C_DN<10>P5E_CPU1_PE3_RX_DP<8>P5E_CPU1_PE3_RX_DP<10>FM_SMB_2_ALERT_GPU_NP5E_CPU1_PE2_RX_DP<10>P5E_CPU1_PE2_RX_DN<10>P5E_CPU1_PE2_RX_DP<8>P5E_CPU1_PE3_RX_DN<10>P5E_CPU1_PE3_RX_DN<9>P5E_CPU1_PE3_TX_C_DP<8>P5E_CPU1_PE2_RX_DN<8>P5E_CPU1_PE3_TX_C_DN<8>P5E_CPU1_PE3_TX_C_DP<9>GPU_BASE_STBY_EN_BUFP5E_CPU1_PE3_RX_DP<9>P5E_CPU1_PE2_RX_DN<9>GPU_FPGA_EROT_RST_BUF_NP5E_CPU1_PE2_TX_C_DN<8>P5E_CPU1_PE2_TX_C_DP<10>P5E_CPU1_PE2_TX_C_DN<10>P5E_CPU1_PE2_TX_C_DP<11>P5E_CPU1_PE2_TX_C_DN<11>
N4
N3
N2
N1
M4
M3
M2
M1
L4
L3
L2
L1
K4
K3
K2
K1
J4
J3
J2
J1
I4
I3
I2
I1
H4
H3
H2
H1
G4
G3
G2
G1
F4
F3
F2
F1
E4
E3
E2
E1
D4
D3
D2
D1
C4
C3
C2
C1
B4
B3
B2
B1
A4
A3
A2
A1
N8
N7
N6
N5
M8
M7
M6
M5
L8
L7
L6
L5
K8
K7
K6
K5
J8
J7
J6
J5
I8
I7
I6
I5
H8
H7
H6
H5
G8
G7
G6
G5
F8
F7
F6
F5
E8
E7
E6
E5
D8
D7
D6
D5
C8
C7
C6
C5
B8
B7
B6
B5
A8
A7
A6
A5
J110
J110
2/2
NM
1
LKJC D E F G H IA B
2
3
4
N4
M4
N3
M3
N2
M2
N1
M1
L1
L2
L3
L4
K1
K2
K3
K4
J1
J2
J3
J4
I1
I2
I3
I4
H1
H2
H3
H4
G1
G2
G3
G4
F1
F2
F3
F4
E1
E2
E3
E4
D1
D2
D3
D4
C1
C2
C3
C4
B1
B2
B3
B4
A1
A2
A3
A4
1/2
NM
5
LKJC D E F G H IA B
6
7
8
N8
M8
N7
M7
N6
M6
N5
M5
L5
L6
L7
L8
K5
K6
K7
K8
J5
J6
J7
J8
I5
I6
I7
I8
H5
H6
H7
H8
G5
G6
G7
G8
F5
F6
F7
F8
E5
E6
E7
E8
D5
D6
D7
D8
C5
C6
C7
C8
B5
B6
B7
B8
A5
A6
A7
A8
SHEETDATE
DEPARTMENT
SIZE
PROJECT DOCUMENT NUMBER REV
REVIEWER
DESIGNER
123
7 3 2 1 6 5 4
E
A
B
C
E
D
C
B
A
7 6 5 4
D
OUT
OUT
IN
IN
IN
IN
OUT
OUT
OUT
OUTOUT
OUTOUT
IN
ININ
OUT
IN
OUTOUT
OUTOUT
ININ
IN
OUT
IN
OUTOUT
OUTOUT
IN
ININ
IN
IN
OUTOUT
OUT
ININ
OUT
IN
IN IN
OUTOUT
OUTOUT
ININ
ININ
OUT
OUTOUT
OUTOUT
ININ
ININ
OUT
IN
OUT
OUTOUT
ININ
ININ
IN
C



20210527 MODIFY FOR GTCPU1_PE4_TX/RX<0-15>LANE REVERSALDP/DN SWAPDP/DN SWAPDP/DN SWAPDP/DN SWAPDP/DN SWAPDP/DN SWAPDP/DN SWAPDP/DN SWAP
Fri Aug 25 14:02:03 2023N/A142 OF 312N/AN/AN/AV05PCIE - CPU1_EXAMAX_P0/P4_X161771761761771771771771771761766262606262151177176176177151147177177176176626014422760606262176176177177176176626260606060626260601442271442276262176176177177626217617617762606017714422760606060148P5E_CPU1_PE4_TX_C_DP<8>P5E_CPU1_PE0_TX_C_DP<7>P5E_CPU1_PE0_TX_C_DN<7>P5E_CPU1_PE4_TX_C_DN<8>P5E_CPU1_PE4_TX_C_DP<15>P5E_CPU1_PE4_TX_C_DN<15>P5E_CPU1_PE4_TX_C_DP<14>P5E_CPU1_PE4_TX_C_DN<14>P5E_CPU1_PE0_TX_C_DP<1>P5E_CPU1_PE0_TX_C_DN<1>P5E_CPU1_PE4_RX_DP<14>P5E_CPU1_PE4_RX_DN<14>P5E_CPU1_PE0_RX_DN<1>P5E_CPU1_PE4_RX_DP<10>P5E_CPU1_PE4_RX_DN<10>GPU_FPGA_RST_R_BUF_NP5E_CPU1_PE4_TX_C_DP<11>P5E_CPU1_PE0_TX_C_DN<4>P5E_CPU1_PE0_TX_C_DP<4>P5E_CPU1_PE4_TX_C_DN<11>FM_GPU_PWR_EN_R_BUFGPU_PRSNT_NP5E_CPU1_PE4_TX_C_DP<9>P5E_CPU1_PE4_TX_C_DN<9>P5E_CPU1_PE0_TX_C_DP<0>P5E_CPU1_PE0_TX_C_DN<0>P5E_CPU1_PE4_RX_DN<15>P5E_CPU1_PE0_RX_DP<1>GPU_PEX_STRAP1P5E_CPU1_PE0_RX_DN<7>P5E_CPU1_PE0_RX_DP<7>P5E_CPU1_PE4_RX_DN<11>P5E_CPU1_PE4_RX_DP<11>P5E_CPU1_PE0_TX_C_DN<5>P5E_CPU1_PE0_TX_C_DP<5>P5E_CPU1_PE4_TX_C_DN<10>P5E_CPU1_PE4_TX_C_DP<10>P5E_CPU1_PE0_TX_C_DP<6>P5E_CPU1_PE0_TX_C_DN<6>P5E_CPU1_PE4_RX_DN<9>P5E_CPU1_PE4_RX_DP<9>P5E_CPU1_PE0_RX_DN<0>P5E_CPU1_PE0_RX_DP<0>P5E_CPU1_PE0_RX_DP<3>P5E_CPU1_PE0_RX_DN<3>P5E_CPU1_PE4_RX_DP<15>P5E_CPU1_PE4_RX_DN<8>P5E_CPU1_PE0_RX_DP<5>P5E_CPU1_PE0_RX_DN<5>GPU_BASE_ID0GPU_BASE_ID1P5E_CPU1_PE4_RX_DP<13>P5E_CPU1_PE4_RX_DN<13>P5E_CPU1_PE0_TX_C_DN<2>P5E_CPU1_PE0_TX_C_DP<2>P5E_CPU1_PE4_TX_C_DN<13>P5E_CPU1_PE4_TX_C_DP<13>P5E_CPU1_PE4_RX_DN<12>P5E_CPU1_PE4_RX_DP<12>P5E_CPU1_PE0_TX_C_DN<3>P5E_CPU1_PE0_TX_C_DP<3>P5E_CPU1_PE4_TX_C_DN<12>P5E_CPU1_PE4_RX_DP<8>P5E_CPU1_PE0_RX_DP<6>P5E_CPU1_PE0_RX_DN<6>P5E_CPU1_PE4_TX_C_DP<12>GPU_PEX_STRAP0P5E_CPU1_PE0_RX_DN<2>P5E_CPU1_PE0_RX_DP<2>P5E_CPU1_PE0_RX_DP<4>P5E_CPU1_PE0_RX_DN<4>IOTHLFFM_GPU_PWRGDIOTHLF
N4
N3
N2
N1
M4
M3
M2
M1
L4
L3
L2
L1
K4
K3
K2
K1
J4
J3
J2
J1
I4
I3
I2
I1
H4
H3
H2
H1
G4
G3
G2
G1
F4
F3
F2
F1
E4
E3
E2
E1
D4
D3
D2
D1
C4
C3
C2
C1
B4
B3
B2
B1
A4
A3
A2
A1
N8
N7
N6
N5
M8
M7
M6
M5
L8
L7
L6
L5
K8
K7
K6
K5
J8
J7
J6
J5
I8
I7
I6
I5
H8
H7
H6
H5
G8
G7
G6
G5
F8
F7
F6
F5
E8
E7
E6
E5
D8
D7
D6
D5
C8
C7
C6
C5
B8
B7
B6
B5
A8
A7
A6
A5
J111J111
2/2
NM
1
LKJC D E F G H IA B
2
3
4
N4
M4
N3
M3
N2
M2
N1
M1
L1
L2
L3
L4
K1
K2
K3
K4
J1
J2
J3
J4
I1
I2
I3
I4
H1
H2
H3
H4
G1
G2
G3
G4
F1
F2
F3
F4
E1
E2
E3
E4
D1
D2
D3
D4
C1
C2
C3
C4
B1
B2
B3
B4
A1
A2
A3
A4
1/2
NM
5
LKJC D E F G H IA B
6
7
8
N8
M8
N7
M7
N6
M6
N5
M5
L5
L6
L7
L8
K5
K6
K7
K8
J5
J6
J7
J8
I5
I6
I7
I8
H5
H6
H7
H8
G5
G6
G7
G8
F5
F6
F7
F8
E5
E6
E7
E8
D5
D6
D7
D8
C5
C6
C7
C8
B5
B6
B7
B8
A5
A6
A7
A8
SHEETDATE
DEPARTMENT
SIZE
PROJECT DOCUMENT NUMBER REV
REVIEWER
DESIGNER
123
7 3 2 1 6 5 4
E
A
B
C
E
D
C
B
A
7 6 5 4
D
ININ
IN
ININ
OUTOUT
OUTOUT
ININ
ININ
OUT
OUTOUT
OUTOUT
OUT OUT
OUTOUT
OUTOUT
IN
ININ
OUT
IN
OUTOUT
OUTOUT
IN
ININ
IN
IN
OUTOUT
OUTOUT
ININ
ININ
OUT
OUTOUTOUT
IN
ININ
IN IN
IN
OUTOUT
OUT
IN
OUT
OUT
OUT
OUT
OUT
IN
OUT
IN
IN
OUT
IN
IN
C



DP/DN SWAPDP/DN SWAPDP/DN SWAP
DP/DN SWAP20210527 MODIFY FOR GT
DP/DN SWAPCPU1_PE4_TX/RX<0-15>LANE REVERSALDP/DN SWAPN/AN/AFri Aug 25 14:02:04 2023N/AN/AV05143 OF 312PCIE - CPU1_EXAMAX_P0/P4_X16
18118118114918160144606218160606262176181167167147149606062181602341502072072341441456262176176177177207207234234606062621761761771772122121481496060207207177177176626217617617717716718162176176177177606017617617717716760606262176176177177
62176176177177152152
626260P3E_PCH_NVS_TX_C_DN<1>P3E_PCH_NVS_TX_C_DN<0>P3E_PCH_NVS_RX_DP<1>RST_PERST_0_SWB_BUF_NP3E_PCH_NVS_TX_C_DP<0>P5E_CPU1_PE0_RX_DN<9>PRSNT_SWB_NP5E_CPU1_PE0_RX_DP<9>P5E_CPU1_PE4_RX_DN<6>P3E_PCH_NVS_TX_C_DP<1>P5E_CPU1_PE0_RX_DN<10>P5E_CPU1_PE0_RX_DP<10>P5E_CPU1_PE4_RX_DP<5>P5E_CPU1_PE4_RX_DN<5>P5E_CPU1_PE0_TX_C_DN<10>P3E_PCH_NVS_RX_DP<0>P2E_MB_BMC_TX_BUF_C_DN<0>P2E_MB_BMC_TX_BUF_C_DP<0>GPU_FPGA_THERM_OVERT_NRST_PERST_1_SWB_BUF_NP5E_CPU1_PE0_RX_DP<11>P5E_CPU1_PE0_RX_DN<11>P5E_CPU1_PE4_RX_DN<4>P3E_PCH_NVS_RX_DN<0>P5E_CPU1_PE0_RX_DN<13>SMB_1_BMC_GPU_BUF_SDAGPU_NVS_PWR_BRAKE_N_BUFCLK_100M_GPU_1_DNCLK_100M_GPU_1_DPSMB_1_BMC_GPU_BUF_SCLHGX_DETECT_N_ISOP5E_CPU1_PE4_RX_DN<2>P5E_CPU1_PE4_RX_DP<2>P5E_CPU1_PE0_TX_C_DN<13>P5E_CPU1_PE0_TX_C_DP<13>P5E_CPU1_PE4_TX_C_DN<2>P5E_CPU1_PE4_TX_C_DP<2>CLK_100M_SWB_DNCLK_100M_SWB_DPSMB_2_BMC_GPU_BUF_SCLSMB_2_BMC_GPU_BUF_SDAP5E_CPU1_PE0_RX_DN<14>P5E_CPU1_PE0_RX_DP<14>P5E_CPU1_PE4_RX_DP<1>P5E_CPU1_PE4_RX_DN<1>P5E_CPU1_PE0_TX_C_DN<14>P5E_CPU1_PE0_TX_C_DP<14>P5E_CPU1_PE4_TX_C_DP<1>P5E_CPU1_PE4_TX_C_DN<1>NC_J112_N2NC_J112_O2CLK_100M_GPU_FPGA_DNCLK_100M_GPU_FPGA_DPGPU_FPGA_READYRST_PERST_2_SWB_BUF_NP5E_CPU1_PE0_RX_DN<15>P5E_CPU1_PE0_RX_DP<15>CLK_100M_GPU_2_DPCLK_100M_GPU_2_DNP5E_CPU1_PE4_TX_C_DP<0>P5E_CPU1_PE4_TX_C_DN<0>P5E_CPU1_PE0_TX_C_DP<15>P5E_CPU1_PE4_RX_DN<0>P5E_CPU1_PE4_RX_DP<0>P5E_CPU1_PE0_TX_C_DN<15>P5E_CPU1_PE0_TX_C_DP<10>P5E_CPU1_PE4_TX_C_DN<5>P5E_CPU1_PE4_TX_C_DP<5>P2E_MB_BMC_RX_DP<0>P3E_PCH_NVS_RX_DN<1>P5E_CPU1_PE4_RX_DP<6>P5E_CPU1_PE0_TX_C_DN<9>P5E_CPU1_PE0_TX_C_DP<9>P5E_CPU1_PE4_TX_C_DP<6>P5E_CPU1_PE4_TX_C_DN<6>P5E_CPU1_PE0_RX_DP<12>
NC_J112_R5NC_J112_S5NC_J112_O5NC_J112_P5P5E_CPU1_PE0_RX_DP<13>P5E_CPU1_PE0_TX_C_DN<12>P5E_CPU1_PE0_TX_C_DP<12>P5E_CPU1_PE4_TX_C_DN<3>P5E_CPU1_PE4_TX_C_DP<3>P2E_MB_BMC_RX_DN<0>P5E_CPU1_PE0_RX_DP<8>P5E_CPU1_PE0_RX_DN<8>P5E_CPU1_PE4_RX_DP<7>P5E_CPU1_PE4_RX_DN<7>P5E_CPU1_PE0_TX_C_DP<8>P5E_CPU1_PE0_TX_C_DN<8>P5E_CPU1_PE4_TX_C_DN<7>P5E_CPU1_PE4_TX_C_DP<7>
P5E_CPU1_PE4_RX_DP<4>P5E_CPU1_PE0_TX_C_DN<11>P5E_CPU1_PE0_TX_C_DP<11>P5E_CPU1_PE4_TX_C_DP<4>P5E_CPU1_PE4_TX_C_DN<4>
THLFIO
USB2_HUB_BUF_SWB_DNUSB2_HUB_BUF_SWB_DP
P5E_CPU1_PE4_RX_DN<3>P5E_CPU1_PE4_RX_DP<3>P5E_CPU1_PE0_RX_DN<12>THLFIO
T4
T3
T2
T1
S4
S3
S2
S1
R4
R3
R2
R1
Q4
Q3
Q2
Q1
P4
P3
P2
P1
O4
O3
O2
O1
N4
N3
N2
N1
M4
M3
M2
M1
L4
L3
L2
L1
K4
K3
K2
K1
J4
J3
J2
J1
I4
I3
I2
I1
H4
H3
H2
H1
G4
G3
G2
G1
F4
F3
F2
F1
E4
E3
E2
E1
D4
D3
D2
D1
C4
C3
C2
C1
B4
B3
B2
B1
A4
A3
A2
A1
T8
T7
T6
T5
S8
S7
S6
S5
R8
R7
R6
R5
Q8
Q7
Q6
Q5
P8
P7
P6
P5
O8
O7
O6
O5
N8
N7
N6
N5
M8
M7
M6
M5
L8
L7
L6
L5
K8
K7
K6
K5
J8
J7
J6
J5
I8
I7
I6
I5
H8
H7
H6
H5
G8
G7
G6
G5
F8
F7
F6
F5
E8
E7
E6
E5
D8
D7
D6
D5
C8
C7
C6
C5
B8
B7
B6
B5
A8
A7
A6
A5
J112
J112
2/2
TSRQPONM
1
LKJC D E F G H IA B
2
3
4
T4
S4
R4
Q4
P4
O4
T3
S3
R3
Q3
P3
O3
T2
S2
R2
Q2
P2
O2
T1
S1
R1
Q1
P1
O1
N4
M4
N3
M3
N2
M2
N1
M1
L1
L2
L3
L4
K1
K2
K3
K4
J1
J2
J3
J4
I1
I2
I3
I4
H1
H2
H3
H4
G1
G2
G3
G4
F1
F2
F3
F4
E1
E2
E3
E4
D1
D2
D3
D4
C1
C2
C3
C4
B1
B2
B3
B4
A1
A2
A3
A4
1/2
TSRQPONM
5
LKJC D E F G H IA B
6
7
8
T8
S8
R8
Q8
P8
O8
T7
S7
R7
Q7
P7
O7
T6
S6
R6
Q6
P6
O6
T5
S5
R5
Q5
P5
O5
N8
M8
N7
M7
N6
M6
N5
M5
L5
L6
L7
L8
K5
K6
K7
K8
J5
J6
J7
J8
I5
I6
I7
I8
H5
H6
H7
H8
G5
G6
G7
G8
F5
F6
F7
F8
E5
E6
E7
E8
D5
D6
D7
D8
C5
C6
C7
C8
B5
B6
B7
B8
A5
A6
A7
A8
SHEETDATE
DEPARTMENT
SIZE
PROJECT DOCUMENT NUMBER REV
REVIEWER
DESIGNER
123
7 3 2 1 6 5 4
E
A
B
C
E
D
C
B
A
7 6 5 4
D
ININ
IN
OUT
IN
OUT
IN
IN
IN
IN
IN
ININ
IN
ININ
ININ
ININ
OUTOUT
ININ
ININ
IN
ININ
BIIN
BIIN
OUT
OUTOUT
OUTOUT
ININ
ININ
OUTOUT
OUTOUT
ININ
ININ
OUTOUT
OUTOUT
ININ
ININ
OUTOUT
OUTOUT
ININ
ININ
OUTOUT
OUTOUT
ININ
ININ
OUTOUT
OUTOUT
ININ
ININ
ININ
ININ
OUTOUT
OUTOUT
IN
IN
IN
IN
OUTOUT
OUTOUT
C



20220504 POP R3442,R3443
20210527 MODIFY FOR GT
Fri Aug 25 14:02:05 2023N/AN/AN/AN/AV05144 OF 312P3V3_AUXP3V3_AUXP3V3_AUXP3V3_AUXP3V3_AUXP3V3_AUX
P3V3_AUXP3V3_AUXP3V3_AUXP3V3_AUXP3V3_AUXP3V3_AUX
EXAMAX_PRESENT227139137227138142227142227142227142227145143
143215 227227
IC1/16W1/16WCHIP0402LF0402LFPRSNT_CABLE_GPU_A3_ISO_NSMLFPJT138KPJT138KPRSNT_CABLE_GPU_A3PRSNT_CABLE_GPU_A3_N100KPJT138KSMLFIC5%4.7KCHIPSMLFPRSNT_CABLE_SWB_B1_NPRSNT_CABLE_SWB_B1PRSNT_CABLE_SWB_B1_ISO_N100K1%1/16W0402LFEMPTY0402LFCHIP10K1/16W1%0402LF5%CHIP4.7K1/16WEMPTY1000PF5%040250V1/16W0402LFCHIP5%4.7KPJT138KSMLFICIC4.7K5%1/16W50V04025%1000PFEMPTY1%10KCHIP0402LFEMPTY0402LF1/16W1%
PRSNT_CABLE_SWB_B2_N0402LFPRSNT_CABLE_SWB_B2
5%00402LFCHIP 1/16W0402LF1/16WEMPTY1001%01/16WEMPTY5%0402LF0402LF0CHIP 1/16W5%1/16W5%CHIP0GPU_BASE_ID0GPU_BASE_ID1GPU_PEX_STRAP0GPU_PEX_STRAP10402LFHGX_DETECT_N_ISO
PRSNT_SWB_NPRSNT_SWBPRSNT_SWB_ISO_N100K1%1/16W0402LFEMPTY1/16W10K0402LF1%CHIPPJT138KICSMLF4.7KCHIP1/16W0402LF5%SMLFPJT138KIC4.7K1/16W0402LFCHIP5%EMPTY5%1000PF040250V1000PFEMPTY5%040250V4.7K1/16W0402LFCHIP5%ICSMLF1/16W5%CHIP4.7KICSMLF0402LFCHIP1/16W10K1%0402LF100K1%EMPTYPJT138KPRSNT_CABLE_SWB_B2_ISO_NPJT138K1/16W
G1
G2
G1
G2
G1
G1
G2
G2
D1S1S2 D2D1S1S2 D2D1S1D1S1S2 D2S2 D2
R4800
R4801
R4739
R4740
R4732
R4725
R4733
R4726
R3441
R3442
R2656
R3440
R3443
2
5
2
5
2
2
5
5
1 64 31 64 31 61 64 34 3
Q154
Q154
Q153
Q153
Q152
Q151
Q152
Q151
2
1
2
1
2
1
2
1
2
1
2
1
2
1
2
1 2
1
2
1
2
1
2
1
2
1
2
1
2
1
2
1
2
1
2
1
2
1
2
1
21
21
21
21
21
SHEETDATE
DEPARTMENT
SIZE
PROJECT DOCUMENT NUMBER REV
REVIEWER
DESIGNER
123
7 3 2 1 6 5 4
E
A
B
C
E
D
C
B
A
7 6 5 4
D
OUT
IN
OUT
IN
OUT
IN
IN
OUT
OUT
OUT
OUT
OUT
OUT
R4799
R4798 C2391
R4738
R4737 C2374
R4731
R4730
R4724
R4727
C2373
C2372
C



PUSH-PULL OUTPUT
20220802 CHANGE TO Q148
20211130 CHANGE FOR GPU/BD RSVD PIN20220105 CHANGE PIN3 CONNECT TO GND
Fri Aug 25 14:02:06 2023N/AN/AN/AN/AV05145 OF 312P3V3_AUXP3V3_AUXP3V3_AUXP3V3_AUX
P3V3_AUXP3V3_AUX
P3V3_AUXP3V3_AUXP3V3_AUXP3V3_AUX
P3V3_AUXP3V3_AUXP3V3_AUXP3V3_AUXP3V3_AUX
EXAMAX_ISO (1/7)144 143215
215215215215136136 138
1365%1000PFSMLFGPU_3V3IO_RSVD4_N0402LFCHIP1/16W5%ICGPU_3V3IO_RSVD1_N1/16W5%1/16WEMPTYGPU_3V3IO_RSVD3_NPJT138K1/16W5%PJT138KEMPTY50V04021/16W0402LFEMPTYHGX_DETECT_N_ISO4.7K5%SMLFPJT138KIC4.7KCHIP1/16W5%0402LFSMLFPJT138KHGX_DETECTICHGX_DETECT_N0402LF4.7K5%1/16WCHIP0402LF1%100K1/16WEMPTYEMPTYGPU_3V3IO_RSVD1_ISOGPU_3V3IO_RSVD3_ISO4.7K1/16W0402LFCHIP5%1000PFNC_U316_2YSWB_HSC_EN0402LF1%1/16W100KSMLFPJT138KIC0402EMPTY100K1%0402X7R1/16W5%4.7KSMLF1/16WEMPTY0402LF1%100K1/16W54.9K1%1/16WEMPTY4.7KSMLF0402ICSMLFCHIPSMLF1%5%5%4.7K1%1%EMPTY50VEMPTY50V5%IC0402LFPJT138K0402LFPJT138K50V5%EMPTY0402LF5%0402LFEMPTY1/16WIC54.9K1/16WEMPTY0402LF4.7K4.7K100K54.9K1/16W0402LF4.7KCHIP1/16W100K1%EMPTY25V0.1UF0402LF005%GPU_3V3IO_RSVD4_ISO0402LF1/16WEMPTY1/16W05%GPU_3V3IO_RSVD10402LFCHIP0402LFSMLFPJT138KCHIP0402LFGPU_3V3IO_RSVD3CHIPEMPTY1/16WEMPTY1000PF1000PF10%0402LFSWB_HSC_EN_BUF_R0402LFEMPTY1/16WCHIPSWB_HSC_EN_BUF49.94.7K5%0402LF5%1/16WIC0402IC74LVC2G17GW0402LFGPU_3V3IO_RSVD4
G1
G2
G2
G2
G1
G2
G1
G1
D1S1S2 D2 S2 D2S2 D2D1S1S2 D2D1S1D1S1
R4550
R4549
R4545
R4546
R4167
R4169
R4168
R4164
R4166
R4165
4
6
3
1
2
5
5
5
2
5
2
2
52
1 64 3 4 34 31 64 31 61 6
U316
Q148
Q148
Q135
Q137
Q135
Q136
Q137
Q136
B0
A1
A0
B1
GND VCC
21
21R4570
21R4571
21R4569
2
1
2
1
2
1C2341
2
1
2
1
2
1
2
1
2
1
2
1
2
1
2
1
2
1
2
1
2
1
2
1
2
1
2
1
2
1
2
1
2
1
2
1
2
1
2
1
2
1
2
1
SHEETDATE
DEPARTMENT
SIZE
PROJECT DOCUMENT NUMBER REV
REVIEWER
DESIGNER
123
7 3 2 1 6 5 4
E
A
B
C
E
D
C
B
A
7 6 5 4
D
OUTIN
IN
OUT
IN
OUT
OUT
OUT
IN
IN
R4555
R4547
R4548
R4543
R4544
C2340
C2271
C2273
C2272
R4158
R4159
R4162
R4163
R4160
R4161
C



20220802 CHANGE R4135 TO 10K OHM
20220802 CHANGE R4153 TO 10K OHM20220802 CHANGE R4121 TO 10K OHM20220103 ADD SWB_HSC_PWRGD
20211130 CHANGE FOR GPU/BD RSVD PIN
Fri Aug 25 14:02:07 2023N/AN/AN/A146 OF 312V05N/A
P3V3_AUX
P3V3_AUXP3V3_AUXP3V3_AUXP3V3_AUXP3V3_AUXP3V3_AUXP3V3_AUXP3V3_AUXP3V3_AUXP3V3_AUXP3V3_AUXP3V3_AUXP3V3_AUXP3V3_AUXP3V3_AUXP3V3_AUXP3V3_AUXP3V3_AUXP3V3_AUXP3V3_AUXP3V3_AUXP3V3_AUXP3V3_AUX
EXAMAX_ISO (2/7)
215139139139140137
215140140 215215
138215215 227215 227
215 227
0402LFGPU_3V3IO_RSVD0_FFU_ISOGPU_3V3IO_RSVD3_FFUPRSNT_CABLE_GPU_A2_N1/16WEMPTY0402LFGPU_3V3IO_RSVD5_FFU4.7K0402LF1/16W1%PRSNT_CABLE_GPU_B3_NPJT138KPRSNT_CABLE_GPU_B35%EMPTY5%PRSNT_CABLE_GPU_A1_N00402LF 1/16W5%PRSNT_CABLE_GPU_A1PJT138KIC4.7KPJT138KEMPTY0402LFCHIP1/16WPJT138K0402LFPJT138KSMLF1/16W0GPU_3V3IO_RSVD5_FFU_NSMLFPJT138KICCHIP4.7KEMPTY0402LFGPU_3V3IO_RSVD3_FFU_NEMPTY5%0402LF 1/16W
SMLF4.7K5%
4.7KGPU_3V3IO_RSVD0_FFU_N0402LFCHIP1/16W1/16W5%
1%CHIPCHIP1%EMPTY1/16W100K50V5%100KEMPTY1%1%5%0402LF1/16WCHIPPJT138KSMLFICEMPTY1000PF04025%50V4.7K5%0402LF1/16WCHIP5%04021000PFCHIP0402LFCHIPCHIPCHIPCHIPCHIPCHIPICPJT138K1000PF1/16WSMLF5%0402LF0402LFICICICICIC
4.7K
1% 4.7K0402LFEMPTY100K5%1/16W5%0402LF1/16WPJT138KSMLF1/16WEMPTY0402LFEMPTY5%1/16W4.7K4.7K5%4.7K5%
04021000PF50VEMPTY1/16W5%1/16W4.7K5%54.9K1%0402LFEMPTY1/16W5%5%4.7K0402LF1%1/16W1%100K1/16W
1/16WEMPTY0402LF100K1%1/16W0402LF100K1%100K1%1000PF50V
GPU_3V3IO_RSVD3_FFU_ISOEMPTY0402LF1/16W1%54.9KEMPTY5%50V1000PF040250V040204021000PF50V5%EMPTY04021000PF50V5%EMPTY54.9K1%54.9K4.7K0402LF5%4.7K0402LFSMLFPJT138K0402LF1/16WEMPTY5%SWB_HSC_PWRGD_NSMLFICPJT138K1/16WIC
SMLFPJT138K4.7KSMLFICGPU_3V3IO_RSVD0_FFU1/16WEMPTYSMLFGPU_3V3IO_RSVD1_FFU05%0EMPTYICGPU_3V3IO_RSVD5_FFU_ISO0402LFEMPTY00402LFEMPTY1/16W05%EMPTY00402LFGPU_3V3IO_RSVD1_FFU_ISO0402LFEMPTYIC
SMLF1/16WGPU_3V3IO_RSVD1_FFU_N0402LF1/16W1/16WCHIP1/16W0402LFSMLFIC100KCHIP5%0402LFCHIPEMPTY04025%PJT138K1/16WSWB_HSC_PWRGD1/16W0402LF100K0402LFSWB_HSC_PWRGD_ISOICPJT138KSMLFPRSNT_CABLE_GPU_B3_ISO_N1/16W1/16W10K1/16W0402LFCHIP1%PJT138K0402LFEMPTYSMLFPRSNT_CABLE_GPU_A20402LFSMLFPJT138K1/16W5%PRSNT_CABLE_GPU_A2_ISO_N
PRSNT_CABLE_GPU_A1_ISO_NCHIP0402LF10KCHIP0402LF1/16W1%10K
G1
G1
G1
G2
G1
G2
G2
G2
G1
G2
G1
G2
G1
G2
G1
G2
D1S1
D1S1D1S1S2 D2D1S1S2 D2S2 D2
S2 D2D1S1S2 D2D1S1S2 D2
D1S1S2 D2
D1S1S2 D2
R4560
R4561
R4156
R4155
R4138
R4139
R4137
R4141
R4142
R4140
R4126
R4129
R4127
R4130
R4125
R4128
2
5
5
2
2
2
5
2
5
5
2
5
2
5
2
5
1 64 3
4 31 6
1 61 64 31 64 34 3
1 64 31 64 31 64 3
Q146
Q146
Q134
Q134
Q129
Q133
Q129
Q130
Q133
Q130
Q132
Q132
Q131
Q131
Q128
Q128
2
1
2
1
2
1
21R4575
21R4572
21R4573
21R4576
21R4578
21R4577
21R4574
2
1
2
1
2
1
2
1
2
1
2
1
2
1
2
1
2
1
2
1
2
1
2
1
2
1
2
1
2
1
2
1
2
1
2
1
2
1
2
1
2
1
2
1
2
1
2
1
2
1
2
1
2
1
2
1
2
1
2
1
2
1
2
1
2
1
2
1
2
1 2
1
2
1
SHEETDATE
DEPARTMENT
SIZE
PROJECT DOCUMENT NUMBER REV
REVIEWER
DESIGNER
123
7 3 2 1 6 5 4
E
A
B
C
E
D
C
B
A
7 6 5 4
D
IN
IN
IN
OUT
OUT
OUT
IN
OUT
IN
OUT
IN
IN
OUT
IN
OUT
OUT
R4153
R4135
R4121
R4562
R4559
C2343
R4154
C2270
R4134
R4133
R4136
R4132
R4131
C2268
C2269
C2267
R4122
C2265
R4124
R4123 C2266
R4120
R4119 C2264
C



20220802 CHANGE TO Q10820220802 CHANGE TO Q107
Fri Aug 25 14:02:08 2023V05147 OF 312N/AN/AN/AN/A
P3V3_AUXP3V3_AUXP3V3_AUXP3V3_AUXP3V3_AUXP3V3_AUXP3V3_AUXP3V3_AUXP3V3_AUXP3V3_AUXP3V3_AUXP3V3_AUXP3V3_AUXP3V3_AUX
P3V3_AUXP3V3_AUX
P3V3_AUXP3V3_AUXP3V3_AUX
EXAMAX_ISO (3/7)213140142141
213
139141143 246 213227213136213213
213CHIP0402LFICGPU_FPGA_EROT_FATALERR_ISO_N1000PF1/16WCHIP0402LFSMLFPJT138K5%GPU_FPGA_EROT_FATALERR_N1/16WPJT138KGPU_FPGA_EROT_FATALERRICGPU_PRSNT_N0402LFPJT138KSMLF54.9KGPU_HMC_PRSNT_N1/16W0402LF1%10K1/16WCHIPGPU_WP_HW_CTRL_N100K1%1/16WEMPTYEMPTY1%100K0402LF4.7K0402LF100K1%1/16WEMPTYSMLFGPU_FPGA_OVERT_N1%100KEMPTY1/16W0402LF0402LF1/16W1%54.9KCHIPGPU_BASE_HMC_READY0402LF1/16WEMPTY100K1%GPU_FPGA_THERM_OVERT_N0402GPU_PRSNTGPU_PRSNT_N_ISO0402LF0402LFICSMLF54.9K1%CHIP1/16W0402LF1/16WCHIP1%54.9K0402LF10K1/16WCHIP1%5%4.7K1/16W1/16WCHIP0402LF4.7K5%5%50V1000PF0402EMPTYPJT138KSMLFICEMPTY040250V5%4.7K1/16W4.7K5%CHIP0402LFGPU_BASE_HMC_READY_NSMLFPJT138KPJT138K
CHIP1%1/16W0402LFICGPU_HMC_PRSNT1/16WCHIP0402LF 1000PF1/16W0402LFGPU_BASE_HMC_READY_ISO4.7K5%1/16WSMLF0402EMPTY0402LF0402LF1/16W
GPU_WP_HW_CTRL_ISO10K1%0402LFEMPTY1/16W05%0402LFEMPTYICPJT138KSMLF5%1/16WGPU_HMC_PRSNT_ISO_N50V1000PFGPU_FPGA_OVERTGPU_FPGA_OVERT_ISO_NICPJT138K0402LF5%4.7KCHIP1/16WPJT138KSMLFICCHIP5%5%50V1000PF0402EMPTYPJT138K0402EMPTYGPU_FPGA_THERM_OVERT_ISO_NSMLFPJT138KEMPTY5%50V1000PF0402LF
1%10KCHIPPJT138KSMLF4.7K5%ICICCHIP4.7K1/16W5%0402LFGPU_FPGA_THERM_OVERTICICSMLF0402LFCHIPPJT138KSMLF5%4.7KCHIPCHIPCHIP
EMPTY0402LF100K1%1/16WIC5%1/16W4.7K4.7K5%50V5%
G2
G1
G2
G2
G1
G1
G2
G1
G1
G2
G1
G2
G1
S2 D2D1S1S2 D2S2 D2D1S1D1S1S2 D2D1S1
D1S1S2 D2D1S1S2 D2D1S1
R3503
C1988
R3474
C1978
C1975
R3439
R3438
R3432
R3433
R3434
C1976
R3435
2
5
2
5
2
5
2
5
5
2
2
5
2
1 64 31 64 31 6
4 31 64 34 31 61 64 31 6
Q108
Q108
Q107
Q107
Q106
Q101
Q101
Q102
Q103
Q102
Q103
Q104
Q104
2
1
2
1
2
1
2
1
2
1
2
1
2
1
2
1
2
1
2
1
2
1
R3472
2
1
2
1
2
1
2
1
2
1
2
1
2
1
2
1
2
1
2
1
2
1
2
1
2
1
2
1
2
1
2
1
2
1
2
1
2
1
2
1
2
1
21
SHEETDATE
DEPARTMENT
SIZE
PROJECT DOCUMENT NUMBER REV
REVIEWER
DESIGNER
123
7 3 2 1 6 5 4
E
A
B
C
E
D
C
B
A
7 6 5 4
D
OUT
OUT
OUT
IN
OUT
OUT
IN
IN
OUT
IN
OUT
OUT
IN
IN
IN
R3525
R3502
R3504
R3498
R3487
R3473
R3475
R3470
R3471
R3464
R3431
R3465
R3463
R3429
C1974
C1973
R3436
R3437
R3428
R3430
C



20211230 DEPOP R2837,POP R283820210527 MODIFY FOR GT
Fri Aug 25 14:02:09 2023N/A V05148 OF 312N/AN/AN/A
P3V3_AUXP3V3_AUXP3V3_AUXP3V3_AUXP3V3_AUXP3V3_AUXP3V3_AUXP3V3_AUXP3V3_AUXP3V3_AUXP3V3_AUXP3V3_AUXP3V3_AUXP3V3_AUXP3V3_AUXP3V3_AUXP3V3_AUXP3V3_AUXP3V3_AUXP3V3_AUXP3V3_AUXP3V3_AUXP3V3_AUX
P3V3_AUX
EXAMAX_ISO (4/7)
137213213213
212213214140136143141142
141213136214213FM_SWB_PWRGD4.7KBIC_MONITER_ISO1000PF
SMLF
BIC_MONITER_NPJT138KSMLFSMLFPJT138KFM_GPU_PWRGD_ISOFM_SWB_PWRGD_ISO0402LF
0402SMLFPJT138K0402LFFM_SMB_2_ALERT_GPU50VSMLFGPU_FPGA_READY_N1/16WCHIPEMPTY
RST_BMC_FROM_SWBICFM_GPU_PWRGD_N4.7KIC1000PFPJT138KSMLF5%ICEMPTY5%0402IC 5%CHIP4.7K5%CHIP1/16WICPJT138KSMLFICSMLF1/16W5%0402LFICSMLF1/16WCHIPPJT138K1/16WCHIPICICIC040250V5%4.7K0402LF5%CHIP5% 040250V0402EMPTY50V1000PF5%5%4.7K4.7K5%04025%50V1000PFEMPTY0402LF1/16WCHIP4.7K5%5%CHIP1/16W5%4.7K0402LFEMPTY5%5%4.7K100K1%
IC50V4.7K0402LFPJT138KICICPJT138K1/16W0402LFSMLFGPU_FPGA_READY_ISO5%FM_SMB_2_ALERT_GPU_ISO_N0402LF5%100KEMPTY
1%100KEMPTY0402LFEMPTY1%1/16W0402LF0402LFCHIP1%54.9K1/16WCHIP1/16WPJT138KCHIP0402LFSMLFSMLFIC1/16WCHIP0402LFSMLFPJT138KPJT138K1/16WCHIP0402LF1000PF5%0402EMPTYPJT138K0402EMPTY5%4.7K4.7K4.7K5%PJT138K100KCHIP1%1/16W0402LFFM_SMB_1_ALERT_GPU0402LF4.7KSMLFICIC1000PF1/16W1/16W54.9K1%50V1/16WCHIPSMLF1000PF5%PJT138KPJT138KBIC_MONITER0402LF1/16WEMPTY1%100KRST_BMC_FROM_SWB_N100K1%0402LFEMPTY1/16WSMLFPJT138K0402LF1%EMPTY50VGPU_FPGA_READY54.9KCHIP0402LF1/16W1%100KFM_SMB_2_ALERT_GPU_N1%1/16WEMPTY0402LFFM_GPU_PWRGD0402LFCHIP1/16W1%FM_SMB_1_ALERT_GPU_NCHIP0402LF100K1/16WCHIP1/16W1/16WCHIP100K1%1/16WEMPTY1/16W1%100K0402LFFM_SWB_BIC_READY0402LFFM_SWB_BIC_READY_ISO_N0402LFCHIP0402LFFM_SWB_BIC_READY_N1000PFFM_SMB_1_ALERT_GPU_ISO_N1/16W4.7K
1%0402LF100K4.7K5%FM_SWB_PWRGD_NCHIP1/16W0402LF1%54.9KRST_BMC_FROM_SWB_ISO_N100K1/16WEMPTY0402LF1/16WCHIP0402LFCHIP1/16W
G2
G2
G1
G1
G1
G2
G1
G1
G2
G2
G1
G2
G2
G1
G1
G2
S2 D2S2 D2
D1S1
D1S1D1S1
S2 D2D1S1
D1S1S2 D2
S2 D2D1S1
S2 D2
S2 D2D1S1
D1S1
S2 D2
R3320
C1881
C1802
R3029
R3034
C1804
C1756
C1754
R2919
R2920
R2842
R2841
R2836
R2834
R2835
2
5
2
5
5
2
5
5
2
2
5
5
5
2
2
2
1 64 3
1 64 3
4 31 6
4 3
4 31 6
1 6
4 3
4 34 3
1 6
1 61 6
Q96
Q96
Q75
Q75
Q74
Q74
Q70
Q72
Q71
Q69
Q71
Q69
Q67
Q72
Q70
Q67
2
1
2
1
2
1
2
1
2
1
2
1
2
1
2
1
2
1
2
1
2
1
2
1
2
1
2
1
2
1
2
1
2
1
2
1
2
1
2
1
2
1
2
1
2
1
2
1
2
1
2
1
2
1
2
1
2
1
2
1
2
1
2
1
2
1
2
1
2
1
2
1
2
1
2
1
2
1
2
1
SHEETDATE
DEPARTMENT
SIZE
PROJECT DOCUMENT NUMBER REV
REVIEWER
DESIGNER
123
7 3 2 1 6 5 4
E
A
B
C
E
D
C
B
A
7 6 5 4
D
OUT
OUT
OUT
OUT
IN
IN
IN
IN
IN
OUT
IN
OUT
OUT
IN
IN
OUT
OUT
R3510
R3514
R3512
R3513
R3511
R3318
R3321
R3030
R3028
R3032
R3035
C1772
C1773
C1774
R2935
R2934
R2933
R2837
R2830
R2832
R2828
R2838
R2833
R2829
R2831
C



2021014 MODIFY FOR GT
PUSH-PULL OUTPUTPUSH-PULL OUTPUT
PUSH-PULL OUTPUT
Fri Aug 25 14:02:11 2023N/AN/AN/AN/A149 OF 312V05
P3V3_AUX
P3V3_AUX
P3V3_AUXP3V3_AUXP3V3_AUXP3V3_AUX
P3V3_AUXP3V3_AUXP3V3_AUX
EXAMAX_ISO (5/7)
141141143143143136213
213213223GPU_FPGA_BOOT_EN_BUFCHIP0402GPU_FPGA_BOOT_EN_BUF_R49.90402LFGPU_BASE_STBY_EN_BUFCHIP49.90402LF0402LFRST_PERST_0_SWB_BUF_NRST_PERST_1_SWB_BUF_N49.9CHIPCHIP49.9CHIPRST_PERST_2_SWB_BUF_NFM_SWB_PWR_EN_R_BUF49.9CHIPFM_SWB_PWR_EN_R1_BUF1/16W49.9CHIP5%1/16WEMPTY0402LF4.7K1/16WRST_PERST_2_SWB_BUF_R_N0402LFCHIP5%4.7K1/16W0402LF5%CHIP4.7KFM_SWB_PWR_EN_RSMLF
1/16W100K1%CHIP0402LFGPU_BASE_STBY_EN1/16W0402LF1%CHIP100KGPU_FPGA_BOOT_ENIC74LVC2G17GWSMLF
74LVC2G17GW1%ICRST_PERST_0_SWB_BUF_R_N0.1UFRST_PERST_1_SWB_BUF_R_N74LVC2G17GWSMLFIC25V040210%X7RGPU_BASE_STBY_EN_BUF_R1/16W1%100KCHIP0402LFCHIP1/16W1%04020402LFRST_PERST_SWB_R_N100K1/16W0402LFEMPTY10K0402LF1%CHIP
5%1/16WEMPTY4.7K4.7KEMPTY0402LF1/16W5%
25V10%X7R0.1UF0402LF10K1%0402LF1/16W10K1/16WCHIP1%10K100K1%1/16WEMPTY1%1K1/16W10%X7R25V0.1UFEMPTY
R3392
R3390
R3391
R3469
R3515
R3468
R2914
R2918
4
6
3
1
4
6
3
1
4
6
3
1
52 52 52
U256
U252
U253
B0
A1
A0
B1
B0
A1
A0
B1
B0
A1
A0
B1 GND VCCGND VCCGND VCC
21
21
21
21
21
21
2
1
2
1
2
1
2
1
2
1
2
1
2
1C1977
2
1
2
1
2
1
2
1
2
1C1957
2
1
2
1
2
1
2
12
1
2
1C1958
SHEETDATE
DEPARTMENT
SIZE
PROJECT DOCUMENT NUMBER REV
REVIEWER
DESIGNER
123
7 3 2 1 6 5 4
E
A
B
C
E
D
C
B
A
7 6 5 4
D
OUT
OUT
IN
OUT
IN
OUT
IN
IN OUT
OUT
R2932
R2910 R3466
R3467
R3449
R3448
R3454
R3453
R3455
R3451
R3456
R3457
R3452
C



20220105 CHANGE PIN3 CONNECT TO GNDOPEN-DRAIN OUTPUTOPEN-DRAIN OUTPUT20210603 MODIFY FOR GT
Fri Aug 25 14:02:12 2023N/AN/AN/AN/AV05150 OF 312P3V3_AUXP3V3_AUXP3V3_AUXP3V3_AUXP3V3_AUXP3V3_AUXP3V3_AUXP3V3_AUX
EXAMAX_ISO (6/7)
213213213141141143EMPTY1%GPU_FPGA_EROT_RECOV_NICSMLF74LVC2G07DW-7GPU_FPGA_EROT_RST_BUF_R_N54.9KX7R0402LFCHIP0402LFEMPTY0402LF1/16W1%100K0402LFCHIP1%100K1/16W0402LFEMPTYGPU_FPGA_EROT_RST_NEMPTY0402LF1/16W100K1%GPU_NVS_PWR_BRAKE_N
NC_U257_2YIC74LVC2G07DW-74.7KGPU_FPGA_EROT_RECOV_BUF_NGPU_FPGA_EROT_RST_BUF_NGPU_NVS_PWR_BRAKE_N_BUFGPU_FPGA_EROT_RECOV_BUF_R_NGPU_NVS_PWR_BRAKE_N_RCHIP1/16W5%0402LF0402LFCHIP5%4.7K1/16W10%0.1UF25VX7R0402SMLF1/16W0402LF100KCHIP0402LF33.2CHIP1/16W1%0402LFEMPTY100K1%1/16W100K1%1/16WEMPTY0402LF1%54.9K1/16W33.24.7K5%1/16WCHIP0402LF0402LFCHIP1%54.9K1/16WCHIP0402LF33.20.1UF040225V10%
52
43
61
52
43
61
21R3497
U257
21R3496
21R3397
U255
VCCGND
2Y
1Y
2A
1A
VCCGND
2Y
1Y
2A
1A
2
1
2
1C1979
2
1
2
1
2
1
R3494
2
1
2
1
R3492
2
1
2
1
2
1
R3461
2
1
2
1
2
1
2
1C1963
SHEETDATE
DEPARTMENT
SIZE
PROJECT DOCUMENT NUMBER REV
REVIEWER
DESIGNER
123
7 3 2 1 6 5 4
E
A
B
C
E
D
C
B
A
7 6 5 4
D
IN OUT
OUTIN
OUTIN
R3491
R3495
R3490
R3493
R3489
R3488
R3462
R3460
R3459
C



20211126 CHANGE R3036 TO 33.2 OHM20220805 DEPOP R4173PUSH-PULL OUTPUT
20211126 DPPOP R259,R260PUSH-PULL OUTPUT20210527 MODIFY FOR GT
PUSH-PULL OUTPUT20211215 ADD R4515 PU TO P3V3_AUXFri Aug 25 14:02:13 2023N/AN/AN/AN/AV05151 OF 312P3V3_AUXP3V3_AUXP3V3_AUXP3V3_AUX
P3V3_AUXP3V3_AUXP3V3_AUXP3V3_AUXP3V3_AUXP3V3_AUXP3V3_AUXP3V3_AUXP3V3_AUX
EXAMAX_ISO (7/7)240215245214142137
136140142213213227
UART_BMC_BIC_R_BUF_RX74LVC1G126SE-7UART_BMC_BIC_BUF_RX33.2CHIP0402LF1/16WEMPTY100K1%0402LFFM_PDB_BUF_EN_RCHIPICUART_BMC_BIC_R_RX0402LFCHIP1%0402LFGPU_FPGA_RST_R_N0402LFCHIP10K1/16W0402LFGPU_FPGA_RST_R_BUF_N10%X7R0402FM_UART_EN0402LFSMLF74LVC2G17GWGPU_FPGA_RST_R1_BUF_NEMPTY1/16W5%4.7K4.7K33.2SMLFUART_BMC_BIC_RX100K1/16W1%0402LFCHIP1%0CHIP0402LF25V0.1UF10%0.1UF49.9
0402BMC_MONITER_BUF_RRST_SWB_BIC_BUF_N49.9CHIPBMC_MONITER_BUFCHIP49.95%1/16W0402LF1/16W5%4.7K4.7KRST_SWB_BIC_BUF_R_N0402LFFM_GPU_PWR_EN_R_BUF74LVC2G17GW1/16WEMPTYCHIP49.9CHIP1/16WCHIP0402LFCHIP1/16W0402LF100K1%EMPTY54.9K0402LFEMPTY1/16W4.7K1/16WFM_GPU_PWR_EN_R FM_GPU_PWR_EN_R1BMC_MONITER_RRST_SWB_BIC_R_N4.7KEMPTY1/16W5%0402LF5%1%0402LF
X7R10%25V0.1UFCHIP1/16W5%4.7K0402LFICSMLFX7R25V04024.7K1/16WEMPTY0402LF5%5%1%CHIP1/16WIC10KCHIP1/16W5%4.7K100K0402LFEMPTY1/16W1%EMPTY100K1%0402LF1/16W4.7K0402LFCHIP5%
R3063
R2924
R2917
R3315
R2925
R3036
R3317
R2937
R2911
R2912
R2916
R2915
R2820
4
1
2
4
6
3
1
4
6
3
1
53 52 52
U204
R3033
U196
U195
B0
A1
A0
B1
OE
Y
A
B0
A1
A0
B1
GND VCCGND VCCGND VCC
21
21
21
21
21
2
1
2
1
2
1
R4515
2
1
21
2
1
2
1
2
1
2
1
2
1
21
2
1C1803
2
1
2
1
2
1
2
1
2
1C1770
2
1
2
1
2
1
2
1C1769
2
1
2
1
SHEETDATE
DEPARTMENT
SIZE
PROJECT DOCUMENT NUMBER REV
REVIEWER
DESIGNER
123
7 3 2 1 6 5 4
E
A
B
C
E
D
C
B
A
7 6 5 4
D
OUT
OUT
IN
IN
OUT
OUTIN
IN
IN
IN OUT
R2927
R4173
R2909
R3508
R3506
R3507
R3509
R2936
R2926
R2815
C



20220725 CHANGE C2029,C2030 TO 18 PF20210527 MODIFY FOR GTUSB_HUB_I2C ONLY FOR EEPROM.
Fri Aug 25 14:02:14 2023N/AN/AN/AN/AV05152 OF 312P3V3_AUXP3V3_AUXP3V3_AUXP3V3_AUXP3V3_AUX
USB HUB
240240152152152152152143
227196
143
152152152152152152152152152USB1_BOM15%18PFUSB1_BOM118PF50VC0G0402USB1_BOM1USB2_HOST_BMC_B_DP50V5%0402C0GMISCUSB2_HOST_BMC_B_DNUSB_HUB_XTAL_IN
0402USB1_BOM20.1UF25V10%EMPTY04020.1UFUSB1_BOM225V10%EMPTY040210%25V0.1UFUSB1_BOM2EMPTYUSB1_BOM10.1%680USB1_BOM1USB2_HOST_BMC_B_BUF_DPUSB2_HOST_BMC_B_BUF_DNR2788/R2786,R2789/R2787 CO-LAYOUTUSB1_BOM2USB_HUB_OVCUR2USB_HUB_OVCUR3SHORT THE NET USB2_HUB_SWB_R_DP/DN TO USB2_HUB_BUF_SWB_R_DP/DNCHIPEMPTY10%EMPTYUSB1_BOM2EMPTYUSB2_HUB_BUF_SWB_R_DP0402LF5%1/16WUSB1_BOM2TUSB211IRWBRSMLFUSB1_BOM2USB2_HUB_BUF_SWB_R_DPC040225VUSB2_HUB_BUF_SWB_R_DNUSB1_BOM2EMPTY5%EMPTY49.9USB1_BOM2USB1_BOM20EMPTY5%1/16WNC_USB_HUB_DM3NC_USB_HUB_DP4
PD_U5201_EQUSB2_HUB_SWB_DPUSB2_HUB_SWB_DNCHIPCHIP1/16WEMPTY49.900402LF00PD_U5201_RSTNTP_USB2_CDTP_USB2_TEST1UF000402LFCHIP0402LF1%10K33.21/16W10K0402LFUSB_HUB_OVCUR4EMPTY0 ICSMLFUSB2_P0_R_DP00EMPTY49.900402LFSMLF12MHZEMPTYPD_U5201_VREGUSB2_HUB_BUF_SWB_R_DNTP_USB2_ENA_HSUSB2_HUB_BUF_SWB_DP3.9KEMPTY
0402LFNC_USB_HUB_DP21/16WEMPTYUSB2_P0_R_DNUSB_HUB_TESTCHIPCHIPCHIPRST_USB_HUB_N25V1%CHIP10K0402LF0402LFUSB2_HUB_BUF_SWB_DN
USB_HUB_PSELFUSB2_HUB_SWB_DNUSB2_HUB_SWB_DPC0402GL852G-OHY60USB1_BOM11/16W0402LFX6S0402LFRST_USB_HUB_R_N10K1/16W1%CHIPUSB1_BOM1USB_HUB_PSELF1%1/16W10%CHIP10K1%0402LFUSB1_BOM1CHIP1/16W0402LFCHIPP3V3_AUX_USB_HUBUSB1_BOM125VX7R0402USB1_BOM110%0.1UFUSB1_BOM110UF6.3V20%X6SC0402USB1_BOM125V10%X7R04020.1UFUSB1_BOM11UF25V10%X6SC040210%25VX7R0402USB1_BOM10.1UFUSB1_BOM10.1UF25V10%X7R04020.1UF25V10%X7R0402USB1_BOM11UF25V10%X6SUSB1_BOM1USB1_BOM1CHIP0402LF0USB1_BOM11UF1/16WEMPTY0402LF47KUSB1_BOM10402LFUSB_HUB_OVCUR1USB_HUB_PGANGUSB_HUB_XTAL_OUTNC_USB_HUB_SDAUSB1_BOM1NC_USB_HUB_DM2NC_USB_HUB_DM40NC_USB_HUB_DP30402LF0402LFUSB1_BOM1EMPTYR2790/R3651,R3652/R2791 CO-LAYOUTEMPTY49.9USB1_BOM1CHIP1/16W1%100KUSB_HUB_RREFUSB_HUB_OVCUR4USB_HUB_OVCUR3USB_HUB_OVCUR2USB_HUB_OVCUR1USB_HUB_DVDDC0402EMPTY10K10K1%EMPTY0402LF0402LFUSB1_BOM1USB1_BOM10152152152152
R4419
R3665
C2038 C2031 C2032 C2033
R3653
R2789
R2791R2790
C2030C2029
R4483R4482
R4420
R3661
R3666
R3659
R3658
R3657
R3656
R3662
C2039 C2040
R3655
R3660
C2035C2034
R2788
31
42
11
10
28
27
TH
18
26
8
17
22
23
19
20
24
25
21
16
13
7
4
2
15
12
6
3
1
14
9
5
Y4
R3654
21R3651 21R3652
U268
2
1C5234
21R5234 21R5236
2
1C5229
2
1C5236
U5201
R5238
2
1C5232
R2786
R2787
GND
EQ
D2PD1P
D1M
CD
ENA_HS
VCCTEST
VREG
D2M
RSTN
X2
G2G1
X1
DM4
DP4
DM3
DP3
DM2
DP2
DM1
DP1
DM0
DP0
RREF
PSELF
PGANG
RESET#
OVCUR4#
OVCUR3#
OVCUR2#||SMD
OVCUR1#||SMC
TH
DVDD
AVDD
AVDD
AVDD
V33
V5 SDA
TEST||SCL
X2
X1
2
1
2
1
2
1
2
1
2
1
2
1
21
21
21
21
212
1
2
1 2
1
21
2
1
2
1
2
1
21
2
1
2
1
2
1
2
1
2
1
2
1
2
1
2
1
2
1
2
1
2
1
2
1
21 21
CAD NOTE:
CAD NOTE:
CAD NOTE:
21
11123
5 106 9
7821
4
SHEETDATE
DEPARTMENT
SIZE
PROJECT DOCUMENT NUMBER REV
REVIEWER
DESIGNER
123
7 3 2 1 6 5 4
E
A
B
C
E
D
C
B
A
7 6 5 4
D
BIBIBIBI
OUT
OUT
OUT
OUT
OUT
IN
ININININ
IN
BIBI
BIBI
R3664
R3663
C2041
C



DP/DN SWAPDP/DN SWAPDP/DN SWAPDP/DN SWAPDP/DN SWAPDP/DN SWAPDP/DN SWAPDP/DN SWAPDP/DN SWAPDP/DN SWAPTO CPU0 PCIE PORT1 [15:0]DP/DN SWAPDP/DN SWAPDP/DN SWAPDP/DN SWAPDP/DN SWAPDP/DN SWAPDP/DN SWAPDP/DN SWAPDP/DN SWAPDP/DN SWAPDP/DN SWAPDP/DN SWAP
FRU ADDRESS:0X50
FROM CPU0 PCIE PORT1 [15:0]20210525 MODIFY FOR GT20230414 CHANGE R425 TO 200 OHM
N/AFri Aug 25 14:02:15 2023N/A153 OF 312V05N/AN/AP3V3_OCP_SFFP3V3_OCP_SFF
P12V_OCP_SFF
P12V_OCP_SFFP3V3_OCP_SFF
P3V3_OCP_SFF
PCIE - SFF OCP3.0_X16 (1/3)
CLK_50M_NCSI_OCP_SFF_ISO33.20402LF1/16W0402LF1%FM_OCP_SFF_PWR_GOODRST_PERST2_OCP_SFF_NRST_PERST3_OCP_SFF_NIRQ_LVC3_OCP_SFF_WAKE_N1541/16WSMB_OCP_SFF_3V3AUX_BUF_SDASMB_OCP_SFF_3V3AUX_BUF_R_SDA2001%CHIPCHIPSMB_OCP_SFF_3V3AUX_BUF_R_SCL153158154158 153 154153
155
153213
153214153213153213153213153154213153213209209154154209155209174154154209174153214153153 154213154154209154154209154154
153213213153213153
29180180156165156 16515616529155153
238238155155155153155156 165154209OCP_SFF_AUX_PWR_ENOCP_SFF_AUX_PWR_EN1/16W
0402LF 0402LFCHIP1%1/16W1/16W0402LF4.7K1%OCP_SFF_ID14.7K0402LFEMPTYSGPIO_OCP_SFF_CLK10KCHIP1K1/16W
0402LF0402LF5%0CHIP1/16WOCP_SFF_MAIN_PWR_ENOCP_SFF_MAIN_PWR_EN_RSGPIO_OCP_SFF_LD_NSGPIO_OCP_SFF_DATAINSGPIO_OCP_SFF_DATAOUTSGPIO_OCP_SFF_CLKCLK_100M_OCP_SFF_2_DNCLK_100M_OCP_SFF_2_DPNCSI_OCP_SFF_RXD005%NCSI_OCP_SFF_CRS_DVCLK_100M_OCP_SFF_3_DPRST_PERST0_OCP_SFF_NCLK_100M_OCP_SFF_0_DPP5E_CPU0_PE1_TX_C_DP<15:0>100K1%CHIPOCP_SFF_ISO_BIF2_ENOCP_SFF_ISO_BIF0_EN OCP_SFF_BIF0_R_NOCP_SFF_BIF1_R_NOCP_SFF_BIF2_R_NOCP_SFF_AUX_PWR_EN_RCLK_100M_OCP_SFF_0_DNP5E_CPU0_PE1_TX_C_DN<15:0>1/16WCHIPOCP_SFF_MAIN_PWR_EN0402LF5%1%OCP_SFF_ID0CHIPFM_OCP_SFF_PWR_GOODNCSI_OCP_SFF_RXD15%OCP_SFF_ISO_BIF1_ENCLK_100M_OCP_SFF_1_DNNCSI_OCP_SFF_TXD0NCSI_OCP_SFF_TX_ENCLK_100M_OCP_SFF_3_DNNCSI_OCP_SFF_TXD1OCP_SFF_ISO2_RBT_ARB_OUT00402LFRST_SMB_OCP_SFF_N
SGPIO_OCP_SFF_DATAINSGPIO_OCP_SFF_LD_NCHIP0402LF 1/16W1%1K1%0402LF10K1%CHIPSGPIO_OCP_SFF_DATAOUT1%CHIP
10KTP_OCP_SFF_B68TP_OCP_SFF_B690402LFP5E_CPU0_PE1_RX_DN<15:0>0402LF0402LFPLACE THE BULK CAPS CLOSE TO SLOTOCP_SFF_USB2_3_DNUSB2_3_DNUSB2_3_DP5%0OCP_SFF_PRSNT3_R_N
0 OCP_SFF_PRSNT1_R_NOCP_SFF_PRSNT0_R_NCHIP 1/16WP5E_CPU0_PE1_RX_DP<15:0>05%040225V10%0.1UF22UF16V20%C0805X6S16VX6S20%22UFC08050402X7R0.1UF25V10% 10%0.1UF25V0402X7R25V10%0402X7R0.1UFX7ROCP_SFF_PWRBRK_NOCP_SFF_USB2_3_DP100CHIP1/16W1%10K1%0402LF4.7KOCP_SFF_ID0
5%0
CHIP1%1/16W4.7K1%EMPTY1/16W
SMB_OCP_SFF_3V3AUX_BUF_SCL0402LFOCP_SFF_ID1OCP_SFF_PRSNTA_R_NRST_PERST1_OCP_SFF_NSCONN168_ME1016810202011IOSMLFOCP_SFF_PRSNT2_R_N0402LF
25V10%X7R0.1UF04020.1UF25V10%0402X7R04020.1UF25V10%X7RX7R040210%25V0.1UF
OCP_SFF_ISO1_RBT_ARB_INCLK_100M_OCP_SFF_1_DP
R420
R421
R422
R423
R1895
R445
R444
R429
R425
OA3
A69
A68
A9
A8
A7
OA6
OB7
B69
B68
OA12OB12
A15B15
OA11OB11
A14B14
OA8
OA9
OA7
OB8
OB9
OB14 OA14
OA5
OA4
A70B70
A12
A42B42
A10
B66
B63
B60
B57
B54
B51
B48
B45
B40
B37
B34
B31
B27
B24
B21
B18
B65
B62
B59
B56
B53
B50
B47
B44
B39
B36
B33
B30
B26
B23
B20
B17
OA2
OA1
A11
B10
A66
A63
A60
A57
A54
A51
A48
A45
A40
A37
A34
A31
A27
A24
A21
A18
A65
A62
A59
A56
A53
A50
A47
A44
A39
A36
A33
A30
A26
A23
A20
A17
OB1
OB2
OB3
OB13
OB10
OA13
OA10
B67
B64
B61
B58
B55
B52
B49
B46
B43
B41
B38
B35
B32
B29
B28
B25
B22
B19
B16
B13
A67
A64
A61
A58
A55
A52
A49
A46
A43
A41
A38
A35
A32
A29
A28
A25
A22
A19
A16
A13
A6
A5
A4
A3
A2
A1
G5
G4
G3
G2
G1
OB5
OB4
OB6
B9
B8
B7
B12
B6
B5
B4
B3
B2
B1
B11
0
1
4
7
8
10
1
1
15
13
6
4
2
0
2
9
10
12
13
0
2
1
0
12
14
15
12
14
5
6
7
3
4
6
7
8
8
9
10
11
13
12
14
6
4
3
3
5
7
8
9
11
11
13
15
15
3
9
10
14
5
2
11
5
J37
KEY
KEY
KEY
G5
G4
G3
G2
G1
PRSNTB3#
RFU1_NC_B69
RFU1_NC_B68
GND_B67
PETp15
PETn15
GND_B64
PETp14
PETn14
GND_B61
PETp13
PETn13
GND_B58
PETp12
PWRBRK0#
USB_DATp
USB_DATn
GND_A67
PERp15
PERn15
GND_A64
PERp14
PERn14
GND_A61
PERp13
PERn13
GND_A58
PERp12
PERn12
GND_A55
PERp11
PERn11
GND_A52
PERp10
PERn10
GND_A49
PERp9
PERn9
GND_A46
PERp8
PERn8
GND_A43
PRSNTB1#
GND_A41
PERp7
PERn7
GND_A38
PERp6
PERn6
GND_A35
PERp5
PERn5
GND_A32
PERp4
PERn4
GND_A29
GND_A28
PERp3
PERn3
GND_A25
PERp2
PERn2
GND_A22
PERp1
PERn1
GND_A19
PERp0
PERn0
GND_A16
REFCLKp1
REFCLKn1
GND_A13
PRSNTB2#
PERST1#
PRSNTA#
SMRST#
SMDAT
SMCLK
GND_A6
GND_A5
GND_A4
GND_A3
GND_A2
GND_A1
RBT_CLK_IN
GND_OA13
REFCLKp3
REFCLKn3
GND_OA10
RBT_TXD0
RBT_TXD1
RBT_TX_EN
SLOT_ID1
RBT_ARB_OUT
RBT_ARB_IN
WAKE#
PERST3#
PERST2#
PETn12
GND_B55
PETp11
PETn11
GND_B52
PETp10
PETn10
GND_B49
PETp9
PETn9
GND_B46
PETp8
PETn8
GND_B43
PRSNTB0#
GND_B41
PETp7
PETn7
GND_B38
PETp6
PETn6
GND_B35
PETp5
PETn5
GND_B32
PETp4
PETn4
GND_B29
GND_B28
PETp3
PETn3
GND_B25
PETp2
PETn2
GND_B22
PETp1
PETn1
GND_B19
PETp0
PETn0
GND_B16
REFCLKp0
REFCLKn0
GND_B13
AUX_PWR_EN
+3.3V_EDGE
PERST0#
BIF2#
BIF1#
BIF0#
+12V_EDGE_B6
+12V_EDGE_B5
+12V_EDGE_B4
+12V_EDGE_B3
+12V_EDGE_B2
+12V_EDGE_B1
RBT_CRS_DV
GND_OB13
REFCLKp2
REFCLKn2
GND_OB10
RBT_RXD0
RBT_RXD1
SLOT_ID0
CLK
DATA_OUT
DATA_IN
LD#
MAIN_PWR_EN
NIC_PWR_GOOD
21
21
21
21
21
2
1C1240
21R424
2
1
21 21
2
1C1239
2
1C1238
2
1C1237
2
1C1236
2
1C1235
2
1C1234
2
1C1233
2
1C1232
2
1C1213
21
21R416 21R417 21R418
21R1671
21R1929
21R1930
21R3132
2
1
2
1
2
1
2
1
CAD NOTE:
SHEETDATE
DEPARTMENT
SIZE
PROJECT DOCUMENT NUMBER REV
REVIEWER
DESIGNER
123
7 3 2 1 6 5 4
E
A
B
C
E
D
C
B
A
7 6 5 4
D
OUT
INININOUTIN
OUT
OUT
OUT
ININ
OUT
OUT
ININ
IN
OUT
OUT
OUT
OUT
IN
ININ
IN
IN
OUT
OUT
IN
IN
ININ
OUT
INOUT
OUT
ININ
ININ
ININ
IN
INBI
OUT
ININ
ININ
OUTOUT
OUT
ININ
OUT
INOUT
R414R409
R415R410
C



20220504 CHANGE NETNAME TO OCP_SFF_AUX_PWR_EN20220803 POP R2473, DEPOP R2474Fri Aug 25 14:02:16 2023N/AN/AN/AN/A V05154 OF 312P3V3_AUX
P3V3_AUXP3V3_AUXP3V3_AUX
PCIE - SFF OCP3.0 (2/3)155153158154215161191227231233236245
153154 160240154240160215
165154240160154240160154160240154160240154160240154 160240154 160240165153153240154160240154160240154160240153153
153153153153153153153158154
153153213CHIP49.90402LFEMPTY1/16W1%FB_BMC_ISOLATEOCP_SFF_AUX_PWR_EN0.1UFOCP_SFF_AUX_PWR_EN_R4RST_SMB_SWITCH_NCHIPOCP_SFF_AUX_PWR_EN_R174LVC1G126SE-7100KOCP_SFF_ISO2_RBT_ARB_OUTSMLFRMII_OCP_BMC_RXD_0CO-LAYOUT1/16W220CHIPRMII_BMC_OCP_TX_ENCHIP1/16W5%0FM_NCSI_OCP_V3_1_R_OE
OCP_SFF_RBT_ARB_IN0402LFEMPTY0402LF1%CHIP1/16W100K100K CHIP1%1%CHIP100KCHIP2222CHIPCHIP22CHIP00CHIP0100K1%CHIP100K1%CHIP1%100K CHIPCHIP1K1/16W1%0402LF1%1001/16WCHIP0402LF0402LFCHIP1001%1/16W1001%CHIP1/16W0402LF
10%0402X7R0.1UF25VIC74CBTLV3126PWSMLF0.1UF25VX7R040210%ICX7R0.1UF25V10%04021/16W5%0CHIPIC100KCHIP1/16W1%X7R25V0402ICSMLF1%1%33.20402LF
RMII_BMC_OCP_TXD_0RMII_BMC_OCP_TXD_1RMII_OCP_BMC_RXD_1RMII_OCP_BMC_CRSDVRMII_OCP_BMC_RXD_0RMII_OCP_BMC_CRSDVOCP_SFF_RBT_ARB_IN_RRMII_OCP_BMC_RXD_1OCP_SFF_RBT_ARB_OUTNCSI_BMC_CRS_DV_RNCSI_BMC_RXD0_RNCSI_BMC_RXD1_RNCSI_BMC_TXD1_RNCSI_BMC_TXD0_RNCSI_BMC_TX_EN_ROCP_SFF_ISO_BIF2_ENOCP_SFF_ISO_BIF1_ENRMII_BMC_OCP_TX_ENRMII_BMC_OCP_TXD_1RMII_BMC_OCP_TXD_0RMII_BMC_OCP_RX_EROCP_SFF_ISO_BIF0_ENRST_SMB_OCP_SFF_N
OCP_SFF_ISO1_RBT_ARB_INNCSI_OCP_SFF_RXD1NCSI_OCP_SFF_CRS_DVNCSI_OCP_SFF_TX_ENNCSI_OCP_SFF_TXD0NCSI_OCP_SFF_TXD110%0402LFOCP_SFF_AUX_PWR_ENCHIP 1/16W0402LF74LVC1G126SE-7RST_HP_OCP_SFF_R_N0402LFSMLFNCSI_OCP_SFF_RXD074CBTLV3126PWFB_BMC_ISOLATE_R1CHIPFM_OCP_SFF_PWR_GOOD33.21/16W0402LF
R1356
R1350
R1351
R1352
R1354
R1355
R1898R1897R1896
R1719
R3231
R1353
R1290
R1291
R1292
R1293
R1294
R1295
R1296
4
1
2
4
1
2
5353
U67
U68
U66
U224
OE
Y
A
VCC
4OE
4A4B
3OE
3A
GND
1A
2B
1B
2OE
1OE
3B
2A
VCC
4OE
4A4B
3OE
3A
GND
1A
2B
1B
2OE
1OE
3B
2A
OE
Y
A
GND VCCGND VCC
21
21
21
21
21
21
21
2
1
2
1
2
1
2
1
2
1
2
1
2
1
R1289
21R2474
21R3233
2
1
R3232
2
1
21
21
21 21
R2473
14
7
1311 12
108 9
46 5
13 2
14
7
1311 12
108 9
46 5
13 2
SHEETDATE
DEPARTMENT
SIZE
PROJECT DOCUMENT NUMBER REV
REVIEWER
DESIGNER
74CBTLV3126
74CBTLV3126
123
7 3 2 1 6 5 4
E
A
B
C
E
D
C
B
A
7 6 5 4
D
OUT
OUT
OUT
OUT
IN
IN
IN
IN
OUT
OUT
OUT
OUT
OUT
OUT
OUT
OUT
OUT
OUT
OUT
OUTIN
IN
IN
IN
IN
OUT
OUT
OUT
OUT
IN
IN
IN
IN
R3237
C640
C641
C639
C1840
C



20220120 ADD R460120210706 MODIFY FOR GT
20210607 MODIFY FOR GT
Fri Aug 25 14:02:18 2023N/A155 OF 312N/AN/AN/AV05
P3V3_AUXP3V3_AUXP3V3_AUXP3V3_AUXP3V3_AUXP3V3_AUXP3V3_AUXP3V3_AUXP3V3_OCP_SFFP3V3_AUX
P3V3_AUX
PCIE - SFF OCP3.0 (3/3)
153
154155240155161153161190 182
158 1531531531531532151612200402LFRST_PERST1_OCP_SFF_N1%0402LF1/16W4.7K1%1/16WCHIP33.2NC_U157_NC174LVC1G07GVX7RCHIP 1/16W4.7KSMLF4.7K1/16WOCP_SFF_PWRBRK_BUFF_NICICSMLF74LVC1G66GVFB_BMC_ISOLATECLK_50M_NCSI_OCP_SFF_ISO_RCLK_50M_NCSI_OCP_SFF0402X7RCHIPCLK_50M_RMII_BMC_OCPCLK_50M_NCSI_OCP_SFFCLK_50M_NCSI_OCP_V3_21%CHIPCHIPCLK_50M_NCSI_OCP_SFF_ISO0IRQ_LVC3_WAKE_N27.45%CLK_50M_RMII1/16W0402LFCHIP10%0.1UF25VIRQ_LVC3_WAKE_BUF_NTP_CLK_50M_PCH_LOM0402CLK_50M_BMC_MAC_RCLK_50M_NCSI_OCP_110%0.1UFIC0402X7R10%25V0.1UFCHIPSMLFCLK_50M_NCSI_OCP_2CLK_50M_RMII_RCLK_50M_EN1%27.427.41%X7R25V0CHIP0402LF1/16W50MHZSMLFOSC0402X7R25V0.1UF10%0402LFCHIP10K1%1/16WPI6CV304LEIC
RST_HP_OCP_V3_1_NCHIPCHIP1/16WIC1/16W0402LFRST_PERST0_OCP_SFF_NRST_PERST2_OCP_SFF_NRST_PERST3_OCP_SFF_N1%33.2RST_OCP_V3_1_BUF_N74LVC1G17GWSMLF74LVC1G07GV1/16W10%25V0.1UFSMLF1/16WOCP_SFF_WAKE_BUFF_N74LVC1G126SE-7SMLFICIRQ_LVC3_OCP_SFF_WAKE_NCHIP25V0402X7R10%0.1UF1%1/16W10K10K1%1/16WPU_OCP_SFF_WAKE_OE0402LFCHIP0402LFCHIPCHIP1%33.2 0402LFCHIP33.21%0402LFOCP_SFF_PWRBRK_N33.2 0402LF1%OCP_SFF_WAKE_BUFF_R_N1%33.20402LF0402LF1%33.21/16W0402LF1%CHIP1/16W1%0402LFEMPTY
X7R10%0.1UF0402FM_SYS_THROTTLE_R_NNC_U104_NC1PLACE R2487 CLOSE TO U157040225V
R1505
R1504
R435
R419
R4601
R3181
R2489
R1139
R1141
R1140
R1595
R1594
2
1 5
3
4
4
1
2
4 3
1 2
4
51
3
2
4
51
3
2
4
5
13
2
53
U320
U82
OSC1
U157
U104
U90
U75
VCC
E
GND
Z
Y
OE
Y
A
VDD OUT
GNDOE
NC1
YGND
A
VCC
NC1
YGND
A
VCC
GND
VDD
Y3
Y2
Y1
Y0
OE
CLK_IN
NC
Y
GND
A
VCC
GND VCC
21
2
1
21
21
2
1
2
1
2
1
2
1
R1824
2
1
R1138
2
1C1274
21 21 21
2
1
2
1
2
1
R1593
21
2
1
21
2
1
21
21
21
21
2
1
CAD NOTE:
8753
6
2
4
1
R1592
SHEETDATE
DEPARTMENT
SIZE
PROJECT DOCUMENT NUMBER REV
REVIEWER
DESIGNER
123
7 3 2 1 6 5 4
E
A
B
C
E
D
C
B
A
7 6 5 4
D
OUT
OUT
IN
IN
OUT
OUT
OUT
OUTOUT
OUT
IN
IN
IN
OUT
OUT
C2344
R2488
R2487
C1663
C1275
C188
C1175
C1173
C



START UP TIME:3.94MSSTART UP TIME:8.21MSVIMON(MAX)= 1.679V @ IOUT=9.03AVIMON(MAX)= 1.594V @ IOUT=1.6A20211108 MODIFY FOR GTUVP: 2.63VOVP: 3.89VVIMON(MAX)= 1.594V @ IOUT=1.6A20220802 CHANGE TO Q124OVP: 14.91VUVP: 10.17V
P3V3_OCP_V3IMAX=1.1AIMAX=6.6AP12V_OCP_V3OCP=IMAX*1.3=8.58AOCP=IMAX*1.3=1.43ADESIGN SPECIFICATION
20211130 CHANGE TO 1K OHM20211130 CHANGE TO 1K OHMFri Aug 25 14:02:21 2023156 OF 312V05N/AN/AN/AN/AP3V3_AUXP3V3_AUXP12V_AUXP3V3_AUXP3V3_AUXP12V_AUXP3V3_AUX
P12V_AUXP3V3_AUXP3V3_AUXP12V_OCP_SFFP3V3_AUXP3V3_OCP_SFF_R
SFF_OCP3.0 HSC(1/3)
NIC1_P3V3_BOM10402LFNIC1_P3V3_BOM1NIC1_P3V3_BOM1NIC1_P3V3_BOM11/16W25.5K1%CHIP25VX6S1UFCHIP0402LF
158158216
158157238153165153165153165153165 157 158214250250158
HP_LVC3_OCP_V3_1_ATTN_OUT_SW_NHP_LVC3_OCP_V3_1_PRSNT2_NHP_LVC3_OCP_V3_1_PRSNT2_PLD_N0402LF1/16WP12V_OCP_EN_1_RHP_LVC3_OCP_V3_1_ENP12V_OCP_1_EN_GP3V3_OCP_EN_1_ROCP_SFF_PRSNT0_R_NOCP_SFF_PRSNT2_R_NOCP_SFF_PRSNT3_R_NOCP_SFF_PRSNT1_R_NP3V3_OCP_1_EN_GP12V_OCP_UV_1_RHP_LVC3_OCP_V3_1_PRSNT2_N_RP12V_OCP_UV_1P12V_OCP_VCC_1P12V_OCP_REG_1P12V_OCP_CB_1P3V3_OCP_UV_1_R1P3V3_OCP_OV_1P3V3_OCP_UV_1P3V3_OCP_CB_1P3V3_OCP_REG_1P3V3_OCP_VCC_1P12V_OCP_FAULT_1P12V_OCP_PWRGD_1P12V_OCP_GATE_1P12V_OCP_SENSE_1HP_LVC3_OCP_V3_1_P12V_PWRGDP12V_OCP_SFF_ISENSE_MAM_MAMP12V_OCP_SFF_ISENSE_MAM_TICP3V3_OCP_GATE_PU202_1P3V3_OCP_SENSE_1P3V3_OCP_PWRGD_1P3V3_OCP_FAULT_1OCP_V3_1_P3V3_PWRGDP12V_OCP_OV_101/16W0402LFNIC1_P12V_MAM_MAM_BOM1EMPTY5%0402LF1K1%CHIP1/16WEMPTYNIC1_P12V_MAM_MAM_BOM1SMLFPJT138KCHIP1/16W1%1K0402LFEMPTY1%10KNIC1_P12V_MAM_MAM_BOM10402LF1/16WEMPTYSMLFNIC1_P12V_MAM_MAM_BOM1PJT138K1/16W00402LF5%CHIP4.7K5%0402LFCHIP1/16WPJT138KSMLFICNIC1_P3V3_BOM1
0402LFCHIP1%1K1/16WICSMLF74LVC2G07DW-71/16W0402LF1K1%CHIPICSMLF74LVC2G07DW-7040210%25VX7R0.1UFX7R10%040225V0.1UF15K1%0402LFEMPTYNIC1_P12V_MAM_MAM_BOM11/16WSMLFNIC1_P3V3_BOM1PJT138KICICSMF14ANIC1_P12V_MAM_MAM_BOM10402LF05%1/16WEMPTY0402LFEMPTY6.8K1%1/16WNIC1_P12V_MAM_MAM_BOM1NIC1_P12V_MAM_MAM_BOM1160K1%1/16W0402LFEMPTY1UFX6SC040225V5%0402LF0CHIP 1/16W1/16W05%CHIPCHIP05%0402LF1%0402LFEMPTY1/16W30.1KNIC1_P12V_MAM_MAM_BOM10402LFCHIP10K1%1/16WEMPTYSMLFMAX15090BEWI+TNIC1_P12V_MAM_MAM_BOM11UF25VC0402NIC1_P12V_MAM_MAM_BOM1NIC1_P12V_MAM_MAM_BOM125VC0402EMPTY1UF1%101/16WEMPTY0402LFNIC1_P12V_MAM_MAM_BOM11/16W1%15KCHIP0402LFNIC1_P3V3_BOM11/16W5.36K1%0402LFCHIPNIC1_P3V3_BOM1MAX15090BEWI+TNIC1_P3V3_BOM1ICSMLF1/16WCHIP0402LFNIC1_P3V3_BOM11%10KCHIP5%1/16W00402LFC0402X6S25V1UF0402LF7.15K1%1/16WCHIPNIC1_P3V3_BOM1C0402NIC1_P3V3_BOM125VC04021UF101%1/16W
0402LFCHIP10K1/16W1%10K1%0402LF1/16WCHIP1/16WEMPTYNIC1_P12V_MAM_MAM_BOM10402LF1%845R3869/R3870 CO-LAYOUTEMPTY50V0.01UFC04021/16WEMPTY05%0402LFNIC1_P12V_MAM_MAM_BOM1C04023900PF50VNIC1_P12V_MAM_MAM_BOM10402LFEMPTY1%10MNIC1_P12V_MAM_MAM_BOM11/16WB340A-13-FIC1/16WEMPTY05%0402LFNIC1_P12V_MAM_MAM_BOM1NIC1_P12V_MAM_TIC_BOM21/16WEMPTY05%0402LF1%100KNIC1_P12V_MAM_MAM_BOM11/16WEMPTY0402LF 0402LF1/16WEMPTY1%NIC1_P12V_MAM_MAM_BOM1100K0.1UF25VX7R040216V22UFC0805X6S10UF16VX6SC0805EMPTYC040250V0.01UF4.53KNIC1_P3V3_BOM11%1/16WCHIP0402LF10M0402LF1/16WNIC1_P3V3_BOM1CHIP1%B340A-13-FIC0402LFNIC1_P3V3_BOM11/16WCHIP05%6800PFC040250VNIC1_P3V3_BOM11%1/16W100KCHIP0402LFNIC1_P3V3_BOM11/16W1%100KNIC1_P3V3_BOM1CHIP0402LFX7R25V0.1UF0402C080510UFX6S16V
G1
G2
G1
G2
D1S1CAS2 D2D1S1S2 D2
PC2080
PD102
2
1
PR4524
PC4056
PR3792
A2
D2
D1 D7
D3
D6
D4
C6
C4
B6
B4
A4
A1
D5
C5
C3
B5
B3
A5
A3
C2
C1
B2
A6
C7
B7
A7B1
PU203
21R1148
PC2079
PR3786
R3784
PR3788
2
1 C592
2
1
R1907
2
1
R4068
2
1
R1905
2 Q123
2
1
R1906
2
1
R3797
2
1
R3799
21R3870
21R3869
R3144
2
1
R1149
PR3787
PD101
2
1 C593
52
43
61
U211
52
43
61
U212
5 Q123
R4061
PC2082PC2092
PC2088
2
1
PR3781
2
1
R1150
PC2085
PC2087
2
1 PR5484
21R1147
2
1
R1908
CA
1 6CA4 3
PC2091
R3783R3796
PR3798
PR3790
PC5328
PR3780
R5487
R3794
PR4525
PR5481
PC2144
PC2093
PC2086
R4070
PR3791
PC2089
PR3789
R4752
PC2081
A2
D2
D1 D7
D3
D6
D4
C6
C4
B6
B4
A4
A1
D5
C5
C3
B5
B3
A5
A3
C2
C1
B2
A6
C7
B7
A7B1
5
2
4 31 6
PU202
Q124
Q124
PD103
PG
FAULT#
GND_C2
GND_C1
GND_B2
CDLY
GATE
OUT_D6
OUT_D4
OUT_C6
OUT_C4
OUT_B6
OUT_B4
OUT_A4
ISENSEOV
UV
REG
EN#
CB
IN_D5
IN_C5
IN_C3
IN_B5
IN_B3
IN_A5
IN_A3
VCC
PG
FAULT#
GND_C2
GND_C1
GND_B2
CDLY
GATE
OUT_D6
OUT_D4
OUT_C6
OUT_C4
OUT_B6
OUT_B4
OUT_A4
ISENSEOV
UV
REG
EN#
CB
IN_D5
IN_C5
IN_C3
IN_B5
IN_B3
IN_A5
IN_A3
VCC
VCCGND
2Y
1Y
2A
1A
VCCGND
2Y
1Y
2A
1A
CACA
2
1
2
1
2
1
2
1
2
1
2
1
2
1
2
1
21
CAD NOTE:
CA
SHEETDATE
DEPARTMENT
SIZE
PROJECT DOCUMENT NUMBER REV
REVIEWER
DESIGNER
123
7 3 2 1 6 5 4
E
A
B
C
E
D
C
B
A
7 6 5 4
D
OUT
OUT
OUT
OUT
OUT
IN
IN
IN
IN
OUT
IN
OUT
R3785
R4069
R4762
C



PU204 OPTIONAL BOMDE-POPDE-POPPOPPOPMP5025A/POPDE-POPDE-POPDE-POPMP5022AMP5025C/POPPOPMP5022CVIMON(MAX)= 1.582V @ IOUT=9.09APC2158PR3843PR3841PR3838PR3840START UP TIME:8.62MSTFAULT: 1.27MSTDELAY: 6.29MSVTH>1.391V(HIGH)ENABLE:CURRENT LIMIT20211108 MODIFY FOR GTOCP=IMAX*1.3=8.58AOCP=IMAX*1.3=1.43ADESIGN SPECIFICATIONIMAX=1.1AP3V3_OCP_V3IMAX=6.6AP12V_OCP_V3START UP TIME:4.7MS=1.6A
N/AN/AN/AFri Aug 25 14:02:22 2023N/A157 OF 312V05P12V_AUXP3V3_AUXP3V3_AUXP12V_AUXP12V_OCP_SFFP3V3_AUXP3V3_OCP_SFF_R
SFF_OCP3.0 HSC CO-LAYOUT(2/3)HP_LVC3_OCP_V3_1_P12V_PWRGD0402LF1/16WCHIP1/16W0402LFNIC1_P12V_MPS_MAM_BOM30402LFCHIP10K1%NIC1_P12V_MPS_MAM_BOM3NIC1_P12V_MPS_MAM_BOM3100NFP12V_OCP_SFF_ISENSE_MPS_TIC0402LFNIC1_P12V_MPS_MAM_BOM3NIC1_P12V_MPS_MAM_BOM3157250P12V_OCP_SFF_ISENSE_MPS_MAMCHIP1/16W00402LF250158156157238156158214157
158156157238
EMPTY5%0402LF1/16WNIC1_P12V_MPS_TIC_BOM405%R3871/R3872 CO-LAYOUTNIC1_P12V_MPS_MAM_BOM3HP_LVC3_OCP_V3_1_ENP12V_OCP_SS_1P12V_OCP_EN_1_R2P12V_OCP_TIMER_1P12V_OCP_ISET_1P12V_OCP_FLTB_1P12V_OCP_AVIN_PD_1P12V_OCP_OV_FB_1P12V_OCP_AVIN_PD_1P12V_OCP_IMON_116VNIC1_P12V_MPS_MAM_BOM30402X7R0.22UF0402LFNIC1_P12V_MPS_MAM_BOM3CHIP1/16W1%14.3KX7RC040225V0.047UFNIC1_P12V_MPS_MAM_BOM3CHIP05%1/16W0402LFNIC1_P12V_MPS_MAM_BOM3X6S25V1UFC0402NIC1_P12V_MPS_MAM_BOM3RS31312RNIC1_P12V_MPS_MAM_BOM3IC1%1/16WCHIP17.4K0402LF X7R50VC04021%10K0402LF1/16WEMPTY1%1001/16WNIC1_P12V_MPS_MAM_BOM3CHIP10K1%1%EMPTY71.5K1/16W1%CHIP0402LFNIC1_P12V_MPS_MAM_BOM3120KX7RC060320%2.2UF16V0603LFCHIP1%49.9NIC1_P12V_MPS_MAM_BOM31/10W0402X7R10%25V0.1UFNIC1_P12V_MPS_MAM_BOM31%NIC1_P3V3_BOM210UFNIC1_P3V3_BOM2P3V3_OCP_EN_1_R2EMPTY0402LF5%EMPTYC0402EMPTYEMPTYNIC1_P3V3_BOM2040216VNIC1_P3V3_BOM2 NIC1_P3V3_BOM2P3V3_OCP_DVDT_1NIC1_P3V3_BOM21UFEMPTY25VC0402NIC1_P3V3_BOM2HP_LVC3_OCP_V3_1_ENEMPTYP3V3_OCP_MODE_1P3V3_OCP_ILIMIT_10402NIC1_P3V3_BOM271.5K1%P3V3_OCP_GATE_10.068UFNIC1_P3V3_BOM2MP5016GQH-L-Z1/16W39PF0402LFEMPTY100PF50VEMPTY0402LF1.33KEMPTYC080516V05%50VSMLF
2
1
PC2160
2
1
PR3843
PC2158
PR3841
2
1PR3840
PR3842
21
R3871
21
R3872
2
1
PR3838
2
1
R4532
PR3839
PC2156
2
1
PR3837
PC2154
21
R3834
PC2155
2
1
PR3835
PC2153
PC2159
20
19
18
17
16
15
14
13
26
25
24
23
21_22
4
6
10
11
2
5
87
9
3
1
12
PU204
PC2163
PU205
PC2161
PR3844PC2157
GND
SS
ISET
TIMER
ENTM
LOADEN
EN
VIN_26
VIN_25
VIN_24
VIN_23
IMON
FLTB
PG
OV
VOUT_13
AVIN
VOUT_14
VOUT_15
VOUT_16
VOUT_17
VOUT_18
VOUT_19
VIN_21_22
VOUT_20
SOURCE
GATE
DV_DT
VCC
GND
ILIMIT
MODE
EN
PC2162
21R3845
CAD NOTE:
PR3846
1_2 6_7
54 3
8
9
10
SHEETDATE
DEPARTMENT
SIZE
PROJECT DOCUMENT NUMBER REV
REVIEWER
DESIGNER
123
7 3 2 1 6 5 4
E
A
B
C
E
D
C
B
A
7 6 5 4
D
OUT
OUT
OUT
OUT
IN
IN
IN
C



20210811 MODIFY FOR GT20220804 ADD R4764
20220803 DESIGN CHANGE20220224 CHANGE TO P3V3_OCP_SFFPUSH PULL OUTPUT20210607 MODIFY FOR GT
PCA9554 ADDR: 0X4020210607 MODIFY FOR GT
Fri Aug 25 14:02:23 2023158 OF 312N/AN/AN/AV05N/AI177
P3V3_AUXP3V3_AUX
P3V3_AUXP3V3_AUXP3V3_OCP_SFFP3V3_AUXP3V3_AUXP3V3_AUXP3V3_AUXP3V3_AUX
P3V3_AUXSFF_OCP3.0 HSC(3/3)
156156 158158235156153 154213158216156 157238158216223156157214155158235158158
158156158
15815815823510K0402LFCHIP1/16W1%PCA9555APWSMLF0.1UF0402TP_PCA9555_0_P7TP_PCA9555_0_P10HP_LVC3_OCP_V3_1_ATTN_OUT_SW_NHP_LVC3_OCP_V3_1_PRSNT2_NHP_OCP_V3_1_ENICTP_PCA9555_0_P5SMB_PEHPCPU0_LVC3_SCLOCP_V3_1_P3V3_PWRGD10KHP_LVC3_OCP_V3_1_PWRGD_R2OCP_SFF_AUX_PWR_PLD_EN_ROCP_SFF_AUX_PWR_EN_R25%0EMPTY0402LF00402LF5%EMPTY1%SMLFOCP_SFF_AUX_PWR_EN0402LF25VHP_OCP_V3_1_RST1%33.20402LF33.2CHIP1%1/16WOCP_SFF_AUX_PWR_PLD_ENHP_LVC3_OCP_V3_1_PWRGD_RCHIPCHIP0402LFHP_LVC3_OCP_V3_1_EN040274LVC1G08W5-710%X7RCHIP25V5%00402LFEMPTYCHIP33.2ICCHIPHP_LVC3_OCP_V3_1_PWRGD_RRST_OCP_V3_1_N49.9IC74LVC1G08W5-70402LFPD_SMB_OCP1_HP_ADD0TP_PCA9555_0_P13TP_PCA9555_0_P14TP_PCA9555_0_P16TP_PCA9555_0_P17SMLFHP_LVC3_OCP_V3_1_P12V_PWRGDHP_OCP_V3_1_RST_R1%33.2 0402LFCHIP0.1UFHP_LVC3_OCP_V3_1_PWRGDIC0.1UF10%X7R040225VSMLF74LVC1G08W5-7X7R10%25V0.1UF0402ICRST_HP_OCP_V3_1_NAPX809-29SAG-71%0402LF0402LF1/16WEMPTY1K1%0402LFEMPTY1/16W1%1K1/16WCHIP1%1/16W1K1%EMPTY1/16W1K1%1KCHIP1/16W0402LFFM_SMB_CPU0_ALERT25V0402LF10%X7R1KCHIPSMB_PEHPCPU0_LVC3_SDAFM_SMB_CPU0_ALERTPD_SMB_OCP1_HP_ADD1SMB_PEHPCPU0_LVC3_R_SDATP_PCA9555_0_P6TP_PCA9555_0_P12TP_PCA9555_0_P15TP_PCA9555_0_P11TP_PCA9555_0_P00TP_PCA9555_0_P01
ICSMLF10%0.1UF0402LF1KCHIP1/16W1%ICBSS138KHP_LVC3_OCP_V3_1_PRSNT2HP_OCP_V3_1_ENX7RHP_LVC3_OCP_V3_1_PRSNT2_N040274LVC1G08W5-7
SMB_PEHPCPU0_LVC3_R_SCLPD_SMB_OCP1_HP_ADD210%0402X7R0.1UF25VSMB_PEHPCPU0_LVC3_R_SCLSMB_PEHPCPU0_LVC3_R_SDA33.21%0402LF0402LF33.21%1/16W0402LF1%0402LFEMPTY1K1%1/16WSMLFFM_SMB_PEHPCPU0_PCIE_ALERT_N33.21%0402LF
U49
R4749
R4748
R4747
R4750
R4746
R4614
R4618
R4613
R1921
R1131
R1130
G
S D
4
5
3
2
1
4
5
3
2
1
12
24
23
22
20
19
18
17
16
15
14
13
11
10
9
8
7
6
5
4
1
3
2
21
4
5
3
2
1
4
5
3
2
1
U334
U52
U322
U209
U208
U210
VCC
Y
GND
B
A
GND
RESET_L
VCC
VCC
Y
GND
B
A
A2
A1
A0
P1_7
P1_6
P1_5
P1_4
P1_3
P1_2
P1_1
P1_0
P0_7
P0_6
P0_5
P0_4
P0_3
P0_2
P0_1
P0_0
SCL
SDA
INT#
VSS
VDD
VCC
Y
GND
B
A
VCC
Y
GND
B
A
2
1
2
1
R4745
21
21
21 21
21 2
1
21
21
2
1
21
2
1
2
1
2
1
2
1
2
1
2
1
2
1
2
1
2
1
2
1
2
1
2
1
21 21 21
3
2
1
SHEETDATE
DEPARTMENT
SIZE
PROJECT DOCUMENT NUMBER REV
REVIEWER
DESIGNER
123
7 3 2 1 6 5 4
E
A
B
C
E
D
C
B
A
7 6 5 4
D
IN OUT
IN
OUT
IN
IN
BI
OUT
ININOUT
IN
IN
IN
IN
OUT
OUT
IN OUT
BIIN BIOUT
R4764
C2376
R3160
C580
C2346
C579
R1129 C578
C581
R1124
R1123
R1126 R1128
R3037 R1127
C



20210824 MODIFY FOR GTTO CPU1 PCIE PORT1 [15:0]DP/DN SWAPDP/DN SWAP
FRU ADDRESS:0X52DP/DN SWAPDP/DN SWAPDP/DN SWAPFROM CPU1 PCIE PORT1 [15:0]DP/DN SWAPDP/DN SWAPDP/DN SWAP20230414 CHANGE R3229 TO 200 OHM20230503 CHANGE R3228 TO 200 OHM
Fri Aug 25 14:02:26 2023N/AN/AV05159 OF 312N/AN/AP3V3_OCP_V3_2P3V3_OCP_V3_2 P3V3_OCP_V3_2
P3V3_OCP_V3_2P12V_OCP_V3_2
P12V_OCP_V3_2PCIE - V3_2 OCP3.0_X16(1/3)
CLK_50M_NCSI_OCP_V3_2_ISO1%SMB_OCP_V3_2_3V3AUX_BUF_SCLCHIP0402LFSMB_OCP_V3_2_3V3AUX_BUF_R_SCLSMB_OCP_V3_2_3V3AUX_BUF_R_SDARST_SMB_OCP_V3_2_N200CHIP200 0402LF1/16W1/16W1%OCP_V3_1_PRSNTA_R_NRST_PERST1_OCP_V3_2_NOCP_V3_2_PRSNT2_R_NCLK_100M_OCP_V3_2_B_DNCLK_100M_OCP_V3_2_B_DP207207SMB_OCP_V3_2_3V3AUX_BUF_SDAP5E_CPU1_PE1_RX_DN<15:0>P5E_CPU1_PE1_RX_DP<15:0>CLK_100M_OCP_V3_2_D_DN161161
162FM_OCP_V3_2_PWR_GOOD164161162159164160161161207207160160160159 160161213159159165162 16516116560161213159159213159213
160207160160159159213159213207159213161160160159214159160213 238238159160160161159 16021315921415921320717560207175162165159
160
180180
OCP_V3_2_AUX_PWR_EN OCP_V3_2_AUX_PWR_EN_ROCP_V3_2_BIF2_R_NCLK_100M_OCP_V3_2_D_DPNCSI_OCP_V3_2_TXD0NCSI_OCP_V3_2_TXD1NCSI_OCP_V3_2_TX_ENOCP_V3_2_AUX_PWR_ENCHIP0402LF
4.7KSGPIO_OCP_V3_2_LD_N1%CHIPOCP_V3_2_ID10402LF4.7K1%OCP_V3_2_PRSNT3_R_NTP_OCP_V3_2_B691%1/16W100CHIP0402LF
4.7K1/16WEMPTYOCP_V3_2_PRSNT1_R_NCHIP0.1UF25V10%X7R0402040210%10%25V0.1UFUSB2_5_R1_DNUSB2_5_R1_DPOCP_V3_2_PWRBRK_NPLACE THE BULK CAPS CLOSE TO SLOTSGPIO_OCP_V3_2_DATAOUTSGPIO_OCP_V3_2_CLK0402LFSGPIO_OCP_V3_2_DATAIN1%
NCSI_OCP_V3_2_CRS_DV1/16WCLK_100M_OCP_V3_2_C_DNNCSI_OCP_V3_2_RXD0NCSI_OCP_V3_2_RXD1OCP_V3_2_ID0SGPIO_OCP_V3_2_CLKSGPIO_OCP_V3_2_DATAOUTCLK_100M_OCP_V3_2_C_DPSGPIO_OCP_V3_2_DATAINRST_PERST0_OCP_V3_2_NOCP_V3_2_ISO_BIF2_ENOCP_V3_2_ISO_BIF1_ENCHIPOCP_V3_2_MAIN_PWR_EN_ROCP_V3_2_MAIN_PWR_ENFM_OCP_V3_2_PWR_GOOD0402LFOCP_V3_2_BIF0_R_NOCP_V3_2_ID1OCP_V3_2_ISO2_RBT_ARB_OUTOCP_V3_2_ISO1_RBT_ARB_INIRQ_LVC3_OCP_V3_2_WAKE_NRST_PERST3_OCP_V3_2_NRST_PERST2_OCP_V3_2_NOCP_V3_2_MAIN_PWR_EN0SGPIO_OCP_V3_2_LD_N5%0402LFCLK_100M_OCP_V3_2_A_DNP5E_CPU1_PE1_TX_C_DN<15:0>0402LF100K5%OCP_V3_2_BIF1_R_NCLK_100M_OCP_V3_2_A_DPP5E_CPU1_PE1_TX_C_DP<15:0>OCP_V3_2_PRSNT0_R_N0402LF5%00402LF0C080516V20%X6S22UF 22UF16V20%X6SC080510%X7R25V0402 0402X7R0.1UF25VX7R0.1UF040225VX7R10%04020.1UF 0.1UFX7R040210%25V 25V04020.1UF10%X7R04020.1UFX7R10%25VX7R10%0.1UF25VOCP_V3_2_ID0CHIP0402LF5%1/16W1%CHIP0402LF1/16W1%OCP_V3_2_ISO_BIF0_EN0402LF
1%0402LFEMPTY1/16W 1/16W4.7K0402LF1/16W1%
5%005%00
1/16W1%10KCHIP10K5%0402LFSMLFIOSCONN168_ME1016810202011
TP_OCP_V3_2_B680402LF1KCHIP1%1%10KCHIP1%10K1KCHIPCHIP1/16W1/16WUSB2_5_DNUSB2_5_DP
R3176
R3175
R3174
R3180
R3177
R3178
R3168
R3228
R3229
OA3
A69
A68
A9
A8
A7
OA6
OB7
B69
B68
OA12OB12
A15B15
OA11OB11
A14B14
OA8
OA9
OA7
OB8
OB9
OB14 OA14
OA5
OA4
A70B70
A12
A42B42
A10
B66
B63
B60
B57
B54
B51
B48
B45
B40
B37
B34
B31
B27
B24
B21
B18
B65
B62
B59
B56
B53
B50
B47
B44
B39
B36
B33
B30
B26
B23
B20
B17
OA2
OA1
A11
B10
A66
A63
A60
A57
A54
A51
A48
A45
A40
A37
A34
A31
A27
A24
A21
A18
A65
A62
A59
A56
A53
A50
A47
A44
A39
A36
A33
A30
A26
A23
A20
A17
OB1
OB2
OB3
OB13
OB10
OA13
OA10
B67
B64
B61
B58
B55
B52
B49
B46
B43
B41
B38
B35
B32
B29
B28
B25
B22
B19
B16
B13
A67
A64
A61
A58
A55
A52
A49
A46
A43
A41
A38
A35
A32
A29
A28
A25
A22
A19
A16
A13
A6
A5
A4
A3
A2
A1
G5
G4
G3
G2
G1
OB5
OB4
OB6
B9
B8
B7
B12
B6
B5
B4
B3
B2
B1
B11
14
3
1
3
12
15
12
5
4
6
8
0
1
15
4
0
9
9
1
1
2
5
0
2
4
6
7
8
10
5
6
7
8
11
13
11
14
0
2
6
14
12
14
15
15
9
7
7
5
3
3
8
13
10
11
13
9
10
13
12
11
4
2
10
J35
KEY
KEY
KEY
G5
G4
G3
G2
G1
PRSNTB3#
RFU1_NC_B69
RFU1_NC_B68
GND_B67
PETp15
PETn15
GND_B64
PETp14
PETn14
GND_B61
PETp13
PETn13
GND_B58
PETp12
PWRBRK0#
USB_DATp
USB_DATn
GND_A67
PERp15
PERn15
GND_A64
PERp14
PERn14
GND_A61
PERp13
PERn13
GND_A58
PERp12
PERn12
GND_A55
PERp11
PERn11
GND_A52
PERp10
PERn10
GND_A49
PERp9
PERn9
GND_A46
PERp8
PERn8
GND_A43
PRSNTB1#
GND_A41
PERp7
PERn7
GND_A38
PERp6
PERn6
GND_A35
PERp5
PERn5
GND_A32
PERp4
PERn4
GND_A29
GND_A28
PERp3
PERn3
GND_A25
PERp2
PERn2
GND_A22
PERp1
PERn1
GND_A19
PERp0
PERn0
GND_A16
REFCLKp1
REFCLKn1
GND_A13
PRSNTB2#
PERST1#
PRSNTA#
SMRST#
SMDAT
SMCLK
GND_A6
GND_A5
GND_A4
GND_A3
GND_A2
GND_A1
RBT_CLK_IN
GND_OA13
REFCLKp3
REFCLKn3
GND_OA10
RBT_TXD0
RBT_TXD1
RBT_TX_EN
SLOT_ID1
RBT_ARB_OUT
RBT_ARB_IN
WAKE#
PERST3#
PERST2#
PETn12
GND_B55
PETp11
PETn11
GND_B52
PETp10
PETn10
GND_B49
PETp9
PETn9
GND_B46
PETp8
PETn8
GND_B43
PRSNTB0#
GND_B41
PETp7
PETn7
GND_B38
PETp6
PETn6
GND_B35
PETp5
PETn5
GND_B32
PETp4
PETn4
GND_B29
GND_B28
PETp3
PETn3
GND_B25
PETp2
PETn2
GND_B22
PETp1
PETn1
GND_B19
PETp0
PETn0
GND_B16
REFCLKp0
REFCLKn0
GND_B13
AUX_PWR_EN
+3.3V_EDGE
PERST0#
BIF2#
BIF1#
BIF0#
+12V_EDGE_B6
+12V_EDGE_B5
+12V_EDGE_B4
+12V_EDGE_B3
+12V_EDGE_B2
+12V_EDGE_B1
RBT_CRS_DV
GND_OB13
REFCLKp2
REFCLKn2
GND_OB10
RBT_RXD0
RBT_RXD1
SLOT_ID0
CLK
DATA_OUT
DATA_IN
LD#
MAIN_PWR_EN
NIC_PWR_GOOD
21 21
21
21
21
2
1
2
1C1832
2
1C1838
2
1C1837
2
1C1836
2
1C1835
2
1C1834
2
1C1833
2
1C1831
2
1C1830
2
1C1829
21R3173
2
1
21 21
21R413
21R3164
21R3165
21R3172
21R3169 21R3170 21R3171
2
1
2
1
2
1
2
1
21
CAD NOTE:
SHEETDATE
DEPARTMENT
SIZE
PROJECT DOCUMENT NUMBER REV
REVIEWER
DESIGNER
123
7 3 2 1 6 5 4
E
A
B
C
E
D
C
B
A
7 6 5 4
D
OUT
OUT
ININ ININ
ININININ
OUT
OUT
OUT
IN
IN
OUT
OUT
IN
OUT
IN
IN
IN
OUTOUTININ
OUTOUT
IN
INBI
OUT
OUT
OUT
IN
IN
IN
IN
IN
INOUT
IN
IN OUTINININ
ININ
IN
OUT
OUT
OUT
OUT
OUTINOUT
C1839
R3162
R3163
R3166
R3167
C



20220803 POP R3205, DEPOP R3206
20210824 MODIFY FOR GT
Fri Aug 25 14:02:27 2023N/AV05N/AN/AN/A160 OF 312
P3V3_AUXP3V3_AUXP3V3_AUX
PCIE - V3_2 OCP3.0 (2/3)161159164161 154240159159159159159159213159
159159159159154240154240154240154240165154240159165
213CHIP1/16W74LVC1G126SE-7FB_BMC_ISOLATE11/16W5%OCP_V3_2_AUX_PWR_EN
ICSMLF04020.1UF25V0402X7RIC0.1UF25VX7R10%74CBTLV3126PWRMII_OCP_BMC_CRSDVNCSI_BMC_CRS_DV_R1NCSI_BMC_RXD0_R1NCSI_OCP_V3_2_CRS_DVNCSI_OCP_V3_2_RXD0NCSI_OCP_V3_2_RXD1OCP_V3_2_ISO1_RBT_ARB_IN OCP_V3_2_RBT_ARB_IN_R10%74CBTLV3126PWNCSI_OCP_V3_2_TXD00.1UFFM_OCP_V3_2_PWR_GOOD33.21%NCSI_OCP_V3_2_TX_EN0402LF10%04021%100CHIP1001%1/16W1001%1/16W0402LFCHIP CHIP1/16WOCP_V3_2_ISO_BIF2_ENOCP_V3_2_ISO_BIF1_ENOCP_V3_2_ISO_BIF0_EN0402LF0402LF
NCSI_OCP_V3_2_TXD11/16WCHIPRMII_BMC_OCP_TXD_0RMII_BMC_OCP_TX_ENSMLFSMLFNCSI_BMC_TXD1_R1NCSI_BMC_TXD0_R1RMII_OCP_BMC_RXD_022222200EMPTYEMPTYEMPTYEMPTYEMPTY0RMII_BMC_OCP_TXD_1EMPTYEMPTYOCP_V3_2_RBT_ARB_OUTNCSI_BMC_TX_EN_R1RMII_OCP_BMC_RXD_1NCSI_BMC_RXD1_R1OCP_V3_2_ISO2_RBT_ARB_OUT0402LF220OCP_V3_2_RBT_ARB_INCO-LAYOUT
EMPTY25VX7R0IC49.9FB_BMC_ISOLATE_R2CHIP1%100K1/16W0402LFCHIPFM_NCSI_OCP_V3_2_R_OE0402LFOCP_V3_2_AUX_PWR_EN_R1
R3203
R3217R3216R3208
4
1
2
R3210
R3209
R3211
R3212
R3213
R3214
R3215
53
U286
U223
U222
OE
Y
A
VCC
4OE
4A4B
3OE
3A
GND
1A
2B
1B
2OE
1OE
3B
2A
VCC
4OE
4A4B
3OE
3A
GND
1A
2B
1B
2OE
1OE
3B
2A
GND VCC
2121
2
1
2
1
2
1
2
1
2
1
2
1
2
1
R3207
21R3206
21
R3205
14
7
1311 12
108 9
46 5
13 2
14
7
1311 12
108 9
46 5
13 2
SHEETDATE
DEPARTMENT
SIZE
PROJECT DOCUMENT NUMBER REV
REVIEWER
DESIGNER
74CBTLV3126
74CBTLV3126
123
7 3 2 1 6 5 4
E
A
B
C
E
D
C
B
A
7 6 5 4
D
IN
OUTIN
OUT
OUT
OUT
OUT
IN
IN
IN
IN
OUT
OUT
OUT
IN
IN
IN
IN
IN
OUT
OUT
OUT
OUT
R3244
C1827
C1826
C1825
C



20210824 MODIFY FOR GT
20220120 ADD R4602Fri Aug 25 14:02:29 2023N/AN/AN/AN/AV05161 OF 312
P3V3_AUXP3V3_AUXP3V3_AUXP3V3_AUX
P3V3_AUXP3V3_AUXP3V3_AUXP3V3_AUXP3V3_OCP_V3_2P3V3_AUXPCIE - V3_2 OCP3.0 (3/3)159164160215154191227231233236245215155220159159160155159159
159159159164159 155 190 182OCP_V3_2_AUX_PWR_ENRST_SMB_SWITCH_NFM_SYS_THROTTLE_R_N0402LF0402LFOCP_V3_2_WAKE_BUFF_R_NCHIP0402LFOCP_V3_2_PWRBRK_BUFF_N04024.7K1/16WRST_PERST3_OCP_V3_2_N0402LF0.1UF25VNC_U218_NC133.21%4.7KOCP_V3_2_PWRBRK_NFB_BMC_ISOLATE1CLK_50M_NCSI_OCP_V3_2_ISO_RCLK_50M_NCSI_OCP_V3_274LVC1G66GVSMLFICCLK_50M_NCSI_OCP_V3_2_ISO0
1/16W10%1/16WIRQ_LVC3_V3_2_WAKE_BUF_N1/16W5%100KCHIPRST_SMB_OCP_V3_2_N0402X7RCHIPRST_OCP_V3_2_BUF_N
CHIP0402LF0 0.1UF25V10%X7R0402
74LVC1G07GV0.1UF10%X7RIC25V0.1UFX7R10%74LVC1G17GWSMLFIC1%1/16WCHIP0402LF33.21/16W1%33.21%0402LFCHIP33.21/16W1%1/16W33.20402RST_PERST0_OCP_V3_2_NCHIP0402LFSMLFRST_PERST2_OCP_V3_2_NRST_PERST1_OCP_V3_2_N0402LF1%CHIPRST_HP_OCP_V3_2_N25VPLACE R2487 CLOSE TO U157IC74LVC1G126SE-7SMLF1/16WCHIP1%33.21/16W4.7K1%0402LFEMPTY0.1UF25VCHIP1%33.20402LFICSMLF74LVC1G07GV1%1/16WCHIP10%X7R04020402LF1%10K1/16WCHIP10K1%1/16W0402LFIRQ_LVC3_OCP_V3_2_WAKE_NOCP_V3_2_WAKE_BUFF_NPU_OCP_V3_2_WAKE_OEIRQ_LVC3_WAKE_NNC_U219_NC1CHIPICSMLF74LVC1G126SE-70402LFCHIP1/16W1%10%0402X7R25V0.1UF1%33.2CHIP 1/16W0402LFRST_HP_OCP_V3_2_R_NOCP_V3_2_AUX_PWR_EN_R3
R3186
R3187
R3188
R3189
R3234
R3193
R3191
R3185
2
1 5
3
4
4
1
2
4
1
2
4
51
3
2
4
5
13
2
4
51
3
2
5353
U321
U217
U225
U219
U207
U218
VCC
E
GND
Z
Y
OE
Y
A
OE
Y
A
NC1
YGND
A
VCC
NC
Y
GND
A
VCC
NC1
YGND
A
VCC
GND VCCGND VCC
21R4602
2
1
21
2
1
R3235
21R3236
2
1
2
1
21
2
1
21
2
1
R3190
21
21
21
21
2
1
2
1
2
1
21
2
1
2
1
2
1
R3182
CAD NOTE:
R3183
SHEETDATE
DEPARTMENT
SIZE
PROJECT DOCUMENT NUMBER REV
REVIEWER
DESIGNER
123
7 3 2 1 6 5 4
E
A
B
C
E
D
C
B
A
7 6 5 4
D
OUT
IN
IN
IN
IN
IN OUT
OUT
OUT
OUT
OUT
IN
OUT
OUT
IN
C2345
C1841
R3192
C1824
C1823
R3184C1822
C1821
C



START UP TIME:3.94MSSTART UP TIME:8.21MS
20211108 MODIFY FOR GTUVP: 2.63VOVP: 3.89VDESIGN SPECIFICATIONIMAX=1.1AP3V3_OCP_V3_2_RP12V_OCP_V3_2OCP=IMAX*1.3=8.58AIMAX=6.6AOCP=IMAX*1.3=1.43A
OVP: 14.91VUVP: 10.17V20211130 CHANGE TO 1K OHM20211130 CHANGE TO 1K OHMVIMON(MAX)= 1.679V @ IOUT=9.03AVIMON(MAX)= 1.594V @ IOUT=1.6A
Fri Aug 25 14:02:31 2023N/AN/AN/AN/AV05162 OF 312P3V3_AUXP3V3_AUXP3V3_AUXP3V3_AUXP12V_AUXP3V3_AUXP3V3_AUX
P12V_AUXP12V_AUXP3V3_AUXP12V_OCP_V3_2P3V3_AUXP3V3_OCP_V3_2_R
V3_2_OCP3.0 HSC(1/3)
NIC1_P12V_MAM_MAM_BOM1NIC1_P12V_MAM_MAM_BOM1P12V_OCP_PWRGD_2P12V_OCP_FAULT_2NIC1_P12V_MAM_MAM_BOM1EMPTY1/16W1/16W1%845P12V_OCP_SENSE_2NIC1_P12V_MAM_MAM_BOM1NIC1_P12V_MAM_MAM_BOM10402LFEMPTYNIC1_P12V_MAM_MAM_BOM1NIC1_P12V_MAM_MAM_BOM1NIC1_P12V_MAM_MAM_BOM1NIC1_P12V_MAM_MAM_BOM1NIC1_P12V_MAM_MAM_BOM1NIC1_P12V_MAM_MAM_BOM1NIC1_P12V_MAM_MAM_BOM1NIC1_P12V_MAM_MAM_BOM1NIC1_P12V_MAM_MAM_BOM1NIC1_P12V_MAM_MAM_BOM1NIC1_P12V_MAM_MAM_BOM1NIC1_P12V_MAM_MAM_BOM1NIC1_P12V_MAM_MAM_BOM1NIC1_P12V_MAM_MAM_BOM1EMPTY05%0402LF1/16W5%01/16W0402LFEMPTYPJT138KEMPTYSMLF1/16WEMPTY1%10K0402LFSMLFPJT138KEMPTY0402LFEMPTY5%01/16W1%0402LFEMPTY1/16W160KC040225VEMPTY1UFEMPTYMAX15090BEWI+TSMLFEMPTY0402LF1%EMPTY0402LF1/16W10M1/16WEMPTY05%0402LF0402LF1/16W1%100KEMPTY EMPTY0402LF1/16W100K1%10EMPTY1%0402LF1/16WC04021UF25V1/16W1%6.8K1%1/16W15K0402LFEMPTY0402LF1/16W30.1KEMPTY1%C040250V3900PFP12V_OCP_CB_2P12V_OCP_UV_20402LF05%0.01UFP12V_OCP_REG_2P3V3_OCP_VCC_2P3V3_OCP_PWRGD_2P3V3_OCP_SENSE_24.53KNIC1_P3V3_BOM1NIC1_P3V3_BOM1NIC1_P3V3_BOM1NIC1_P3V3_BOM1NIC1_P3V3_BOM1NIC1_P3V3_BOM1NIC1_P3V3_BOM1NIC1_P3V3_BOM1NIC1_P3V3_BOM1NIC1_P3V3_BOM1NIC1_P3V3_BOM1NIC1_P3V3_BOM1NIC1_P3V3_BOM1NIC1_P3V3_BOM1NIC1_P3V3_BOM1NIC1_P3V3_BOM1NIC1_P3V3_BOM1NIC1_P3V3_BOM1100K1%0402LFCHIP1/16W1%100K1/16WCHIP0402LF0402LFCHIP1%10M1/16W1/16W05%CHIP0402LFC040250V6800PF0402LF1/16WCHIP1%101%0402LFCHIP1/16W1UFX6S25VC0402SMLFMAX15090BEWI+TIC0402LF1/16WCHIP5.36K1%25V1UFC040225.5K1%1/16WCHIP0402LF7.15K1%1/16WCHIP0402LFCHIP0402LF15K1%1/16W00402LF5%1/16WCHIPPJT138KICSMLF1/16W10K0402LFCHIP1%ICPJT138KSMLFP3V3_OCP_FAULT_2P3V3_OCP_GATE_2C0402P12V_OCP_V3_2_ISENSE_MAM_TICHP_LVC3_OCP_V3_2_ATTN_OUT_SW_N0EMPTY159165159165159165159165
164163238
164164216163 164214250250164P12V_OCP_EN_2_RP12V_OCP_2_EN_GP12V_OCP_UV_2_ROCP_V3_2_PRSNT1_R_NOCP_V3_2_PRSNT0_R_NOCP_V3_2_PRSNT2_R_NOCP_V3_2_PRSNT3_R_N
HP_LVC3_OCP_V3_2_ENP3V3_OCP_EN_2_RP3V3_OCP_2_EN_GP3V3_OCP_UV_2_R1P3V3_OCP_UV_2
HP_LVC3_OCP_V3_2_PRSNT2_N_R HP_LVC3_OCP_V3_2_PRSNT2_NP12V_OCP_VCC_2P12V_OCP_OV_2P12V_OCP_GATE_2HP_LVC3_OCP_V3_2_PRSNT2_PLD_NHP_LVC3_OCP_V3_2_P12V_PWRGDP12V_OCP_V3_2_ISENSE_MAM_MAMP3V3_OCP_OV_2P3V3_OCP_CB_2P3V3_OCP_REG_2 OCP_V3_2_P3V3_PWRGD
0402LFCHIP1K1%1/16W1K1%1/16WCHIP0402LF0402LFCHIP1%1/16W1K0402LFCHIP1K1%1/16WICSMLF74LVC2G07DW-7X7R040225V0.1UF10%IC74LVC2G07DW-7SMLFX7R04020.1UF25V10%
CHIP 1/16W0402LF5%04.7K5%0402LFCHIP1/16WSMF14AIC25VX6S1UFC0402C04021UFX6S25V
0402LF1/16W05%CHIPCHIP 1/16W0402LF5%1/16WCHIP00402LF5%0402LF1/16WCHIP10K1%CHIP1/16W1%10K0402LF0402LF10K1%1/16WCHIPR3867/R3868 CO-LAYOUTC040250VB340A-13-FIC25V0402X7R0.1UFX6SC080516V22UF 10UF16VC0805X6S50V0.01UFEMPTYB340A-13-F0402X7R0.1UF25VX6S10UFC080516V
G1
G2
G1
G2
D1S1CAS2 D2D1S1S2 D2
PC2149
C2148
PD107
R3826R3833
PC2152
PR3824
PC190
PC2150
PR3823
PC2146
PC2098
R4753
PR3795
PR3829
PC2139
PR3828
PC2137
PC2141
PC2151
PR3782
PR3822
R3825
R3143
PC2140
R3807
PR3806
R4065
R4059
R3816
R3831
R3142
PR3812
R4067
R4060
PR3805
R3832
PR3830
PR3821
PC2147
2
PC2142
PC2143
A2
D2
D1 D7
D3
D6
D4
C6
C4
B6
B4
A4
A1
D5
C5
C3
B5
B3
A5
A3
C2
C1
B2
A6
C7
B7
A7B1
A2
D2
D1 D7
D3
D6
D4
C6
C4
B6
B4
A4
A1
D5
C5
C3
B5
B3
A5
A3
C2
C1
B2
A6
C7
B7
A7B1
5
52
43
61
52
43
61
5
2
1 64 34 31 6
Q118
PD109
PD108
PU200
PU201
Q119
U58
U59
Q118
Q119
PG
FAULT#
GND_C2
GND_C1
GND_B2
CDLY
GATE
OUT_D6
OUT_D4
OUT_C6
OUT_C4
OUT_B6
OUT_B4
OUT_A4
ISENSEOV
UV
REG
EN#
CB
IN_D5
IN_C5
IN_C3
IN_B5
IN_B3
IN_A5
IN_A3
VCC
PG
FAULT#
GND_C2
GND_C1
GND_B2
CDLY
GATE
OUT_D6
OUT_D4
OUT_C6
OUT_C4
OUT_B6
OUT_B4
OUT_A4
ISENSEOV
UV
REG
EN#
CB
IN_D5
IN_C5
IN_C3
IN_B5
IN_B3
IN_A5
IN_A3
VCC
VCCGND
2Y
1Y
2A
1A
VCCGND
2Y
1Y
2A
1A
CACA
2
1
2
1
2
1
2
1
2
1
2
1
2
1
PR4522
21
2
1
2
1
2
1
21
2
1
2
1
2
1
21
2
1
2
1
2
1
2
1
2
1
2
1
2
1
2
1
2
1
21
21
2
1
2
1
2
1
2
1
2
1
2
1
2
1
21
21
21
2
1
2
1
2
1
21
2
1
2
1
2
1
2
1
CAD NOTE:
21212121CA
CACA
SHEETDATE
DEPARTMENT
SIZE
PROJECT DOCUMENT NUMBER REV
REVIEWER
DESIGNER
123
7 3 2 1 6 5 4
E
A
B
C
E
D
C
B
A
7 6 5 4
D
IN
OUT
OUT
OUT
IN
OUT
OUT
OUT
IN
IN
OUT
IN
PR4523
R3867
R3145
R4066
R3827
C1810
R3147
R3135R3133
R3136R3134
R3868
R4761C1809
C



ENABLE:VTH>1.391V(HIGH)TFAULT: 1.27MS
START UP TIME:4.7MSPOPPOPPU206 OPTIONAL BOMDE-POPMP5025C/DE-POPMP5022CPOPPC1320PR3852PR3850VIMON(MAX)= 1.582V @ IOUT=9.09ASTART UP TIME:8.62MSTDELAY: 6.29MS
20211108 MODIFY FOR GTCURRENT LIMIT=1.6ADESIGN SPECIFICATIONIMAX=6.6AOCP=IMAX*1.3=8.58AP12V_OCP_V3_2P3V3_OCP_V3_2_RIMAX=1.1AOCP=IMAX*1.3=1.43APR3857POPDE-POPDE-POPDE-POPMP5022AMP5025A/PR3853POPFri Aug 25 14:02:33 2023N/A V05163 OF 312N/AN/AN/AP12V_AUXP3V3_AUXNIC1_P12V_MPS_MAM_BOM3
P3V3_OCP_V3_2_RP3V3_AUX
P12V_OCP_V3_2P12V_AUXP3V3_AUXV3_2_OCP3.0 HSC-CO-LAYOUT(2/3)
HP_LVC3_OCP_V3_2_ENP3V3_OCP_EN_2P3V3_OCP_GATE_PU207_2P3V3_OCP_ILIMIT_2
R3873/R3874 CO-LAYOUT0402LF1%71.5KEMPTYEMPTY1/16W1%1000402LFP12V_OCP_AVIN_PD_2P12V_OCP_OV_FB_2P12V_OCP_V3_2_ISENSE_MPS_TICP12V_OCP_AVIN_PD_2P12V_OCP_FLTB_2P12V_OCP_IMON_2P12V_OCP_TIMER_2P12V_OCP_V3_2_EN_2_R3HP_LVC3_OCP_V3_2_ENP12V_OCP_V3_2_ISENSE_MPS_MAM
238163 162 164
163250163214162238163 162250
P3V3_OCP_MODE_2P3V3_OCP_DVDT_20.068UFEMPTY040216VEMPTYSMLFMP5016GQH-L-Z100PF50V0402EMPTY1%0402LF1.33KEMPTY1%71.5K0402LFEMPTYEMPTY 1/16W0402LF05%EMPTY39PFC040250VEMPTYC040225V10%1UF16V10UFC0805EMPTY10%NIC1_P3V3_BOM2NIC1_P3V3_BOM2NIC1_P3V3_BOM2NIC1_P3V3_BOM2NIC1_P3V3_BOM2NIC1_P3V3_BOM2NIC1_P3V3_BOM2NIC1_P3V3_BOM2NIC1_P3V3_BOM2
P12V_OCP_SS_20402LFEMPTY1/16W05%NIC1_P12V_MPS_MAM_BOM3HP_LVC3_OCP_V3_2_P12V_PWRGD20%C0603X7R2.2UF16VNIC1_P12V_MPS_MAM_BOM310%25V0.1UF0402X7RNIC1_P12V_MPS_MAM_BOM349.91/10WCHIP0603LF1%NIC1_P12V_MPS_MAM_BOM3120KCHIP0402LF1%1/16WNIC1_P12V_MPS_MAM_BOM31%CHIP10K0402LF1/16WNIC1_P12V_MPS_MAM_BOM3CHIP0402LF1/16W10K1%NIC1_P12V_MPS_MAM_BOM3ICRS31312RNIC1_P12V_MPS_MAM_BOM31UF25VC0402X6SNIC1_P12V_MPS_MAM_BOM35%01/16WCHIP0402LFNIC1_P12V_MPS_MAM_BOM30.047UFX7R25VC0402NIC1_P12V_MPS_MAM_BOM3100PF0402X7R50VNIC1_P12V_MPS_MAM_BOM317.4K1%1/16W0402LFCHIPNIC1_P12V_MPS_MAM_BOM3CHIP1/16W1%10K0402LF16V0.22UFNIC1_P12V_MPS_MAM_BOM31/16W0402LF1%CHIP14.3K1/16W5%0402LFCHIP0NIC1_P12V_MPS_TIC_BOM4164P12V_OCP_ISET_2NIC1_P12V_MPS_MAM_BOM3X7R0402164
R3848
PC1320
PC2174
PR3857PR3853
PR3854
PR3851
PR3849
PR3847
PR3856
R3631
20
19
18
17
16
15
14
13
26
25
24
23
21_22
4
6
10
11
2
5
87
9
3
1
12
PR3852
PU206
PU207
PC1321PC2168 PC1322PR3855
GND
SS
ISET
TIMER
ENTM
LOADEN
EN
VIN_26
VIN_25
VIN_24
VIN_23
IMON
FLTB
PG
OV
VOUT_13
AVIN
VOUT_14
VOUT_15
VOUT_16
VOUT_17
VOUT_18
VOUT_19
VIN_21_22
VOUT_20
SOURCE
GATE
DV_DT
VCC
GND
ILIMIT
MODE
EN
2
1
2
1
2
1
21
21
2
1
2
1
PC2167
2
1
PC2165
21
PC2166
2
1
PC217321
CAD NOTE:
PC2164
1_2 6_7
54 3
8
9
10
SHEETDATE
DEPARTMENT
SIZE
PROJECT DOCUMENT NUMBER REV
REVIEWER
DESIGNER
123
7 3 2 1 6 5 4
E
A
B
C
E
D
C
B
A
7 6 5 4
D
IN
OUT
OUT
OUT
OUT
IN
IN
R3873
R3874
PR3850R3630
PC2169
C



20210824 MODIFY FOR GT20220804 ADD R4763
20220224 ADD U323PUSH PULL OUTPUT20220224 CHANGE TO P3V3_OCP_V3_2PCA9554 ADDR: 0X4020220224 ADD R4616,R461520220803 DESIGN CHANGEFri Aug 25 14:02:34 2023N/AN/AN/AN/AV05164 OF 312I3
P3V3_AUXP3V3_OCP_V3_2P3V3_AUXP3V3_AUXP3V3_AUXP3V3_AUXP3V3_AUXP3V3_AUXP3V3_AUXP3V3_AUXP3V3_AUXV3_2_OCP3.0 HSC(3/3)
235164164235164235164164164162162163214162 163238164162164 161223164216213164216159 160161
162 16416216410K0402LFHP_LVC3_OCP_V3_2_PWRGD74LVC1G08W5-7SMLF0402LFHP_OCP_V3_2_RST_RTP_PCA9555_U51_P00PCA9555APWIC5%SMB_PEHPCPU1_LVC3_SCL1/16W1%X7R10%EMPTY0402LF1K10%04020.1UF25VSMB_PEHPCPU1_LVC3_R3_SCLSMB_PEHPCPU1_LVC3_R3_SDAFM_SMB_PEHPCPU1_PCIE_ALERT_NFM_SMB_CPU1_ALERTSMB_PEHPCPU1_LVC3_SDA0402LF0402LF0402LF1KCHIP1/16W1%1/16W1KCHIP1%EMPTY0402LF1/16W1K1%0402LFEMPTY1/16W1%0402LFEMPTY1K1%04020.1UF25VX7R04020.1UF25V10%X7R1K1/16WCHIP1%10%1/16W1KICSMLFFM_SMB_CPU1_ALERTTP_PCA9555_U51_P05TP_PCA9555_U51_P06TP_PCA9555_U51_P07TP_PCA9555_U51_P10TP_PCA9555_U51_P11TP_PCA9555_U51_P12TP_PCA9555_U51_P13TP_PCA9555_U51_P14TP_PCA9555_U51_P15TP_PCA9555_U51_P16TP_PCA9555_U51_P17PD_SMB_OCP2_HP_ADD0PD_SMB_OCP2_HP_ADD2PD_SMB_OCP2_HP_ADD1SMB_PEHPCPU1_LVC3_R3_SDASMB_PEHPCPU1_LVC3_R3_SCLOCP_V3_2_P3V3_PWRGDSMLFAPX809-29SAG-7CHIP1%1%0402LF33.233.21/16WX7REMPTY01%33.204021%0402LFHP_OCP_V3_2_RST33.2CHIPHP_LVC3_OCP_V3_2_P12V_PWRGDICSMLFIC0402LF0402LFICSMLF74LVC1G08W5-7ICBSS138K040210%0.1UFX7R25V1K0402LFCHIP1%1/16WHP_LVC3_OCP_V3_2_PRSNT2HP_LVC3_OCP_V3_2_ENHP_OCP_V3_2_ENHP_LVC3_OCP_V3_2_PRSNT2_N5%0EMPTY0402LF49.9040210%IC00402LF5%EMPTY1%0402LF0402LF1%33.225V0.1UF0402LF1%33.274LVC1G08W5-7RST_HP_OCP_V3_2_NRST_OCP_V3_2_N1%0402LF1/16WCHIPCHIPHP_LVC3_OCP_V3_2_PWRGD_ROCP_V3_2_AUX_PWR_PLD_ENHP_LVC3_OCP_V3_2_PWRGD_R25V0.1UFOCP_V3_2_AUX_PWR_ENCHIPOCP_V3_2_AUX_PWR_EN_R2OCP_V3_2_AUX_PWR_PLD_EN_RHP_LVC3_OCP_V3_2_PWRGD_R2CHIP33.210KX7R74LVC1G08W5-7SMLF
TP_PCA9555_U51_P01HP_LVC3_OCP_V3_2_PRSNT2_NHP_LVC3_OCP_V3_2_ATTN_OUT_SW_N1/16W1%CHIPHP_OCP_V3_2_EN
U215
R4757
R4759
R4758
R4754
R4755
R4616
R4617
R4615
R3157
R3156
R3158
G
S D
4
5
3
2
1
4
5
3
2
1
12
24
23
22
20
19
18
17
16
15
14
13
11
10
9
8
7
6
5
4
1
3
2
21
4
5
3
2
1
4
5
3
2
1
U335
U323
U216
U51
U53
U50
VCC
Y
GND
B
A
VCC
Y
GND
B
A
GND
RESET_L
VCC
A2
A1
A0
P1_7
P1_6
P1_5
P1_4
P1_3
P1_2
P1_1
P1_0
P0_7
P0_6
P0_5
P0_4
P0_3
P0_2
P0_1
P0_0
SCL
SDA
INT#
VSS
VDD
VCC
Y
GND
B
A
VCC
Y
GND
B
A
2
1
21
21
2
1
21
2
1
R4756
21
21
21
21
21
2
1
2
1
2
1
2
1
2
1
21
2
1
2
1
2
1
2
1
21
2
1
2
1
21
2
1
2
1
3
2
1
SHEETDATE
DEPARTMENT
SIZE
PROJECT DOCUMENT NUMBER REV
REVIEWER
DESIGNER
123
7 3 2 1 6 5 4
E
A
B
C
E
D
C
B
A
7 6 5 4
D
IN
IN
IN
BI
INBI
OUT
IN
IN
OUT
INININ
BIOUT
OUT
IN OUT
OUT
OUT
OUT
IN
IN
IN
R4763
C2377
R1132
C2347
C1819
C1820
C1817
R3151
R3152R3150 R3154
R3153R3149
C1818R3155
C



20210922 MODIFY FOR GT
Fri Aug 25 14:02:36 2023N/AN/AN/AN/AV05165 OF 312
P3V3_AUXP3V3_AUXP3V3_AUX
P3V3_AUXP3V3_AUXP3V3_AUXP3V3_AUX
OCP3.0 NCSI160154153156153156165159162159162159162159162153156153156165165165160154OCP_V3_2_NOT_PRSNT_RBT_ARB_INOCP_V3_2_PRSNT_ALL_R1_N0.1UFOCP_SFF_PRSNT_ALL_R3_NOCP_SFF_RBT_ARB_IN_MUX1_REMPTYEMPTYEMPTYEMPTYOCP_V3_2_RBT_ARB_OUTNC7SB3157P6XNC7SB3157P6XNC7SB3157P6XNC7SB3157P6XOCP_SFF_NOT_PRSNT_RBT_ARB_IN74LVC2G08DPOCP_SFF_RBT_ARB_IN0.1UF74LVC2G08DPOCP_V3_2_PRSNT01_R_NOCP_SFF_PRSNT23_R_NOCP_SFF_PRSNT01_R_N74LVC2G08DPIC0.1UFOCP_SFF_PRSNT1_R_NOCP_SFF_PRSNT0_R_NSMLF04020.1UFOCP_SFF_RBT_ARB_IN_MUX1OCP_V3_2_PRSNT3_R_NOCP_V3_2_PRSNT2_R_NOCP_V3_2_PRSNT0_R_NOCP_V3_2_PRSNT1_R_NOCP_SFF_PRSNT3_R_NOCP_SFF_PRSNT2_R_NOCP_V3_2_PRSNT23_R_NOCP_SFF_RBT_ARB_IN_MUX2OCP_V3_2_PRSNT_ALL_R_NOCP_SFF_RBT_ARB_IN_MUX2_ROCP_V3_2_PRSNT_ALL_R3_NOCP_SFF_RBT_ARB_IN_MUX1OCP_SFF_PRSNT_ALL_R_NOCP_SFF_RBT_ARB_IN_MUX2OCP_SFF_PRSNT_ALL_R1_N
OCP_V3_2_RBT_ARB_INOCP_SFF_RBT_ARB_OUTIC74LVC2G08DPSMLFICSMLF74LVC2G08DPICSMLF74LVC2G08DPX7R10%25V0.1UF0402X7R10%25VICSMLF1/16W0CHIP5%0402LF00402LFCHIP5%1/16WCHIP0402LF5%1/16W0IC040210%25VX7RCHIP05%1/16W0402LFCHIP0402LF1/16W5%0CHIP0402LF1/16W5%010%X7R040225V04020.1UF25V10%X7R0.1UF10%X7R040225V040225V10%X7R
R3307
R3306
R3308
R3305
R3304
R3303
C1878
C1877
C1879
C1880
5
6
2
1
34
5
6
2
1
34
5
6
2
1
34
5
6
2
1
34
S
B0
B1
VCC GND
A
S
B0
B1
VCC GND
A
S
B0
B1
VCC GND
A
S
B0
B1
VCC GND
A
3
6
5
7
2
1
3
6
5
7
2
1
3
6
5
7
2
1
848484
U245
U246
U244
U243
U242
U242
U240
U240
U241
U241
2Y
2B
2A
2Y
2B
2A
1Y
1B
1A
2Y
2B
2A
1Y
1B
1A
1Y
1B
1A
GND VCCGND VCCGND VCC
21
21
21
21
21
21
2
1
2
1
2
1
2
1
2
1
2
1
2
1
SHEETDATE
DEPARTMENT
SIZE
PROJECT DOCUMENT NUMBER REV
REVIEWER
DESIGNER
123
7 3 2 1 6 5 4
E
A
B
C
E
D
C
B
A
7 6 5 4
D
IN
IN
IN
IN
IN
OUT
OUTIN
OUT
IN
IN
OUT IN
IN
IN
IN
C1876
C1874
C1875
C



FROM GPU FPGAFROM BMC20210929 MODIFY FOR GT
Fri Aug 25 14:02:37 2023N/AN/AN/AN/A166 OF 312V05P3V3_AUXP3V3_AUXP3V3_AUX
P3V3_AUXP3V3_AUX P3V3_AUXP3V3_AUX
FPGA- PCIE - RE-DRIVER
167167166167167166166166166166166166212167166166166166
1661661661661661661661671671671672121661670402LFEMPTYEMPTY1/16W1%P2E_MB_BMC_TX_C_R1_DN<0>P2E_MB_BMC_TX_C_R1_DP<0>FM_P2E_EQB1P2E_MB_BMC_RX_R1_DP<0>P2E_MB_BMC_RX_R1_DN<0>FM_P2E_SWBFM_P2E_FGA68K0402LFEMPTY1/16W1/16W1/16WPCIE REDRIVER1_BOM11%EMPTYFM_P2E_EQB1FM_P2E_EQB0PCIE REDRIVER1_BOM1
PCIE REDRIVER1_BOM1
EMPTY1/16W1%1K68K1KFM_P2E_SWA0402LF0402LFFM_P2E_MODEPCIE REDRIVER1_BOM1CLK_GEN2_GPU_FPGA_OE_OR_N10%25V0.1UFPCIE REDRIVER1_BOM1PCIE REDRIVER1_BOM1PCIE REDRIVER1_BOM1PCIE REDRIVER1_BOM10.1UF10UF25V0.1UFFM_P2E_FGBPCIE REDRIVER1_BOM10402X7R10%25V0402PU_TESTPCIE REDRIVER1_BOM1PCIE REDRIVER1_BOM1FM_P2E_FGB0402LF0402LFEMPTYFM_P2E_EQA1FM_P2E_EQA01K1%0402LF1K1%1/16WCHIP1/16W1%1KEMPTY4.7KEMPTY1/16W4.7K0402LFCHIP1/16WCHIPFM_P2E_MODEX7R10%10%25V10%FM_P2E_FGAFM_P2E_EQA0FM_P2E_EQB0FM_P2E_EQA1FM_P2E_SWAFM_P2E_SWBFM_P2E_EN_NP2E_MB_BMC_RX_BUF_C_DN<0>P2E_MB_BMC_RX_BUF_C_DP<0>P2E_MB_BMC_TX_BUF_DN<0>P2E_MB_BMC_TX_BUF_DP<0>CLK_GEN2_GPU_FPGA_OE_OR_N
EMPTY1/16W1%0402LF68K0402LF1%1K1/16WEMPTY1%1/16W68K0402LFEMPTY0402LF1/16WCHIP0402LF1%1K1/16WEMPTY68K0402LFEMPTY0402LF1%1K1/16W1K1%EMPTY0402LF1%1K1/16W1%1%1KEMPTY0402LF1/16W1%1/16W68K0402LFEMPTY1%0402LF1/16WEMPTY68K0402LFEMPTY1/16W1%EMPTY1K
X6SC0805ICSMLFPI3EQX12902AZLEX0.1UFX7R25VX7R0402 0402
0402LF0402LF1K1%EMPTY1/16W0402LF68KEMPTY1/16W1%1/16W1%1K0402LF1K0402LF1%1/16W1%1/16WEMPTY0402LFEMPTY1%1K1/16W0402LF04.7KEMPTY1/16W0402LF1%EMPTY1/16W4.7K1%0402LFCHIP1/16W0402LF1%1%4.7K1%
R3286
R3285
R3280
R3269
R3267
R3271
R3268 R3279
25
16
10
1
512
29
30
TH
28
22
19
13
7
6
4
14
27
15
20
26
21
11
9
8
17
18
24
23
2
3
U237
GND_TH
MODE
SWA
GND7
FGA
EQA1
VDD4
AOP
AON
GND6
EQA0
EQB0
GND5
BIN
BIP
VDD3
EQB1
FGB
GND4
SWB
EN#
VDD2
BOP
BON
GND3
GND2
TEST#
GND1
AIN
AIP
VDD1
2
1
2
1
2
1
2
1
2
1
2
1
2
1
2
1
2
1
2
1
2
1
2
1C1865
2
1C1864
2
1C1863
2
1
2
1
2
1
2
1
2
1
2
1
2
1
2
1
2
1
2
1
2
1
2
1
2
1
2
1
21
2
1
2
1
2
1
2
1
2
1
2
1
SHEETDATE
DEPARTMENT
SIZE
PROJECT DOCUMENT NUMBER REV
REVIEWER
DESIGNER
123
7 3 2 1 6 5 4
E
A
B
C
E
D
C
B
A
7 6 5 4
D
OUT
OUT
OUTOUT
OUTOUT
IN
IN
OUTOUT
OUTOUT
ININ
IN
IN
IN
ININ
ININ
IN
ININ
OUTOUT
OUTOUT
R3266
R3292
R3265
R3291
R3288R3287
R3283
R3284
C1866
R3282
R3275
R3276R3273R3270
R3278R3274R3272
R3293
R4537
R3289
R3290
C1867
R3281
R3277
C



TO GPU FPGAC1870,C2351 CO-LAYC1871,C2352 CO-LAYTO BMCTO 2ND REDRIVERTO 1ST REDRIVERTO 2ND REDRIVERTO 1ST REDRIVERR4664,R4666 CO-LAYC1868,C2353 CO-LAYC1869,C2354 CO-LAYFROM 2ND REDRIVERR4663,R4665 CO-LAYR4660,R4662 CO-LAYR4659,R4661 CO-LAYFROM 2ND REDRIVERFROM 1ST REDRIVERFROM 1ST REDRIVERFROM BMCFROM FPGA
Fri Aug 25 14:02:38 2023V05167 OF 312N/AN/AN/AN/AP3V3_AUXP3V3_AUXP3V3_AUXP3V3_AUXP3V3_AUX
P3V3_AUX
P3V3_AUXFPGA- PCIE - RE-DRIVER(CO-LAYOUT)
167167167167167167167167143143167167166166
167167167167166166143143166 167167167167167167240167167240166167167167167167167
167
167240240166166167167166212167167PCIE REDRIVER1_BOM2P2E_BUF2_VDDPCIE REDRIVER1_BOM2PCIE REDRIVER1_BOM2PCIE REDRIVER1_BOM210UFC0805FM_P2E_BUF2_EQA0FM_P2E_BUF2_EQA1FM_P2E_BUF2_EQB1FM_P2E_BUF2_EQB0FM_P2E_BUF2_VODA_DBPCIE REDRIVER1_BOM2EMPTY0402LFFM_P2E_BUF2_EQA1FM_P2E_BUF2_EQA0FM_P2E_BUF2_EQB11K1/16WCHIP0402LF1/16WEMPTYPCIE REDRIVER1_BOM20402LF0402LFEMPTY1/16WP2E_MB_BMC_TX_BUF_C_DN<0>P2E_MB_BMC_TX_BUF_C_DP<0>P2E_MB_BMC_RX_R2_DN<0>P2E_MB_BMC_RX_R2_DP<0>P2E_MB_BMC_RX_R1_DN<0>P2E_MB_BMC_RX_R1_DP<0>0402LF0402LF0402LF0402LFX7R25V10%PCIE REDRIVER1_BOM1PCIE REDRIVER1_BOM1EMPTY0402LFFM_P2E_BUF2_VODB_DBP2E_MB_BMC_RX_BUF2_C_DP<0>P2E_MB_BMC_TX_BUF2_DN<0>P2E_MB_BMC_TX_BUF2_DP<0>0.1UF25VP2E_MB_BMC_RX_BUF_C_DP<0>P2E_MB_BMC_RX_BUF_C_DN<0>CHIP0P2E_MB_BMC_RX_DN<0>P2E_MB_BMC_RX_DP<0>CHIP0CHIPEMPTYEMPTYP2E_MB_BMC_TX_BUF_DP<0>EMPTYEMPTY0402LF1%1%1/16WEMPTY1/16W1%1K1K1/16W1/16W1%1K
P2E_MB_BMC_RX_BUF2_C_DN<0>P2E_MB_BMC_RX_BUF2_C_DP<0>P2E_MB_BMC_TX_BUF2_DN<0>P2E_MB_BMC_TX_BUF2_DP<0>FM_P2E_BUF2_VODB_DB1/16W1%P2E_MB_BMC_TX_C_R2_DP<0>10%X6S10%EMPTYEMPTYP2E_MB_BMC_TX_C_DP<0>1KP2E_MB_BMC_TX_C_R2_DN<0>
1%CHIP1/16W1/16W1%1%1/16W1K
0P2E_MB_BMC_RX_BUF2_C_DN<0>P2E_MB_BMC_TX_C_DN<0>
1%1/16WP2E_MB_BMC_TX_BUF_DN<0>00402LFCHIPP2E_MB_BMC_RX_R2_DN<0>P2E_MB_BMC_RX_R2_DP<0>0402LFEMPTY25V0.1UFX7RFM_P2E_BUF2_EQB0FM_P2E_BUF2_RXDETFM_P2E_BUF2_SD_THFM_P2E_BUF2_VOD_SEL
NC_RES
1K0402LFCHIP0402LF1%CHIP1K1%CHIP1K1K1%0402LFEMPTY1%1K0402LF0.1UF04020402LF
1/16WEMPTY0402LF1%1KEMPTY0402LF1/16W1%0402LF1KEMPTY1K0402LFEMPTY1K0402LF1%1K1%1K1/16W1/16W1%0402LF1KEMPTY0402LFCHIP
C040225V10%16V25V0CHIPFM_P2E_BUF2_VOD_SEL1/16W
000402LF00EMPTY1K1/16W1%EMPTYFM_P2E_BUF2_VODA_DBPCIE REDRIVER1_BOM2PCIE REDRIVER1_BOM21/16WPCIE REDRIVER1_BOM20402LFP2E_MB_BMC_RX_BUF_DN<0>PCIE REDRIVER1_BOM2PCIE REDRIVER1_BOM2PCIE REDRIVER1_BOM2P2E_MB_BMC_RX_BUF_DP<0>PCIE REDRIVER1_BOM1PCIE REDRIVER1_BOM1PCIE REDRIVER1_BOM2PCIE REDRIVER1_BOM2PCIE REDRIVER1_BOM2PCIE REDRIVER1_BOM2PCIE REDRIVER1_BOM1CHIPPCIE REDRIVER1_BOM1PCIE REDRIVER1_BOM10402LFPCIE REDRIVER1_BOM1P2E_MB_BMC_TX_C_R1_DP<0>P2E_MB_BMC_TX_C_R1_DN<0>P2E_MB_BMC_TX_C_R2_DP<0>P2E_MB_BMC_TX_C_R2_DN<0>PCIE REDRIVER1_BOM2PCIE REDRIVER1_BOM2PD_P2E_BUF2_ENSMBPCIE REDRIVER1_BOM2X7R10%EMPTYCLK_GEN2_GPU_FPGA_OE_OR_N0402LFFM_P2E_BUF2_SD_THFM_P2E_EN2_NFM_P2E_BUF2_RXDET0.1UFPCIE REDRIVER1_BOM2PCIE REDRIVER1_BOM2SMLFDS125BR111RTWR04020402X6S1UF
C1871
C1870
C2351
C1869
C1868
C2354
C2352
C2353
R4648R4644
R4642
R4651
17
15
16
22
21
25
4
14
5
18
13
6
19
20
8
7
12
11
23
24
2
1
9
10
3
U328
TH_GND
INA+
INA-
VDD_22
VDD_21
OUTB+
OUTB-
RXDET||DONE#
VOD_SEL||READEN#
VDD_SEL
VIN
SD_TH
RES
INB-
INB+
EQA0||AD0
EQA1||AD1
OUTA-
OUTA+
PWDN
SCL||VODB_DB
SDA||VODA_DB
ENSMB
EQB1||AD2
EQB0||AD3
2
1C2357
2
1
C2356
2
1
C2355
2
1
2
1
2
1
2
1
2
1
2
1
2
1
21R4659 21R4660
21R4661 21R4662
21R4664
21R4663
21R4665 21R4666
21 21
21
21 21
21
2
1
2
1
2
1
2
1
21
2
1C2358
2
1
2
1
2
1
2
1
21
21
2
1
2
1
2
1
2
1
SHEETDATE
DEPARTMENT
SIZE
PROJECT DOCUMENT NUMBER REV
REVIEWER
DESIGNER
123
7 3 2 1 6 5 4
E
A
B
C
E
D
C
B
A
7 6 5 4
D
ININ
IN
IN
ININ
ININ
ININ
OUTOUT
OUTOUT
OUT
OUT
OUTOUT
OUTOUT
OUTOUT
OUT
OUT
OUT
OUT
OUTOUT
ININ
ININ
ININ
ININ
ININ
ININ
OUTOUT
OUT
IN
IN
IN
IN
OUTOUT
OUTOUT
R4658
R4649
R4650
R4657R3381
R3362
R4643
R4694
R3386
R4654
R4656R4655
R4645
R4646
R4647R4653
C



Thu Aug 24 16:14:28 2023N/AN/AN/AN/A168 OF 312V05BLANK
SHEETDATE
DEPARTMENT
SIZE
PROJECT DOCUMENT NUMBER REV
REVIEWER
DESIGNER
123
7 3 2 1 6 5 4
E
A
B
C
E
D
C
B
A
7 6 5 4
D
C



TO PCHTO SCM20211209 MODIFY FOR GTFROM PCH20220316 ADD R4636,R4637,C2349,C2350FROM SCM
Fri Aug 25 14:02:39 2023N/AN/AN/AN/AV05169 OF 312P3V3_AUXP3V3_AUXP3V3_AUXP3V3_AUXP3V3_AUXP3V3_AUX
USB3.0 REDRIVER169169
240240169169181181169169169169169169169169169169181181240240169169
FM_USB3_1_EQAFM_USB3_1_EQB
USB3_PCH_RX_DP<4>USB3_PCH_RX_DN<4>FM_USB3_1_FGBFM_USB3_1_FGA
P3V3_AUX_USB_BUFUSB3_PCH_TX_C_DN<4>USB3_PCH_TX_C_DP<4>FM_USB3_1_EQBFM_USB3_1_EQAFM_USB3_1_SWBFM_USB3_1_SWAFM_USB3_1_FGBFM_USB3_1_FGAUSB3_PCH_RX_C_DP<4>USB3_PCH_RX_C_DN<4>USB3_PCH_RX_BUF_C_DN<4>USB3_PCH_RX_BUF_C_DP<4>USB3_PCH_TX_BUF_DN<4>USB3_PCH_TX_BUF_DP<4>FM_USB3_1_EN_NFM_USB3_1_RXDET_ENFM_USB3_1_SWBFM_USB3_1_SWAUSB3_PCH_RX_BUF_DN<4>USB3_PCH_RX_BUF_DP<4>USB3_PCH_TX_BUF_C_DN<4>USB3_PCH_TX_BUF_C_DP<4>FM_USB3_1_EN_NFM_USB3_1_RXDET_EN
1/16WCHIP0402LF1%68K0402LF1/16W1%1KEMPTYCHIP1/16W1%68K0402LF0402LFEMPTY1K1%1/16W0402LF1K1/16W1%EMPTYEMPTY0402LF1K1%1/16W1K1%1/16WEMPTY0402LFEMPTY1%1K0402LF1/16W1%1/16W200K0402LFCHIP CHIP1/16W200K1%0402LFDIFF BUS_0.33UF10%C0402C040210%DIFF BUS_0.33UFSMLFBLM15PX121SN1D/2AIND20%C080522UF16VX6S
1/16W1%EMPTY0402LF1K1%1/16W1KEMPTY0402LF
PI3EQX1002EZREXSMLFIC0.1UF25VX7R10%0402 0402X7R0.1UF25V10%
0402LFEMPTY1/16W1K1%0402LFEMPTY1%1K1/16W0.1UFX6S0.1UFX6S0.1UFX6S6.3VC020110%X6S0.1UF0402LF1%4.7K1/16WEMPTY1/16WEMPTY4.7K1%0402LF1%4.7K1/16W0402LFEMPTY4.7K1%1/16W0402LFEMPTY
21
21
L18
C2289
C2290
C2291
C2292
R4273
R4275
R4284
17
5
TH
14
3 13
22
21
20
10
9
8
15
2
16
1 4
12
11
18
19
24
23
6
7
21
21
21
U309
C2349
C2350
GND_4
BOP
BON
GND_5
GND_3
EQB
GND_1
SWA
BIP
SWB
BIN
FGB
TH_GND
AIP
RXDET_EN
FGA
EQA
AIN
GND_6
AOP
AON
VDD_1
EN
VDD_2
GND_2
1 2
2
1
2
1
21 21
21 21
2
1
2
1
2
1C2286
2
1C2285
2
1
2
1C2284
2
1
2
1
2
1
2
1
2
1
2
1
2
1
2
1
2
1
2
1
R4637
2
1
2
1
2
1
R4636
SHEETDATE
DEPARTMENT
SIZE
PROJECT DOCUMENT NUMBER REV
REVIEWER
DESIGNER
123
7 3 2 1 6 5 4
E
A
B
C
E
D
C
B
A
7 6 5 4
D
OUTOUT
OUT
OUT
OUTOUT
OUTOUT
IN
IN
OUTOUT
IN
ININ
IN
ININ
ININ
OUTOUT
ININ
R4289
R4291
R4287
R4288R4285
R4279
R4282R4276
R4290
R4292
R4280R4274
R4281
C



20211201 MODIFY FOR GTADDRESS : 0X90ADDRESS : 0X90ADDRESS : 0X90
ADDRESS : 0X90
Fri Aug 25 14:02:40 2023N/AN/AN/AN/AV05170 OF 312P3V3_AUXP3V3_AUXP3V3_AUX
P3V3_AUXP3V3_AUXP3V3_AUXP3V3_AUXP3V3_AUXP3V3_AUXP3V3_AUXP3V3_AUX
P3V3_AUX
TEMP SENSOR - LM75
233170214233233233251305
170214233
233251305233
233170214170214
200K1%1/16WEMPTY0402LFEMPTY1/16W0402LF1%200K200K1%0402LF1/16WEMPTY1%1/16WCHIP0402LF200K1/16W0402LF0402LFFM_G751_0_ALERT_N1%SMB_LM75_1_3V3AUX_SCLFM_THERMAL_ALERT_NSMB_LM75_2_3V3AUX_SCLSMB_LM75_2_3V3AUX_SDA1%1/16WSMB_LM75_0_3V3AUX_SDASMB_LM75_1_3V3AUX_SDA_R1
FM_THERMAL_ALERT_NCHIP0402LF0402LF33.2FM_G751_1_ALERT_NSMB_LM75_1_3V3AUX_SCL_R1SMB_LM75_3_3V3AUX_SDA
SMB_LM75_0_3V3AUX_SCL SMB_LM75_0_3V3AUX_SCL_R1SMB_LM75_0_3V3AUX_SDA_R1SMB_LM75_1_3V3AUX_SDAFM_LM75_2_ALERT_NSMB_LM75_2_3V3AUX_SCL_R1SMB_LM75_2_3V3AUX_SDA_R1FM_LM75_3_ALERT_NSMB_LM75_3_3V3AUX_SCL_R1SMB_LM75_3_3V3AUX_SDA_R1SMB_LM75_3_3V3AUX_SCL1/16W CHIP1%0402LF1%IC0.1UF10%0402EMPTY0402LFEMPTY EMPTYU273_3_ADD0U273_3_ADD1U273_3_ADD20402LF00402LFCHIP1/16W 33.20402LFCHIP33.21%LM75BDSMLFSMLFICLM75BDU272_2_ADD1U272_2_ADD20402LF0402LF0402LF0CHIP1/16WCHIP1/16W1%1%33.2CHIPU272_2_ADD0LM75BDICSMLFU271_1_ADD010%U271_1_ADD1U271_1_ADD225V0.1UFFM_THERMAL_ALERT_N33.21%0402LF0CHIP1/16W1%33.2CHIP1/16WLM75BDICSMLF1%1%U270_0_ADD1U270_0_ADD2CHIPCHIPFM_THERMAL_ALERT_N1%33.233.200402LFCHIPU270_0_ADD0EMPTY1%0402LF1K1/16W0402LFEMPTY1K1/16W1%1%1K1/16W0402LFCHIP1/16W1K0402LFCHIP0402LFEMPTY1K1/16W1%1/16W1K0402LFCHIPX7R10%25V0.1UF0402EMPTY1%0402LF1K1/16W0402LFEMPTY1K1/16W1%1K1/16W0402LFCHIP1/16W1K0402LFCHIP0402LFEMPTY1K1/16W1%1%1/16W1K0402LFCHIPX7R10%0402CHIP0402LF1K1/16W1%1/16W1K0402LF1%EMPTY1%1/16W1KEMPTY0402LFCHIP0402LF1/16W1K1%CHIP0402LF1K1/16W1%1%1/16W1KEMPTY0402LF04020.1UF25VX7R1%0402LF1K1/16W1K1/16W1%1%1K1/16W0402LFCHIP1%1/16W1K0402LFCHIP1K1%1/16W1K0402LFCHIP1/16W1%X7R25V
R4209
R4208
R4210
R4211
R4200R4192
R4201R4193
R4184
R4185
R3554
R4212
R3553
R4202R4194
R4203R4195
R4186
R4187
R4181
R4213
R4178
R4179
R4214
R4182
R4189
R4188
R4197 R4205
R4196 R4204
R4190
R4191
R4206
R4207
R4198
R4199
R4215
R4183
R4180
81
2
3
4 5
6
7
81
2
3
4 5
6
7
81
2
3
4 5
6
7
81
2
3
4 5
6
7
U273
U272
U271
U270
VCC
A0
A1
A2GND
OS
SCL
SDA
VCC
A0
A1
A2GND
OS
SCL
SDA
VCC
A0
A1
A2GND
OS
SCL
SDA
VCC
A0
A1
A2GND
OS
SCL
SDA
2
1
2
1
2
1
2
1
2
1
2
1
2
1
2
1
2
1
2
1
2
1
21
21
21
2
1
2
1
2
1
2
1
2
1
2
1
2
1
21
21
21
21
21
21
2
1
2
1
2
1
2
1
2
1
2
1
2
1
2
1
2
1
2
1
2
1
2
1
2
1
21
21
21
2
1
SHEETDATE
DEPARTMENT
SIZE
PROJECT DOCUMENT NUMBER REV
REVIEWER
DESIGNER
123
7 3 2 1 6 5 4
E
A
B
C
E
D
C
B
A
7 6 5 4
D
BI
IN
OUT
OUT
OUT
OUT
IN
BI
IN
BI
BI
IN
C2274
C2275
C2276
C2010
C



ADDRESS : 0X8220211130 ADD R4093,R4094 PU TO P3V3_AUXADDRESS : 0X84
20210929 MODIFY FOR GT
Fri Aug 25 14:02:41 2023N/AN/AN/AN/AV05171 OF 312
P3V3_AUXP3V3_AUXP3V3_AUXP3V3_OCP_SFF_RP3V3_OCP_SFFP3V3_AUXP3V3_OCP_SFF_RP3V3_E1S_0P3V3_E1S_0_RP3V3_E1S_0_R
P3V3_AUX
POWER MONITOR (1/2)
214214232232232232
0.1UFX7RNC_INA230_1_NC5OCP_SFF_P3V3_ADC_ALERTOCP_SFF_P3V3_ADC_ALERT_RNC_INA230_1_NC1NC_INA230_1_NC2NC_INA230_1_NC3NC_INA230_1_NC0NC_INA230_1_NC4CHIP1/16W1%0402LF4.7K0402LF0CHIPSMB_INA230_1_3V3AUX_SDA_R1SMB_INA230_1_3V3AUX_SCL_R1INA230AIRGTRICSMLF
NC_INA230_2_NC3E1S_0_P3V3_ADC_ALERTE1S_0_P3V3_ADC_ALERT_RNC_INA230_2_NC4NC_INA230_2_NC2NC_INA230_2_NC1NC_INA230_2_NC0NC_INA230_2_NC50402LFCHIP1/16W1%4.7K0CHIP 0402LFVSENSE_P3V3_INA230_2_INPVSENSE_P3V3_INA230_2_INNSMB_INA230_2_3V3AUX_SDA_R1SMB_INA230_2_3V3AUX_SCL_R1INA230AIRGTRICSMLFVSENSE_P3V3_INA230_1_INPINA230_1_A0VSENSE_P3V3_INA230_1_INNCHIP1%0.011W2512LF2512LF1WCHIP1%0.01X7R10%25V0.1UF1/16W10%0.1UF1/16WX7R25V1%0402LFSMB_INA230_1_3V3AUX_SDA_RSMB_INA230_1_3V3AUX_SCL_R33.21%CHIPINA230_1_A10402LF1/16W040210%
SMB_INA230_2_3V3AUX_SDA_RSMB_INA230_2_3V3AUX_SCL_RINA230_2_A0INA230_2_A1X7R25V10%04020.1UF101%0402LF1/16W0402LF1%10CHIP25V10%X7R0.1UF0402CHIP1%33.233.21%0402LF 1/16WCHIP0CHIP5%1/16W0402LF1%0402LFEMPTY1/16W4.7K0402LF4.7K 1/16W1%CHIP040225V1/16W CHIP
04020402LFEMPTY1%4.7K 1/16W4.7K 0402LFCHIP1%1/16W1%100402LF0402X7R10%25V0.1UFCHIP1%100402LF33.21%CHIPCHIP0402LF4.7K1/16WEMPTY1%4.7K1/16W CHIP
TH
GND
NC5
NC4
NC3
NC2
NC1
NC0
ALERT
IN-
IN+
BUS
SDA
SCL
A0
A1
VS
TH
GND
NC5
NC4
NC3
NC2
NC1
NC0
ALERT
IN-
IN+
BUS
SDA
SCL
A0
A1
VS R3752
R3563
R3767
R3645
R3763
R3764
R3760
R3758
R3603
R3602
R3617
R3616
9
TH
4
5
16
15
14
8
7
6
12
13 10
11
3
1
2
9
TH
4
5
16
15
14
8
7
6
12
13 10
11
3
1
2
U276
U266
21
21
2
1
2
1
2
1
2
1
21
21
21 2
1
21
21R3756
21R3754
2
1
21
2
1
2
1
2
1
2
1
21
21
21
21R3601
21R3600
21
2
1
21
SHEETDATE
DEPARTMENT
SIZE
PROJECT DOCUMENT NUMBER REV
REVIEWER
DESIGNER
123
7 3 2 1 6 5 4
E
A
B
C
E
D
C
B
A
7 6 5 4
D BIIN
OUT
BIIN
OUT
R4094
R4093
R3751
C2069
C2071
C2067
R3627 R3628
C2027
C2024
C2015
C



ADDRESS : 0X86
ADDRESS : 0X8A
20210929 MODIFY FOR GT20211130 ADD R4090,R4091,R4092 PU TO P3V3_AUXADDRESS : 0X88Fri Aug 25 14:02:43 2023N/AN/AN/AN/AV05172 OF 312P3V3_AUXP3V3_AUXP3V3_AUXP3V3_AUX
P12V_SCM_R
P3V3_AUXP3V3_M2_0P3V3P3V3P3V3_OCP_V3_2_RP3V3_OCP_V3_2P3V3_AUXP3V3_AUXP3V3_AUXP12V_SCM_RP12V_SCM
P3V3_OCP_V3_2_R
POWER MONITOR (2/2)214214214
232232232232232232X7RVSENSE_P12V_INA230_4_INP1/16W0402LFCHIP10%INA230AIRGTR0.1UFVSENSE_P12V_INA230_3_INNINA230_4_A1NC_INA230_3_NC2NC_INA230_3_NC1NC_INA230_3_NC0
NC_INA230_5_NC1P12V_SCM_ADC_ALERTP12V_SCM_ADC_ALERT_RNC_INA230_5_NC2NC_INA230_5_NC0NC_INA230_5_NC4NC_INA230_5_NC5NC_INA230_5_NC3CHIP1%4.7K00402LFSMB_INA230_5_3V3AUX_SDA_R1SMB_INA230_5_3V3AUX_SCL_R1ICSMLFM2_0_P3V3_ADC_ALERTM2_0_P3V3_ADC_ALERT_RNC_INA230_4_NC1NC_INA230_4_NC2NC_INA230_4_NC3NC_INA230_4_NC5NC_INA230_4_NC4NC_INA230_4_NC0CHIP1/16W1%4.7K0402LFCHIP0402LF0SMB_INA230_4_3V3AUX_SDA_R1SMB_INA230_4_3V3AUX_SCL_R1SMLFICINA230AIRGTRNC_INA230_3_NC4OCP_V3_2_P3V3_ADC_ALERT_R OCP_V3_2_P3V3_ADC_ALERTNC_INA230_3_NC5NC_INA230_3_NC3CHIP1/16W0402LF4.7K1%CHIP00402LFINA230_3_A1VSENSE_P12V_INA230_3_INPSMB_INA230_3_3V3AUX_SDA_R1SMB_INA230_3_3V3AUX_SCL_R1SMLFICINA230AIRGTR
0.011W33.2INA230_5_A0INA230_5_A110%25V0.1UF
5%25V0402VSENSE_P12V_INA230_4_INN1/16W1/16W1%EMPTYEMPTY 0402LFSMB_INA230_5_3V3AUX_SCL_R0402LFSMB_INA230_5_3V3AUX_SDA_R0402LF1%4.7K1/16W1/16W CHIP1/16W1%0402SMB_INA230_4_3V3AUX_SCL_RSMB_INA230_4_3V3AUX_SDA_R0.1UFX7RCHIP0402LF
0402LFCHIP01/16WINA230_3_A004020.1UF25V10%X7R33.20402LF 1/16WCHIP1%33.21%CHIPCHIP 0402LF1/16W4.7K1%1/16W4.7K EMPTY1%0402LF0402X7R10%25V0402LFCHIP1%101/16WCHIP1%0402LF101/16W0.1UF25V10%0402SMB_INA230_3_3V3AUX_SDA_RCHIP0402LFINA230_4_A01/16W CHIP1%100402LF100402LF1/16W1%33.20402LF1%CHIP1/16W33.21%CHIP0402LFCHIP1%4.7K 1/16W4.7K1%EMPTY 0402LF1/16WEMPTY1/16W0402LF1%4.7K0.1UF25VX7R10%1%4.7K1/16WX7R10%04020.1UF25V1/16W 0402LF1%4.7K100402LF1%100402LF1/16W1%33.21%04024.7KCHIP CHIP4.7K1%0402X7RVSENSE_P12V_INA230_5_INNCHIPX7R10%25V0.1UFVSENSE_P12V_INA230_5_INPCHIPCHIP
X7RSMB_INA230_3_3V3AUX_SCL_R2512LF1W0.011%CHIP0.1UF25V10%04022512LFCHIP1%0.011W2512LFCHIP1%
TH
GND
NC5
NC4
NC3
NC2
NC1
NC0
ALERT
IN-
IN+
BUS
SDA
SCL
A0
A1
VS
TH
GND
NC5
NC4
NC3
NC2
NC1
NC0
ALERT
IN-
IN+
BUS
SDA
SCL
A0
A1
VS
TH
GND
NC5
NC4
NC3
NC2
NC1
NC0
ALERT
IN-
IN+
BUS
SDA
SCL
A0
A1
VS
R3559
R3561
R3560
R3635
R3634
R3633
R3571
R3570
R3609
R3608
R3620
R3612
R3613
R3578
R3579
R3610
R3611
R3574
R3575
9
TH
4
5
16
15
14
8
7
6
12
13 10
11
3
1
2
9
TH
4
5
16
15
14
8
7
6
12
13 10
11
3
1
2
9
TH
4
5
16
15
14
8
7
6
12
13 10
11
3
1
2
U263
U265
U264
21
21
21
2
1
2
1
2
1
2
1
21
21
2
1
21
21
21R3569
21R3568
2
1
2
1
21
2
1
2
1
2
1
2
1
2
1
2
1
21
2
1
21
21R3576 21R3577
21
21
21
2
1
21
2
1
21
21R3572 21R3573
21
21
21
2
1
SHEETDATE
DEPARTMENT
SIZE
PROJECT DOCUMENT NUMBER REV
REVIEWER
DESIGNER
123
7 3 2 1 6 5 4
E
A
B
C
E
D
C
B
A
7 6 5 4
D
OUT
OUT
INBI
OUT
INBI
BIIN
R4092
R4090
R4091
C2017
C2020
C2012
R3622 R3624
R3621 R3623
C2022
C2021
C2014
C2019
C2013
C2018
C



CPU0 PCIE2 TXCPU0 PCIE0 TX
20210527 MODIFY FOR GT
173 OF 312V05N/AN/AFri Aug 25 14:02:44 2023N/AN/APCIE AC-COUPLE CAPS 1/5
3030136136292929291381381391393030137137P5E_CPU0_PE2_TX_DN<15:8>P5E_CPU0_PE2_TX_DP<15:8>P5E_CPU0_PE2_TX_C_DP<7:0>P5E_CPU0_PE2_TX_C_DN<7:0>DIFF BUS_0.22UFP5E_CPU0_PE0_TX_DP<15:8>P5E_CPU0_PE0_TX_DN<7:0>P5E_CPU0_PE0_TX_DP<7:0>P5E_CPU0_PE0_TX_DN<15:8>P5E_CPU0_PE0_TX_C_DP<7:0>P5E_CPU0_PE0_TX_C_DN<7:0>P5E_CPU0_PE0_TX_C_DP<15:8>P5E_CPU0_PE0_TX_C_DN<15:8>P5E_CPU0_PE2_TX_DP<7:0>P5E_CPU0_PE2_TX_DN<7:0>P5E_CPU0_PE2_TX_C_DN<15:8>P5E_CPU0_PE2_TX_C_DP<15:8>
DIFF BUS_0.22UFDIFF BUS_0.22UFDIFF BUS_0.22UFDIFF BUS_0.22UFDIFF BUS_0.22UFDIFF BUS_0.22UFDIFF BUS_0.22UFDIFF BUS_0.22UFDIFF BUS_0.22UFDIFF BUS_0.22UFDIFF BUS_0.22UFDIFF BUS_0.22UFDIFF BUS_0.22UFDIFF BUS_0.22UFDIFF BUS_0.22UFDIFF BUS_0.22UFDIFF BUS_0.22UFDIFF BUS_0.22UFDIFF BUS_0.22UFDIFF BUS_0.22UFDIFF BUS_0.22UFDIFF BUS_0.22UFDIFF BUS_0.22UFDIFF BUS_0.22UFDIFF BUS_0.22UFDIFF BUS_0.22UFDIFF BUS_0.22UFDIFF BUS_0.22UFDIFF BUS_0.22UFDIFF BUS_0.22UFDIFF BUS_0.22UFX6S20%6.3VDIFF BUS_0.22UFC0201
DIFF BUS_0.22UFDIFF BUS_0.22UFDIFF BUS_0.22UFDIFF BUS_0.22UFDIFF BUS_0.22UFDIFF BUS_0.22UFDIFF BUS_0.22UFDIFF BUS_0.22UFDIFF BUS_0.22UFDIFF BUS_0.22UFDIFF BUS_0.22UFDIFF BUS_0.22UFDIFF BUS_0.22UFDIFF BUS_0.22UFDIFF BUS_0.22UFDIFF BUS_0.22UFDIFF BUS_0.22UFDIFF BUS_0.22UFDIFF BUS_0.22UFDIFF BUS_0.22UFDIFF BUS_0.22UFDIFF BUS_0.22UFDIFF BUS_0.22UFDIFF BUS_0.22UFDIFF BUS_0.22UFDIFF BUS_0.22UFDIFF BUS_0.22UFX6SDIFF BUS_0.22UF6.3V20%C0201DIFF BUS_0.22UFDIFF BUS_0.22UFDIFF BUS_0.22UF
2 1
2 1
2 1
2 1
2 1
2 1
2 1
2 1
2 1
2 1
2 1
2 1
2 1
2 1
2 1
2 1
2 1
2 1
2 1
2 1
2 1
2 1
2 1
2 1
2 1
2 1
2 1
2 1
2 1
2 1
2 1
2 1
2 1
2 1
2 1
2 1
2 1
2 1
2 1
2 1
2 1
2 1
2 1
2 1
2 1
2 1
2 1
2 1
2 1
2 1
2 1
2 1
2 1
2 1
2 1
2 1
2 1
2 1
2 1
2 1
2 1
2 1
2 1
2 10
1
2
0
1
0
1
2
3
4
2
3
5
6
4
5
6
7
7
8
9
8
9
10
11
12
10
11
12
13
14
15
13
14
15
14
11
13
12
10
8
9
7
5
6
3
4
2
1
0
15
0
1
2
3
4
5
6
7
8
9
11
10
12
13
14
15
1
3
2
6
5
4
7
0
1
3
5
4
6
7
9
8
12
11
10
13
14
15
8
9
10
11
12
13
14
15
1
2
3
0
2
3
4
5
4
6
7
5
6
7
8
9
10
11
12
8
9
10
11
12
13
14
15
13
14
15
0
C955
C956
C957
C934
C940
C941
C942
C943
C944
C945
C946
C947
C948
C949
C950
C951
C952
C953
C954
C958
C959
C960
C910
C919
C918
C920
C921
C922
C923
C924
C925
C926
C927
C929
C935
C936
C937
C938
C939
C961
C962
C963
C964
C965
C902
C903
C904
C905
C907
C906
C908
C909
C911
C912
C913
C914
C915
C917
C916
C928
C930
C931
C933
C932
2 1
2 12 1
2 1
2 12 1
2 12 1
2 12 1
2 12 1
2 12 1
2 12 1
2 12 1
2 1
2 12 1
2 1
2 1
2 12 1
2 12 1
2 12 1
2 12 1
2 12 1
2 1
2 1
2 12 1
2 12 1
2 1
2 12 1
2 12 1
2 12 1
2 12 1
2 12 1
2 12 1
2 1
2 12 1
2 12 1
2 12 1
2 1
2 12 1
2 12 1
SHEETDATE
DEPARTMENT
SIZE
PROJECT DOCUMENT NUMBER REV
REVIEWER
DESIGNER
123
7 3 2 1 6 5 4
E
A
B
C
E
D
C
B
A
7 6 5 4
D
ININOUTOUT
ININ OUTOUT
IN OUT OUT
ININOUTOUT
IN
C



20210527 MODIFY FOR GT
CPU0 PCIE3 TXCPU0 PCIE1 TXFri Aug 25 14:02:45 2023V05174 OF 312N/AN/AN/AN/APCIE AC-COUPLE CAPS 2/5
15329292929153153153303013613613713730306.3VDIFF BUS_0.22UFDIFF BUS_0.22UFP5E_CPU0_PE1_TX_C_DP<7:0>P5E_CPU0_PE1_TX_DP<15:8>P5E_CPU0_PE1_TX_DN<15:8>P5E_CPU0_PE1_TX_DN<7:0>P5E_CPU0_PE1_TX_DP<7:0>P5E_CPU0_PE1_TX_C_DN<7:0>P5E_CPU0_PE1_TX_C_DN<15:8>P5E_CPU0_PE1_TX_C_DP<15:8> P5E_CPU0_PE3_TX_DP<15:8>P5E_CPU0_PE3_TX_DN<15:8>P5E_CPU0_PE3_TX_C_DN<7:0>P5E_CPU0_PE3_TX_C_DP<7:0>P5E_CPU0_PE3_TX_C_DP<15:8>P5E_CPU0_PE3_TX_C_DN<15:8>P5E_CPU0_PE3_TX_DN<7:0>P5E_CPU0_PE3_TX_DP<7:0>DIFF BUS_0.22UFDIFF BUS_0.22UFDIFF BUS_0.22UFDIFF BUS_0.22UFDIFF BUS_0.22UFDIFF BUS_0.22UFDIFF BUS_0.22UFDIFF BUS_0.22UFDIFF BUS_0.22UFDIFF BUS_0.22UFDIFF BUS_0.22UFDIFF BUS_0.22UFDIFF BUS_0.22UFDIFF BUS_0.22UFDIFF BUS_0.22UFDIFF BUS_0.22UFDIFF BUS_0.22UFDIFF BUS_0.22UFDIFF BUS_0.22UFDIFF BUS_0.22UFDIFF BUS_0.22UFDIFF BUS_0.22UFDIFF BUS_0.22UFDIFF BUS_0.22UFDIFF BUS_0.22UFDIFF BUS_0.22UFDIFF BUS_0.22UFDIFF BUS_0.22UFX6S20%C0201DIFF BUS_0.22UFDIFF BUS_0.22UF
DIFF BUS_0.22UFDIFF BUS_0.22UFDIFF BUS_0.22UFDIFF BUS_0.22UFDIFF BUS_0.22UFDIFF BUS_0.22UFDIFF BUS_0.22UFDIFF BUS_0.22UFDIFF BUS_0.22UFDIFF BUS_0.22UFDIFF BUS_0.22UFDIFF BUS_0.22UFDIFF BUS_0.22UFDIFF BUS_0.22UFDIFF BUS_0.22UFDIFF BUS_0.22UFDIFF BUS_0.22UFDIFF BUS_0.22UFDIFF BUS_0.22UFDIFF BUS_0.22UFDIFF BUS_0.22UFDIFF BUS_0.22UFDIFF BUS_0.22UFDIFF BUS_0.22UFDIFF BUS_0.22UFDIFF BUS_0.22UFDIFF BUS_0.22UFDIFF BUS_0.22UFDIFF BUS_0.22UFDIFF BUS_0.22UFC020120%6.3VDIFF BUS_0.22UFX6S
DIFF BUS_0.22UF
2 1
2 1
2 1
2 1
2 1
2 1
2 1
2 1
2 1
2 1
2 1
2 1
2 1
2 1
2 1
2 1
2 1
2 1
2 1
2 1
2 1
2 1
2 1
2 1
2 1
2 1
2 1
2 1
2 1
2 1
2 1
2 1
2 1
2 1
2 1
2 1
2 1
2 1
2 1
2 1
2 1
2 1
2 1
2 1
2 1
2 1
2 1
2 1
2 1
2 1
2 1
2 1
2 1
2 1
2 1
2 1
2 1
2 1
2 1
2 1
2 1
2 1
2 1
2 1
5
5
0
1
2
3
4
0
1
2
3
4
5
6
7
5
6
7
0
1
2
3
4
6
7
8
9
10
11
12
8
9
10
11
12
15
14
13
13
14
15
8
9
10
11
12
15
14
13
0
1
2
3
4
6
7
8
9
10
11
12
13
14
15
0
1
2
3
4
6
7
0
1
2
3
5
6
7
8
9
10
11
12
13
14
15
8
9
10
11
12
13
14
15
0
1
2
4
3
0
1
2
3
4
5
6
7
5
6
7
8
9
10
11
12
8
9
10
11
12
13
15
14
13
14
15
4
5
C898
C875
C884
C890
C891
C839
C838
C840
C841
C843
C842
C844
C845
C846
C847
C848
C849
C850
C851
C853
C852
C854
C855
C856
C857
C858
C859
C860
C861
C862
C863
C865
C864
C866
C867
C868
C869
C870
C871
C872
C873
C874
C876
C877
C879
C878
C880
C881
C882
C883
C885
C886
C887
C888
C889
C893
C892
C894
C895
C896
C897
C899
C900
C901
2 1
2 1
2 1
2 12 1
2 12 1
2 12 1
2 12 1
2 12 1
2 12 1
2 12 1
2 12 1
2 12 1
2 12 1
2 12 1
2 12 1
2 12 1
2 12 1
2 12 1
2 12 1
2 12 1
2 12 1
2 12 1
2 1
2 12 1
2 12 1
2 12 1
2 12 1
2 1
2 12 1
2 12 1
2 12 1
2 12 1
2 12 1
2 1
2 12 1
SHEETDATE
DEPARTMENT
SIZE
PROJECT DOCUMENT NUMBER REV
REVIEWER
DESIGNER
123
7 3 2 1 6 5 4
E
A
B
C
E
D
C
B
A
7 6 5 4
D
ININOUTOUT
ININ OUTOUT
IN OUTOUT
ININOUTOUT
IN
C



CPU1 PCIE1 TXCPU0 PCIE4 TX
20210527 MODIFY FOR GT
Fri Aug 25 14:02:46 2023N/AN/AN/AN/AV05175 OF 312PCIE AC-COUPLE CAPS 3/5
1596060606015915915913913913813831313131DIFF BUS_0.22UF20%P5E_CPU1_PE1_TX_C_DP<7:0>P5E_CPU1_PE1_TX_DN<15:8>P5E_CPU1_PE1_TX_DP<15:8>P5E_CPU1_PE1_TX_DN<7:0>P5E_CPU1_PE1_TX_DP<7:0>P5E_CPU1_PE1_TX_C_DP<15:8>P5E_CPU1_PE1_TX_C_DN<15:8>P5E_CPU1_PE1_TX_C_DN<7:0>DIFF BUS_0.22UFDIFF BUS_0.22UFDIFF BUS_0.22UFDIFF BUS_0.22UFDIFF BUS_0.22UFDIFF BUS_0.22UFDIFF BUS_0.22UFDIFF BUS_0.22UFDIFF BUS_0.22UFDIFF BUS_0.22UFDIFF BUS_0.22UFDIFF BUS_0.22UFDIFF BUS_0.22UFDIFF BUS_0.22UFDIFF BUS_0.22UFDIFF BUS_0.22UFDIFF BUS_0.22UFDIFF BUS_0.22UFDIFF BUS_0.22UFDIFF BUS_0.22UFDIFF BUS_0.22UFDIFF BUS_0.22UFDIFF BUS_0.22UFDIFF BUS_0.22UFDIFF BUS_0.22UFDIFF BUS_0.22UFDIFF BUS_0.22UFDIFF BUS_0.22UF6.3VC0201X6SDIFF BUS_0.22UFDIFF BUS_0.22UFDIFF BUS_0.22UFDIFF BUS_0.22UFDIFF BUS_0.22UFP5E_CPU0_PE4_TX_C_DP<7:0>P5E_CPU0_PE4_TX_C_DN<7:0>P5E_CPU0_PE4_TX_C_DP<15:8>P5E_CPU0_PE4_TX_C_DN<15:8>P5E_CPU0_PE4_TX_DP<15:8>P5E_CPU0_PE4_TX_DN<15:8>P5E_CPU0_PE4_TX_DN<7:0>P5E_CPU0_PE4_TX_DP<7:0>DIFF BUS_0.22UFDIFF BUS_0.22UF
DIFF BUS_0.22UF20%X6S6.3VDIFF BUS_0.22UFC0201DIFF BUS_0.22UFDIFF BUS_0.22UFDIFF BUS_0.22UFDIFF BUS_0.22UFDIFF BUS_0.22UFDIFF BUS_0.22UFDIFF BUS_0.22UFDIFF BUS_0.22UFDIFF BUS_0.22UFDIFF BUS_0.22UFDIFF BUS_0.22UFDIFF BUS_0.22UFDIFF BUS_0.22UFDIFF BUS_0.22UFDIFF BUS_0.22UFDIFF BUS_0.22UFDIFF BUS_0.22UFDIFF BUS_0.22UFDIFF BUS_0.22UFDIFF BUS_0.22UFDIFF BUS_0.22UFDIFF BUS_0.22UFDIFF BUS_0.22UFDIFF BUS_0.22UFDIFF BUS_0.22UFDIFF BUS_0.22UF
2 1
2 1
2 1
2 1
2 1
2 1
2 1
2 1
2 1
2 1
2 1
2 1
2 1
2 1
2 1
2 1
2 1
2 1
2 1
2 1
2 1
2 1
2 1
2 1
2 1
2 1
2 1
2 1
2 1
2 1
2 1
2 1
2 1
2 1
2 1
2 1
2 1
2 1
2 1
2 1
2 1
2 1
2 1
2 1
2 1
2 1
2 1
2 1
2 1
2 1
2 1
2 1
2 1
2 1
2 1
2 1
2 1
2 1
2 1
2 1
2 1
2 1
2 1
2 1
3
0
1
0
1
2
3
4
2
3
4
5
6
5
6
7
7
8
9
10
8
9
11
12
10
11
12
13
14
15
13
14
15
0
0
1
1
2
2
3
4
5
5
6
6
7
7
8
8
9
10
9
10
11
11
12
12
13
13
14
15
14
15
4
8
15
15
14
13
14
13
12
12
11
10
11
10
9
9
8
8
7
7
6
6
5
5
4
3
4
3
2
2
1
1
0
0
14
15
13
15
13
14
12
10
11
12
11
9
10
9
8
7
7
6
5
6
5
4
3
2
4
2
3
1
0
1
0
C1576
C1577
C1549
C1548
C1550
C1792
C1552
C1553
C1554
C1555
C1557
C1556
C1558
C1559
C1560
C1793
C1794
C1563
C1564
C1565
C1566
C1567
C1568
C1569
C1571
C1570
C1572
C1573
C1574
C1575
C1578
C1579
C824
C825
C807
C806
C808
C809
C810
C811
C813
C812
C814
C815
C816
C817
C819
C823
C822
C826
C827
C829
C830
C828
C833
C832
C831
C835
C834
C837
C836
C818
C821
C820
2 12 1
2 12 1
2 12 1
2 12 1
2 12 1
2 12 1
2 12 1
2 1
2 12 1
2 12 1
2 1
2 1
2 1
2 12 1
2 1
2 12 1
2 12 1
2 1
2 12 1
2 12 1
2 12 1
2 12 1
2 12 1
2 12 1
2 12 1
2 12 1
2 12 1
2 12 1
2 12 1
2 12 1
2 12 1
2 12 1
2 12 1
2 12 1
2 12 1
SHEETDATE
DEPARTMENT
SIZE
PROJECT DOCUMENT NUMBER REV
REVIEWER
DESIGNER
123
7 3 2 1 6 5 4
E
A
B
C
E
D
C
B
A
7 6 5 4
D
OUTOUT
OUTOUT
ININ
ININ
OUTOUT
OUTOUT
ININ
ININ
C



20210527 MODIFY FOR GT
CPU1 PCIE2 TXCPU1 PCIE0 TXFri Aug 25 14:02:47 2023176 OF 312N/AN/AV05N/AN/APCIE AC-COUPLE CAPS 4/5
60606060 14314314214261616161141141140140X6SC0201DIFF BUS_0.22UFDIFF BUS_0.22UFDIFF BUS_0.22UFDIFF BUS_0.22UFDIFF BUS_0.22UFDIFF BUS_0.22UFDIFF BUS_0.22UFDIFF BUS_0.22UFDIFF BUS_0.22UFP5E_CPU1_PE0_TX_DN<7:0>P5E_CPU1_PE0_TX_DP<7:0>P5E_CPU1_PE0_TX_DN<15:8>P5E_CPU1_PE0_TX_DP<15:8> P5E_CPU1_PE0_TX_C_DP<15:8>P5E_CPU1_PE0_TX_C_DN<15:8>P5E_CPU1_PE0_TX_C_DP<7:0>P5E_CPU1_PE0_TX_C_DN<7:0>DIFF BUS_0.22UFDIFF BUS_0.22UFDIFF BUS_0.22UFDIFF BUS_0.22UFDIFF BUS_0.22UFDIFF BUS_0.22UFDIFF BUS_0.22UFDIFF BUS_0.22UFDIFF BUS_0.22UFDIFF BUS_0.22UFDIFF BUS_0.22UFDIFF BUS_0.22UFDIFF BUS_0.22UFDIFF BUS_0.22UFDIFF BUS_0.22UFDIFF BUS_0.22UFDIFF BUS_0.22UFDIFF BUS_0.22UFDIFF BUS_0.22UFDIFF BUS_0.22UFDIFF BUS_0.22UFDIFF BUS_0.22UFDIFF BUS_0.22UF20%6.3VDIFF BUS_0.22UFP5E_CPU1_PE2_TX_DP<7:0>P5E_CPU1_PE2_TX_DN<7:0>DIFF BUS_0.22UFDIFF BUS_0.22UFP5E_CPU1_PE2_TX_DP<15:8>P5E_CPU1_PE2_TX_DN<15:8>DIFF BUS_0.22UFDIFF BUS_0.22UFP5E_CPU1_PE2_TX_C_DP<15:8>P5E_CPU1_PE2_TX_C_DN<15:8>P5E_CPU1_PE2_TX_C_DP<7:0>P5E_CPU1_PE2_TX_C_DN<7:0>DIFF BUS_0.22UFC0201X6S20%6.3VDIFF BUS_0.22UFDIFF BUS_0.22UFDIFF BUS_0.22UFDIFF BUS_0.22UFDIFF BUS_0.22UFDIFF BUS_0.22UFDIFF BUS_0.22UFDIFF BUS_0.22UFDIFF BUS_0.22UFDIFF BUS_0.22UFDIFF BUS_0.22UFDIFF BUS_0.22UFDIFF BUS_0.22UFDIFF BUS_0.22UFDIFF BUS_0.22UFDIFF BUS_0.22UFDIFF BUS_0.22UFDIFF BUS_0.22UFDIFF BUS_0.22UFDIFF BUS_0.22UFDIFF BUS_0.22UFDIFF BUS_0.22UFDIFF BUS_0.22UFDIFF BUS_0.22UFDIFF BUS_0.22UFDIFF BUS_0.22UF
2 1
2 1
2 1
2 1
2 1
2 1
2 1
2 1
2 1
2 1
2 1
2 1
2 1
2 1
2 1
2 1
2 1
2 1
2 1
2 1
2 1
2 1
2 1
2 1
2 1
2 1
2 1
2 1
2 1
2 1
2 1
2 1
2 1
2 1
2 1
2 1
2 1
2 1
2 1
2 1
2 1
2 1
2 1
2 1
2 1
2 1
2 1
2 1
2 1
2 1
2 1
2 1
2 1
2 1
2 1
2 1
2 1
2 1
2 1
2 1
2 1
2 1
2 1
2 10
1
0
1
2
3
4
2
3
5
6
5
4
6
7
7
0
1
0
1
2
3
2
3
4
6
5
6
7
7
8
9
8
9
11
10
12
10
11
12
13
14
15
13
14
15
8
9
8
9
10
12
11
10
11
12
13
14
13
14
15
15
4
5
11
12
12
3
2
15
14
13
14
15
13
11
10
9
8
12
11
10
9
8
7
6
5
7
6
5
4
3
1
0
3
4
2
1
0
15
14
13
10
9
8
15
14
13
12
11
10
9
8
7
6
5
4
3
2
1
0
7
6
5
4
2
1
0
C726
C710
C711
C713
C712
C714
C715
C716
C717
C718
C719
C720
C721
C723
C722
C724
C725
C727
C728
C729
C730
C731
C732
C733
C735
C734
C736
C737
C738
C739
C741
C740
C742
C743
C744
C745
C746
C747
C748
C749
C751
C750
C752
C753
C754
C755
C757
C756
C758
C759
C760
C761
C762
C763
C765
C764
C766
C767
C768
C769
C770
C771
C772
C773
2 1
2 12 1
2 12 1
2 12 1
2 12 1
2 12 1
2 12 1
2 12 1
2 12 1
2 1
2 12 1
2 12 1
2 12 1
2 12 1
2 12 1
2 12 1
2 12 1
2 12 1
2 12 1
2 12 1
2 12 1
2 12 1
2 12 1
2 12 1
2 12 1
2 12 1
2 12 1
2 12 1
2 12 1
2 12 1
2 12 1
2 12 1
2 12 1
SHEETDATE
DEPARTMENT
SIZE
PROJECT DOCUMENT NUMBER REV
REVIEWER
DESIGNER
123
7 3 2 1 6 5 4
E
A
B
C
E
D
C
B
A
7 6 5 4
D
ININ
OUTOUT
OUTOUT
ININ
ININ
OUTOUT
OUTOUT
ININ
C



CPU1 PCIE3 TX CPU1 PCIE4 TXFri Aug 25 14:02:48 2023N/AN/AN/AN/AV05177 OF 312PCIE AC-COUPLE CAPS 5/5
14114114061611406161 14314362621426214262
DIFF BUS_0.22UFDIFF BUS_0.22UFDIFF BUS_0.22UFDIFF BUS_0.22UFP5E_CPU1_PE3_TX_C_DP<15:8>P5E_CPU1_PE3_TX_C_DN<15:8>P5E_CPU1_PE3_TX_C_DP<7:0>P5E_CPU1_PE3_TX_DN<15:8>P5E_CPU1_PE3_TX_DP<15:8>P5E_CPU1_PE3_TX_C_DN<7:0>P5E_CPU1_PE3_TX_DN<7:0>P5E_CPU1_PE3_TX_DP<7:0>P5E_CPU1_PE4_TX_C_DN<7:0>P5E_CPU1_PE4_TX_C_DP<7:0>P5E_CPU1_PE4_TX_DN<7:0>P5E_CPU1_PE4_TX_DP<7:0>P5E_CPU1_PE4_TX_C_DP<15:8>P5E_CPU1_PE4_TX_DP<15:8>P5E_CPU1_PE4_TX_C_DN<15:8>P5E_CPU1_PE4_TX_DN<15:8>6.3V20%X6SC0201DIFF BUS_0.22UFDIFF BUS_0.22UFDIFF BUS_0.22UFDIFF BUS_0.22UFDIFF BUS_0.22UFDIFF BUS_0.22UFDIFF BUS_0.22UFDIFF BUS_0.22UFDIFF BUS_0.22UFDIFF BUS_0.22UFDIFF BUS_0.22UFDIFF BUS_0.22UFDIFF BUS_0.22UFDIFF BUS_0.22UFDIFF BUS_0.22UFDIFF BUS_0.22UFDIFF BUS_0.22UFDIFF BUS_0.22UFDIFF BUS_0.22UFDIFF BUS_0.22UFDIFF BUS_0.22UFDIFF BUS_0.22UFDIFF BUS_0.22UFDIFF BUS_0.22UFDIFF BUS_0.22UFDIFF BUS_0.22UFDIFF BUS_0.22UFDIFF BUS_0.22UFDIFF BUS_0.22UFDIFF BUS_0.22UF
DIFF BUS_0.22UFX6SC0201 6.3V20%DIFF BUS_0.22UFDIFF BUS_0.22UFDIFF BUS_0.22UFDIFF BUS_0.22UFDIFF BUS_0.22UFDIFF BUS_0.22UFDIFF BUS_0.22UFDIFF BUS_0.22UFDIFF BUS_0.22UFDIFF BUS_0.22UFDIFF BUS_0.22UFDIFF BUS_0.22UFDIFF BUS_0.22UFDIFF BUS_0.22UFDIFF BUS_0.22UFDIFF BUS_0.22UFDIFF BUS_0.22UFDIFF BUS_0.22UFDIFF BUS_0.22UFDIFF BUS_0.22UFDIFF BUS_0.22UFDIFF BUS_0.22UFDIFF BUS_0.22UFDIFF BUS_0.22UFDIFF BUS_0.22UFDIFF BUS_0.22UFDIFF BUS_0.22UFDIFF BUS_0.22UFDIFF BUS_0.22UF
2 1
2 1
2 1
2 1
2 1
2 1
2 1
2 1
2 1
2 1
2 1
2 1
2 1
2 1
2 1
2 1
2 1
2 1
2 1
2 1
2 1
2 1
2 1
2 1
2 1
2 1
2 1
2 1
2 1
2 1
2 1
2 1
2 1
2 1
2 1
2 1
2 1
2 1
2 1
2 1
2 1
2 1
2 1
2 1
2 1
2 1
2 1
2 1
2 1
2 1
2 1
2 1
2 1
2 1
2 1
2 1
2 1
2 1
2 1
2 1
2 1
2 1
2 1
2 1
15
14
13
15
14
13
12
11
12
11
10
10
9
8
9
8
15
14
13
15
14
13
12
10
11
12
11
9
8
9
10
8
7
7
6
5
6
5
4
2
3
3
4
2
1
0
1
0
7
7
6
5
6
5
4
3
2
4
3
2
1
0
1
0
15
15
14
14
13
13
12
11
12
10
11
10
9
9
8
8
7
7
6
6
5
4
5
4
3
3
2
2
1
1
0
0
15
14
13
14
15
13
12
11
10
12
10
11
9
8
9
8
7
7
6
5
4
6
5
3
2
3
4
2
1
0
1
0
C1516
C1517
C1518
C1519
C1521
C1520
C1522
C1523
C1524
C1525
C1526
C1527
C1528
C1529
C1531
C1530
C1532
C1533
C1535
C1534
C1536
C1537
C1538
C1539
C1540
C1541
C1543
C1542
C1544
C1545
C1546
C1547
C678
C681
C680
C679
C683
C682
C684
C685
C686
C689
C688
C687
C691
C690
C692
C693
C694
C695
C697
C696
C699
C698
C700
C703
C702
C701
C705
C704
C707
C706
C709
C708
2 12 1
2 12 1
2 12 1
2 12 1
2 12 1
2 12 1
2 12 1
2 12 1
2 12 1
2 12 1
2 12 1
2 12 1
2 12 1
2 12 1
2 12 1
2 12 1
2 1
2 12 1
2 1
2 12 1
2 12 1
2 1
2 12 1
2 1
2 12 1
2 12 1
2 12 1
2 12 1
2 12 1
2 1
2 12 1
2 1
2 12 1
2 12 1
2 12 1
SHEETDATE
DEPARTMENT
SIZE
PROJECT DOCUMENT NUMBER REV
REVIEWER
DESIGNER
123
7 3 2 1 6 5 4
E
A
B
C
E
D
C
B
A
7 6 5 4
D
OUT
OUTOUT
OUT
ININ
ININ
OUTOUT
OUTOUT
ININ
ININ
C



CPU0 DMI TXCPU0 DMI RXFri Aug 25 14:02:50 2023N/AN/A178 OF 312V05N/AN/ADMI AC-COUPLE CAPS28181181281811812828DMI_CPU0_PCH_RX_C_DN<7:0>DMI_CPU0_PCH_TX_C_DP<7:0>DMI_CPU0_PCH_TX_C_DN<7:0>DMI_CPU0_PCH_TX_DN<7:0>DMI_CPU0_PCH_RX_DN<7:0>DMI_CPU0_PCH_RX_DP<7:0> DMI_CPU0_PCH_RX_C_DP<7:0>DMI_CPU0_PCH_TX_DP<7:0>DIFF BUS_0.22UFDIFF BUS_0.22UFDIFF BUS_0.22UFDIFF BUS_0.22UFDIFF BUS_0.22UFDIFF BUS_0.22UFDIFF BUS_0.22UFDIFF BUS_0.22UFDIFF BUS_0.22UFDIFF BUS_0.22UFDIFF BUS_0.22UFDIFF BUS_0.22UFDIFF BUS_0.22UFDIFF BUS_0.22UFDIFF BUS_0.22UFDIFF BUS_0.22UF
DIFF BUS_0.22UFDIFF BUS_0.22UFDIFF BUS_0.22UFDIFF BUS_0.22UFDIFF BUS_0.22UFDIFF BUS_0.22UFDIFF BUS_0.22UFDIFF BUS_0.22UFDIFF BUS_0.22UFDIFF BUS_0.22UFDIFF BUS_0.22UFDIFF BUS_0.22UFDIFF BUS_0.22UFDIFF BUS_0.22UFDIFF BUS_0.22UFDIFF BUS_0.22UF
2 1
2 1
2 1
2 1
2 1
2 1
2 1
2 1
2 1
2 1
2 1
2 1
2 1
2 1
2 1
2 1
2 1
2 1
2 1
2 1
2 1
2 1
2 1
2 1
2 1
2 1
2 1
2 1
2 1
2 1
2 1
2 1 7
0
1
7
6
5
2
4
3
2
1
0
0
1
2
4
1
3
6
5
7
0
1
0
7
7
6
5
4
6
0
1
0
1
2
5
3
4
2
3
4
6
5
5
7
6
3
7
2
0
1
3
4
2
4
3
2
4
6
5
5
6
7
3
C1791
C170
C169
C167
C168
C166
C165
C164
C163
C162
C161
C160
C159
C158
C157
C156
C155
C139
C141
C142
C143
C144
C145
C146
C147
C148
C150
C149
C151
C152
C154
C153
2 12 1
2 12 1
2 12 1
2 12 1
2 12 1
2 12 1
2 12 1
2 12 1
2 12 1
2 12 1
2 12 1
2 12 1
2 12 1
2 12 1
2 12 1
2 12 1
SHEETDATE
DEPARTMENT
SIZE
PROJECT DOCUMENT NUMBER REV
REVIEWER
DESIGNER
123
7 3 2 1 6 5 4
E
A
B
C
E
D
C
B
A
7 6 5 4
D
OUTOUT
OUTOUTIN
ININ
IN
C



20211206 ADD 0OHM
20210929 MODIFY FOR GTPLACE WITHIN 1.5 INCHES TO PCH
Fri Aug 25 14:02:51 2023N/A0101V05N/A01N/A179 OF 312N/AEMMITSBURG - CLK (1/10)
179179179 190191191209209209179190179209179179179209209209209179240240179179179179179179179CHIPCHIP222225VCLK_100M_E1S_0_R_DPCLK_100M_E1S_0_R_DNCLK_100M_PE_M2_0_R_DP0402LFCLK_100M_PE_M2_0_DPCLK_100M_E1S_0_DNCLK_100M_E1S_0_DPCLK_25M_PCH_CPU1_DNCLK_25M_PCH_CPU1_DPCLK_25M_PCH_CPU0_DPTP_CLK_100M_PCH_0_DNTP_CLK_100M_PCH_0_DPTP_CLK_100M_PCH_1_DPCLK_100M_PE_M2_0_R_DN0402LFCLK_100M_PE_M2_0_DNXTAL_PCH_RTC2XTAL_PCH_RTC2_RCLK_25M_PCH_CPU0_DNX7RTP_CLK_100M_PCH_10_DPTP_CLK_100M_PCH_11_DNTP_CLK_100M_PCH_16_DPTP_CLK_100M_PCH_16_DNTP_CLK_100M_PCH_14_DPTP_CLK_100M_PCH_13_DNRTC_EXT_CAP1%XTAL_PCH_25M_INXTAL_PCH_RTC2XTAL_PCH_RTC1CLK_100M_CK440_PCH_EXTCLK_DNCLK_100M_CK440_PCH_EXTCLK_DPCLK_25M_PCH_REF_NS_DPCLK_25M_PCH_REF_NS_DNTP_PCH_RSVD<19>TP_PCH_RSVD<18>PD_PCH_XCLK_BIASREFTP_CLK_100M_PCH_12_DNTP_CLK_100M_PCH_14_DNTP_CLK_100M_PCH_15_DNTP_CLK_100M_PCH_11_DPTP_CLK_100M_PCH_12_DPTP_CLK_100M_PCH_13_DPTP_CLK_100M_PCH_15_DPXTAL_PCH_25M_OUTBOM CHANGE: AJ0QV2N0T00 CHANGE TO AJ0QV5S0T0110%04020.1UFSMLFICGFNOCPU04302300-QV2N-MM#99A1WT0402LFCHIP1/16W60.4TP_CLK_100M_PCH_10_DNTP_CLK_100M_PCH_9_DPTP_CLK_100M_PCH_9_DNTP_CLK_100M_PCH_8_DPTP_CLK_100M_PCH_8_DNTP_CLK_100M_PCH_7_DPTP_CLK_100M_PCH_7_DNCLK_100M_BMC_P3E_DNCLK_100M_BMC_P3E_DPTP_CLK_100M_PCH_5_DPTP_CLK_100M_PCH_5_DNTP_CLK_100M_PCH_4_DPTP_CLK_100M_PCH_4_DNTP_CLK_100M_PCH_1_DNCLK_100M_E1S_0_R_DNCLK_100M_PE_M2_0_R_DPCLK_100M_E1S_0_R_DP05%CHIP1/16W0402LF1/10W10M0603LF1%SMLFIC5%C0G50V18PF0402C0G04025%50V18PF5%0402LF01/16WEMPTY0.1%0603LF 1/10W200K EMPTY25MHZSMLFEMPTY04025%50V27PFEMPTY040227PF50V5%EMPTYXTAL_PCH_RTC1XTAL_PCH_25M_OUTXTAL_PCH_25M_IN_R XTAL_PCH_25M_IN32.768KHZCHIP0CLK_100M_PE_M2_0_R_DN5%1/16W5%1/16WCHIPCHIP0
R1721
R1720
R1316
2R120
U4
Y7
Y1
1/11
XTAL_OUT
XTAL_IN
RTC_EXTCAP
RTCX2
RTCX1
REFCLK_INJ_S_P
REFCLK_INJ_S_N
REFCLK_INJ_NS_P
REFCLK_INJ_NS_N
PMSYNC_CLK_P_1
PMSYNC_CLK_P_0
PMSYNC_CLK_N_1
PMSYNC_CLK_N_0
CLKOUT_SRC_P_9
CLKOUT_SRC_P_8
CLKOUT_SRC_P_7
CLKOUT_SRC_P_6
CLKOUT_SRC_P_5
CLKOUT_SRC_P_4
CLKOUT_SRC_P_3
CLKOUT_SRC_P_2
CLKOUT_SRC_P_16
CLKOUT_SRC_P_15
CLKOUT_SRC_P_14
CLKOUT_SRC_P_13
CLKOUT_SRC_P_12
CLKOUT_SRC_P_11
CLKOUT_SRC_P_10
CLKOUT_SRC_P_1
CLKOUT_SRC_P_0
CLKOUT_SRC_N_9
CLKOUT_SRC_N_8
CLKOUT_SRC_N_7
CLKOUT_SRC_N_6
CLKOUT_SRC_N_5
CLKOUT_SRC_N_4
CLKOUT_SRC_N_3
CLKOUT_SRC_N_2
CLKOUT_SRC_N_16
CLKOUT_SRC_N_15
CLKOUT_SRC_N_14
CLKOUT_SRC_N_13
CLKOUT_SRC_N_12
CLKOUT_SRC_N_11
CLKOUT_SRC_N_10
CLKOUT_SRC_N_1
CLKOUT_SRC_N_0
XCLK_BIASREF
RSVD_H24
RSVD_J23
X2
G2G1
X1
21
21R4304
21
21
21
21
21
21
2
1
C103 C104
1
2
1
C1508C1507
BOM NOTE:
CAD NOTE:
R4303
R4306
R4305
D23
B23
N29
BF7
BE6
BF5
J23H24
B21D21
B25D25
A28
B27
C28
D27
C18
C6
D7
C8
C10
H15
K18
D15
H18
C14
D11
C12
D19
D17
K21
F21
C16
A18
B5
B7
A8
A10
G16
J16
B15
F18
A14
B11
A12
B19
B17
H21
G23
A16
31
42
21
SHEETDATE
DEPARTMENT
SIZE
PROJECT DOCUMENT NUMBER REV
REVIEWER
DESIGNER
123
7 3 2 1 6 5 4
E
A
B
C
E
D
C
B
A
7 6 5 4
D
OUT
OUTOUT
IN
ININ
OUTOUT
OUTOUT
OUT
IN
OUT
ININ
OUT
IN
OUT
IN
IN
IN
IN
IN
OUT
OUT
OUT
OUT
OUTOUT
OUT
C609
R477
C



PLACE IN TOP WITHIN 0.5 INCH
SCM(RSVD) PORT5 PORT7 NABMC-A NA PORT8 NAOCP_V3_2 NA PORT5 NAOCP-SFF NA PORT3 NASCM PORT4 PORT0 OC1USAGE USB3.0 USB2.0 OC20210616 MODIFY FOR GT
Fri Aug 25 14:02:52 2023N/AV05180 OF 312N/AN/AN/AEMMITSBURG - USB (2/10)
159159153153196240240240240196USB2_5_DPUSB2_5_DNTP_USB2_4_DPTP_USB2_4_DNUSB2_3_DPUSB2_3_DNTP_USB2_2_DPTP_USB2_2_DNTP_USB2_1_DPUSB2_0_DNTP_USB2_6_DNTP_USB2_6_DPUSB2_7_DNUSB2_7_DPUSB2_8_DNUSB2_8_DPTP_USB2_9_DNTP_USB2_1_DNUSB2_0_DPPD_PCH_USB2_COMPNC_PCH_RSVD<14>TP_USB2_9_DPTP_USB2_10_DNTP_USB2_10_DPPIN BT69 & BP69 ARE VSS IN V1.0TP_USB2_11_DNTP_USB2_11_DPTP_USB2_12_DPTP_USB2_13_DNTP_USB2_13_DPSMLFGFNOCPU04302300-QV2N-MM#99A1WTICTP_USB2_12_DNCHIP1/16W1%1130402LF
U4
2/11
USB2_COMP
USB2P_9
USB2P_8
USB2P_7
USB2P_6
USB2P_5
USB2P_4
USB2P_3
USB2P_2
USB2P_13
USB2P_12
USB2P_11
USB2P_10
USB2P_1
USB2P_0
USB2N_9
USB2N_8
USB2N_7
USB2N_6
USB2N_5
USB2N_4
USB2N_3
USB2N_2
USB2N_13
USB2N_12
USB2N_11
USB2N_10
USB2N_1
USB2N_0
RSVD_BC40
2
1
CAD NOTE:
DESIGN NOTE:
DESIGN NOTE:
AG41
BA40
AH40
AY41
AJ41
AW40
AK40
AV41
AL41
AU40
AN40
AT41
AP41
AR40
AG43
BA42
AH42
AY43
AJ43
AW42
AK42
AV43
AL43
AU42
AN42
AT43
AP43
AR42
BB41BC40
SHEETDATE
DEPARTMENT
SIZE
PROJECT DOCUMENT NUMBER REV
REVIEWER
DESIGNER
123
7 3 2 1 6 5 4
E
A
B
C
E
D
C
B
A
7 6 5 4
D
BIBI
BIBI
BIBI
BIBI
BIBI
R496
C



20210616 MODIFY FOR GTM.2RCOMP RESISTOR PLACE IN TOP WITHIN 2 INCHFri Aug 25 14:02:53 2023V05N/AN/AN/A181 OF 312N/AEMMITSBURG - DMI/SATA/PCIE (3/10)
191178178143143169169143143191190191191191191191190190190190190190190191191240240178178190190190190191191190190190190191191191191191143240240143169169143143P3E_PCH_E1S_TX_DN<3>P3E_PCH_E1S_TX_DP<2>P3E_PCH_E1S_TX_C_DP<1>DMI_CPU0_PCH_TX_C_DP<7:0>DMI_CPU0_PCH_TX_C_DN<7:0>TP_P3E_PCH_15_RX_DPP3E_PCH_NVS_RX_DP<0>P3E_PCH_NVS_RX_DN<0>USB3_PCH_RX_BUF_DP<4>USB3_PCH_RX_BUF_DN<4>P3E_PCH_NVS_RX_DN<1>P3E_PCH_NVS_RX_DP<1>TP_P3E_PCH_14_RX_DNTP_P3E_PCH_14_RX_DPTP_P3E_PCH_15_RX_DNTP_P3E_PCH_13_RX_DPTP_P3E_PCH_12_RX_DPTP_P3E_PCH_12_RX_DNTP_P3E_PCH_13_RX_DNNC_PCH_RSVD<9>P3E_PCH_E1S_RX_DN<2>P3E_PCH_M2_RX_DP<0>P3E_PCH_E1S_RX_DP<1>P3E_PCH_E1S_RX_DN<1>P3E_PCH_E1S_RX_DP<0>P3E_PCH_E1S_RX_DP<2>P3E_PCH_E1S_RX_DN<0>P3E_PCH_M2_RX_DP<3>P3E_PCH_M2_RX_DP<2>P3E_PCH_M2_RX_DN<3>P3E_PCH_M2_RX_DN<0>P3E_PCH_M2_RX_DN<2>P3E_PCH_M2_RX_DP<1>P3E_PCH_M2_RX_DN<1>NC_PCH_RSVD<8>P3E_PCH_E1S_RX_DP<3>P3E_PCH_E1S_RX_DN<3>P3E_PCH_BMC_RX_DNP3E_PCH_BMC_RX_DPPCH_PCIEUP_RCOMPNPCH_PCIEUP_RCOMPPDMI_CPU0_PCH_RX_DN<7:0>DMI_CPU0_PCH_RX_DP<7:0>TP_P3E_PCH_15_TX_DNTP_P3E_PCH_14_TX_DNTP_P3E_PCH_14_TX_DPTP_P3E_PCH_15_TX_DPP3E_PCH_NVS_TX_DN<1>USB3_PCH_TX_DP<4>USB3_PCH_TX_DN<4>P3E_PCH_NVS_TX_DN<0>P3E_PCH_NVS_TX_DP<0>P3E_PCH_NVS_TX_DP<1>TP_P3E_PCH_13_TX_DPTP_P3E_PCH_13_TX_DNTP_P3E_PCH_12_TX_DNTP_P3E_PCH_12_TX_DPNC_PCH_RSVD<11>NC_PCH_RSVD<10>P3E_PCH_M2_TX_DN<0>P3E_PCH_E1S_TX_DN<1>P3E_PCH_E1S_TX_DP<1>P3E_PCH_M2_TX_DP<0>P3E_PCH_M2_TX_DN<3>P3E_PCH_E1S_TX_DN<0>P3E_PCH_E1S_TX_DP<0>P3E_PCH_E1S_TX_DN<2>P3E_PCH_M2_TX_DP<3>P3E_PCH_M2_TX_DP<2>P3E_PCH_M2_TX_DN<2>P3E_PCH_M2_TX_DP<1>P3E_PCH_M2_TX_DN<1>P3E_PCH_E1S_TX_DP<3>P3E_PCH_BMC_TX_DNP3E_PCH_BMC_TX_DPP3E_PCH_M2_TX_C_DP<0>P3E_PCH_M2_TX_C_DP<2>P3E_PCH_M2_TX_C_DN<1>P3E_PCH_M2_TX_C_DN<0>P3E_PCH_E1S_TX_C_DN<0>P3E_PCH_E1S_TX_C_DN<2>P3E_PCH_M2_TX_C_DP<3>P3E_PCH_M2_TX_C_DN<3>P3E_PCH_M2_TX_C_DP<1>P3E_PCH_M2_TX_C_DN<2>P3E_PCH_E1S_TX_C_DP<0>P3E_PCH_E1S_TX_C_DN<1>P3E_PCH_E1S_TX_C_DP<2>P3E_PCH_E1S_TX_C_DP<3>P3E_PCH_E1S_TX_C_DN<3>P3E_PCH_NVS_TX_C_DN<1>P3E_PCH_BMC_TX_C_DNP3E_PCH_BMC_TX_C_DPP3E_PCH_NVS_TX_C_DN<0>USB3_PCH_TX_C_DN<4>USB3_PCH_TX_C_DP<4>P3E_PCH_NVS_TX_C_DP<0>P3E_PCH_NVS_TX_C_DP<1>0402LF1/16W1001%CHIPX6SC0201 20% 6.3VDIFF BUS_0.22UFDIFF BUS_0.22UFDIFF BUS_0.22UFDIFF BUS_0.22UFDIFF BUS_0.22UFDIFF BUS_0.22UFDIFF BUS_0.22UFDIFF BUS_0.22UFDIFF BUS_0.22UFDIFF BUS_0.22UFDIFF BUS_0.22UFDIFF BUS_0.22UFDIFF BUS_0.22UFDIFF BUS_0.22UFDIFF BUS_0.22UFDIFF BUS_0.22UFDIFF BUS_0.22UFDIFF BUS_0.22UF0.1UFX6SC0201DIFF BUS_0.22UFX6S 0.1UFC0201DIFF BUS_0.22UFDIFF BUS_0.22UFDIFF BUS_0.22UFICGFNOCPU04302300-QV2N-MM#99A1WTSMLF
C2077
C2078
C1989
C1990
C1991
C1992
C1993
C1994
C1995
C1996
C1098
C1099
C1101
C1100
C1102
C1103
C1104
C1105
C2073
C2074
C2075
C2076
21
21
21
21
21
21
21
21
21
21
21
21
21
21
21
21
21
21
21
21
21
21
C1096
C1097
21
21
21
21
21
21
7
7
6
6
5
4
5
4
3
1
2
2
3
1
0
0
7
6
7
5
4
3
2
1
6
5
4
3
2
1
0
0
U4
3/11
SATA_9_PCIE3_9_USB3_9_TXP
SATA_9_PCIE3_9_USB3_9_TXN
SATA_9_PCIE3_9_USB3_9_RXP
SATA_9_PCIE3_9_USB3_9_RXN
SATA_8_PCIE3_8_USB3_8_TXP
SATA_8_PCIE3_8_USB3_8_TXN
SATA_8_PCIE3_8_USB3_8_RXP
SATA_8_PCIE3_8_USB3_8_RXN
SATA_7_PCIE3_7_USB3_7_TXP
SATA_7_PCIE3_7_USB3_7_TXN
SATA_7_PCIE3_7_USB3_7_RXP
SATA_7_PCIE3_7_USB3_7_RXN
SATA_6_PCIE3_6_USB3_6_TXP
SATA_6_PCIE3_6_USB3_6_TXN
SATA_6_PCIE3_6_USB3_6_RXP
SATA_6_PCIE3_6_USB3_6_RXN
SATA_5_PCIE3_5_USB3_5_TXP
SATA_5_PCIE3_5_USB3_5_TXN
SATA_5_PCIE3_5_USB3_5_RXP
SATA_5_PCIE3_5_USB3_5_RXN
SATA_4_PCIE3_4_USB3_4_TXP
SATA_4_PCIE3_4_USB3_4_TXN
SATA_4_PCIE3_4_USB3_4_RXP
SATA_4_PCIE3_4_USB3_4_RXN
SATA_3_PCIE3_3_USB3_3_TXP
SATA_3_PCIE3_3_USB3_3_TXN
SATA_3_PCIE3_3_USB3_3_RXP
SATA_3_PCIE3_3_USB3_3_RXN
SATA_2_PCIE3_2_USB3_2_TXP
SATA_2_PCIE3_2_USB3_2_TXN
SATA_2_PCIE3_2_USB3_2_RXP
SATA_2_PCIE3_2_USB3_2_RXN
SATA_1_PCIE3_1_USB3_1_TXP
SATA_1_PCIE3_1_USB3_1_TXN
SATA_1_PCIE3_1_USB3_1_RXP
SATA_1_PCIE3_1_USB3_1_RXN
SATA_15_PCIE3_15_TXP
SATA_15_PCIE3_15_TXN
SATA_15_PCIE3_15_RXP
SATA_15_PCIE3_15_RXN
SATA_14_PCIE3_14_GBE_2_TXP
SATA_14_PCIE3_14_GBE_2_TXN
SATA_14_PCIE3_14_GBE_2_RXP
SATA_14_PCIE3_14_GBE_2_RXN
SATA_13_PCIE3_13_TXP
SATA_13_PCIE3_13_TXN
SATA_13_PCIE3_13_RXP
SATA_13_PCIE3_13_RXN
SATA_12_PCIE3_12_GBE_1_TXP
SATA_12_PCIE3_12_GBE_1_TXN
SATA_12_PCIE3_12_GBE_1_RXP
SATA_12_PCIE3_12_GBE_1_RXN
SATA_11_PCIE3_11_TXP
SATA_11_PCIE3_11_TXN
SATA_11_PCIE3_11_RXP
SATA_11_PCIE3_11_RXN
SATA_10_PCIE3_10_GBE_0_TXP
SATA_10_PCIE3_10_GBE_0_TXN
SATA_10_PCIE3_10_GBE_0_RXP
SATA_10_PCIE3_10_GBE_0_RXN
SATA_0_PCIE3_0_USB3_0_TXP
SATA_0_PCIE3_0_USB3_0_TXN
SATA_0_PCIE3_0_USB3_0_RXP
SATA_0_PCIE3_0_USB3_0_RXN
RSVD_C40
RSVD_D39
RSVD_N40
RSVD_N42PHY_PCIE3_RCOMPP
PHY_PCIE3_RCOMPN
DMI_7_SATA_16_PCIE3_16_TXP
DMI_7_SATA_16_PCIE3_16_TXN
DMI_7_SATA_16_PCIE3_16_RXP
DMI_7_SATA_16_PCIE3_16_RXN
DMI_6_SATA_17_PCIE3_17_TXP
DMI_6_SATA_17_PCIE3_17_TXN
DMI_6_SATA_17_PCIE3_17_RXP
DMI_6_SATA_17_PCIE3_17_RXN
DMI_5_SATA_18_PCIE3_18_TXP
DMI_5_SATA_18_PCIE3_18_TXN
DMI_5_SATA_18_PCIE3_18_RXP
DMI_5_SATA_18_PCIE3_18_RXN
DMI_4_SATA_19_PCIE3_19_TXP
DMI_4_SATA_19_PCIE3_19_TXN
DMI_4_SATA_19_PCIE3_19_RXP
DMI_4_SATA_19_PCIE3_19_RXN
DMI_3_TXP
DMI_3_TXN
DMI_3_RXP
DMI_3_RXN
DMI_2_TXP
DMI_2_TXN
DMI_2_RXP
DMI_2_RXN
DMI_1_TXP
DMI_1_TXN
DMI_1_RXP
DMI_1_RXN
DMI_0_TXP
DMI_0_TXN
DMI_0_RXP
DMI_0_RXN
21 21
2
1
CAD NOTE:
N36P34G42G40 T34R32H43H41 W32U32J42J40 U36V34K43K41 V37T37L42L40 Y37W36M43M41 AG32AE32R42R40 AD37AE36U43U41 AG36AF34V42V40 AH37AF37W43W41 AJ32AH34Y42Y40 AM37AL36AA43AA41 AM34AK34AB42AB40 AT37AR36AC43AC41 AP34AN36AD42AD40 AK31AL32AE43AE41
N42N40D39C40
AR29AP31
H37F37D37B37
J36K37C36A36
H34G36D35B35
G32J32C34A34
K31L32D33B33
H31J29C32A32
F28G29D31B31
H28K28C30A30
21 21 21 21 21 21 21 21 21 21
21 21
21 21 21 21
SHEETDATE
DEPARTMENT
SIZE
PROJECT DOCUMENT NUMBER REV
REVIEWER
DESIGNER
123
7 3 2 1 6 5 4
E
A
B
C
E
D
C
B
A
7 6 5 4
D
OUTOUT
OUT
OUTOUT
OUTOUT
OUTOUTOUTIN
OUTOUTOUTOUTOUT
OUT
IN
INININ
IN
IN
IN
IN
ININ
IN
ININ
IN
IN
INININININ
ININ
IN
IN
OUTOUT
OUTOUT
OUT
OUTOUT
OUTOUT
OUT
IN
R495
C



20220725 CHANGE R1736 TO 33.2 OHM
20211116 MODIFY FOR GT20210630 MODIFY FOR GT
N/A182 OF 312V05Fri Aug 25 14:02:54 2023N/AN/AN/A
P3V3_AUXPVNN_TERM_CPU0P1V05_PCH_AUXP3V3_AUXP3V3_AUXP3V3_AUXP3V3_RTC_AUX
EMMITSBURG - GPIO/JTAG (4/10)182213 220182215182155161190182222219240199223252223252223220132203132182204 225204 225223 244131118203182182244 306 307 214222 219204 22513120013113413441311341321321971321821821821616FM_PCH_SLP_SUS_N1%0402LFFM_SLP_SUS_RSM_RST_NRST_PCH_RSTBTN_R_N75FM_BMC_RSTBTN_OUT_N1/16WCHIP33.21%33.2CHIP0402LF1/16WTP_PCH_SLP_S5_NPD_SUSCLKTP_PCH_GPP_O_111/16W1%1K0402LF4.75KFM_PCH_SLP_SUS_NIRQ_LVC3_WAKE_NRST_PCH_RSTBTN_R_NPWRGD_SYS_PWROKFM_PCH_SKIP_RTC_CLOCKTP_PCH_SLP_A_NFM_PCH_SLP_S4_NFM_PCH_SLP_S3_NFM_BMC_PWRBTN_N0402LFTP_SLP_LAN_NCHIPCHIP1/16W1%1/16W0402LF1KJTAG_DBP_TMS_PCHFM_PCH_CPU_PWR_DEBUG_N
1%0402LFCHIPCHIP1/16WCHIPH_DBP_PREQ_N_PCHFM_PCIE_EV_BIF_ENH_CPU_ERR2_PCH_R_NH_CPU_ERR1_PCH_R_N1MRST_RSMRST_PCH_NPWRGD_CPUPWRGD_GTLTP_PCH_CPU_MSMI_NTP_PCH_CPU_MEMTRIP_N1%H_THERMTRIP_LVC1_NTP_PLTRST_NFM_PCH_TRIGGER0_R_NFM_PCH_TRIGGER1_R_NNC_PCH_RSVD<3>PWRGD_DSW_PWROKPWRGD_PCH_PWROKGFNOCPU04302300-QV2N-MM#99A1WTICSMLFH_CPU_ERR0_PCH_R_NJTAG_DBP_PMODEFM_PCH_SPARE0JTAG_DBP_CPU_GTL_TCKJTAG_DBP_TCK_PCHJTAG_DBP_TDI_PCHJTAG_DBP_TDO_PCHPECI_PCHH_DBP_PRDY_N_PCH0402LF1001%1001%0402LFFM_PCH_TRIGGER0_R_N0402LF10K1/16W1%CHIPPU_ACPRESENT1%CHIP10K1/16W0402LFEMPTY1%0402LF1K1%1K0402LFEMPTY1%1/16W2.49K CHIP1/16W2001%0402LF1%1/16WEMPTY0402LF1/16W49.91%2000402LFFM_PCH_TRIGGER1_R_NEMPTY1/16WFM_PCIE_EV_BIF_ENFM_PCH_TRIGGER1_NFM_PCH_TRIGGER0_N1/16W0402LFEMPTY1/16W1%FM_INTRUDER_HDR_PCH_N1/16WCHIP0402LFCHIP1/16WPU_LAN_WAKE_NNC_PCH_RSVD<4>NC_PCH_RSVD<5>NC_PCH_RSVD<17>
R1736
R1676
R1675
R453
R1485 R1486
R697 R1200
R1201
R1197
R1198
U4
4/11
WAKE_N
TRIGGER1_N
TRIGGER0_N
SYS_RESET_N
SYS_PWROK
SUSCLK
SLP_SUS_N
SLP_S5_N
SLP_S4_N
SLP_S3_N
SLP_LAN_N
SLP_A_N
RSVD_AW23
RSVD_AV21
RSVD_BF39
RSVD_BG36
RSMRST_N
PWRBTN_N
PREQ_N
PRDY_N
PLTRST_CPU_N
PCH_PWROK
ME_PECI
LAN_WAKE_N
LANPHYPC
JTAG_TMS
JTAG_TDO
JTAG_TDI
JTAG_TCK
JTAGX
INTRUDER_N
GPP_O_7
GPP_O_0
DSW_PWROK
DBG_PMODE
CPU_THRMTRIP_N
CPU_PWR_DEBUG_N
CPU_MSMI_N
CPU_MEMTRIP_N
CPU_ERR2_N
CPU_ERR1_N
CPU_ERR0_N
CPU_CATERR_N
CPUPWRGD
ACPRESENT
21
2
1
2
1
21
21
21
2
1
2
1
21
2
1
21
21
21
21
2
1
2
1
2
1
AH11
K8H11
AJ10AL10
AR7
AL7
AJ13
AL13AP8
AK8
AM11
BG36BF39
AW26AV21
BD9
AR10
BF37BB37
M8
BE4
J10AJ7
AU7
BD35BD37BE36BE38BF35 BG8
AU10
AN10
BE8
BE40
G10F3
F5
F11E4
L7G7J7
F8
AN7
SHEETDATE
DEPARTMENT
SIZE
PROJECT DOCUMENT NUMBER REV
REVIEWER
DESIGNER
123
7 3 2 1 6 5 4
E
A
B
C
E
D
C
B
A
7 6 5 4
D
IN
OUT
OUTIN
IN
OUT
IN
IN
OUTIN
IN
IN
IN OUT
OUTIN
ININOUT
OUT
INININ
IN
OUT
INININ
ININOUTINOUT
INOUT
OUT
INOUTOUT
R494
R2966
R696
R1024 R1025 R1026
C



ENABLE BMC CLKREQ
20210602 MODIFY FOR GT
20211130 ADD 10K OHM PD20220805 ADD R4768
20220805 ADD R4766,DEPOP R4084
N/AN/AFri Aug 25 14:02:55 2023V05N/A183 OF 312N/AP3V3_AUXEMMITSBURG - GPIO/SMB (5/10)183183131202215183190183202202204202202202202204191131131131131131215216183
201131202131183183183183183198223204 205204 205183183183183183183183228301305183215183183183183183183183241 183183 241198204 205203205201204183201215205204198215204 215204183199223 255241198 201241183183183194183183131131183131131131183183183183 213194183183204183183183183215213 228183183183215228301305183215215213183183183183183183183
202204202183 241183 241191215183216131131131131183183183131240241240241215183183183183183183183183183183183183183183SMB_SML1_PMBUS_3V3AUX_PCH_SCL_R1CONN3_210-HP1-030BR1SMB_SML1_PMBUS_3V3AUX_PCH_SDA_R1JTAG_TRC_PCH_PTI<0>ESPI_LAD0_DATA_IO1FM_BMC_READY_R_NPD_PCH_GPPC_A_14GPPC_A_[10-19]:POWER RAIL --> 3.3VM2_SSD0_CLKREQ_EN_NPD_PCH_GPPC_A_10CLK_24M_66M_LPC0_ESPIIRQ_LPC_SERIRQ_ESPI_CS1_NESPI_LFRAME_N_BMC_CS0_NESPI_LAD0_DATA_IO3ESPI_LAD0_DATA_IO2ESPI_LAD0_DATA_IO0ESPI_ALERT1_N_LPC_RCIN_NE1S_0_PERST1_CLKREQ_NEMPTYJTAG_TRC_PCH_PTI<12>JTAG_TRC_PCH_PTI<11>JTAG_TRC_PCH_PTI<10>JTAG_TRC_PCH_PTI<9>JTAG_TRC_PCH_PTI<8>IRQ_BMC_PCH_NMI_RCHIP1%E1S_0_CLK_OE_N
JTAG_TRC_PCH_PTI<6>JTAG_TRC_PCH_PTI<5>PU_OC6_USB_NPU_OC5_USB_NPU_PCH_PLD_3V3AUX_ALERT_NPU_SMB_PCH_PLD_3V3AUX_SDAPU_SMB_PCH_PLD_3V3AUX_SCLFM_ADR_MODE1FM_BIOS_POST_CMPLT_NFM_THROTTLE_NPU_SMB_SML3_3V3AUX_PCH_SCLPU_SMB_SML3_3V3AUX_PCH_SDAPU_SMB_SML4_3V3AUX_PCH_SCLPU_SMB_SML4_3V3AUX_PCH_SDAPD_PCH_GPPC_C10PD_PCH_GPPC_C9SMB_SML1_PMBUS_3V3AUX_PCH_SDA_R1IRQ_SML1_PMBUS_ALERT_NFM_PMBUS_ALERT_B_ENPD_PCH_GPPC_C5SMB_SML1_PMBUS_3V3AUX_PCH_SCL_R1IRQ_SML0_ALERT_NSMB_SML0B_3V3AUX_SDASMB_SML0B_3V3AUX_SCLFM_BIOS_DEBUG_EN_R_NSMB_SML0_3V3AUX_PCH_SCLSMB_SML0_3V3AUX_PCH_SDAFM_PCH_BOOT_BIOS_STRAPFM_PCH_GLB_RST_WARN_NFM_PLT_BMC_THERMTRIP_R_NFM_CPU_RMCA_CATERR_DLY_NFM_BIOS_IMAGE_SWAP_NFM_PCHHOT_NFM_ADR_COMPLETEFM_ADR_TRIGGER_R_NPU_PCH_VRALERT_NFM_ADR_ACKIRQ_PCH_SCI_WHEA_NPU_LPC_PME_NFM_PCH_CRASHLOG_TRIG_NFM_ESPI_FLASH_MODERST_PLTRST_NSMB_HOST_BMC_3V3AUX_SCLFM_FLASH_SECURITY_STRAPSMB_HOST_BMC_3V3AUX_SDAPD_PCH_GPPC_A_19PD_PCH_GPPC_A_18IRQ_BMC_PCH_NMIFM_PCH_SATA_RAID_KEYPD_PCH_GPPC_A_15JTAG_TRC_PCH_PTI1_CLKJTAG_TRC_PCH_PTI<7>PU_OC4_USB_NJTAG_TRC_PCH_PTI<2>JTAG_TRC_PCH_PTI<1>JTAG_TRC_PCH_PTI0_CLKTP_PCH_GPP_D_2TP_PCH_GPP_D_20ICSMLFGFNOCPU04302300-QV2N-MM#99A1WT0
CHIPCHIPPD_PCH_GPPC_A_19PD_PCH_GPPC_C5PD_PCH_GPPC_C9PD_PCH_GPPC_A_141%CHIPIRQ_SML1_PMBUS_PLD_ALERT_NCHIP1%FM_PCH_SATA_RAID_KEYFM_PCHHOT_NUSB_OC1_REAR_R_NFM_BIOS_DEBUG_EN_R_NSMB_SML1_PMBUS_3V3AUX_PCH_SCL_R1SMB_SML1_PMBUS_3V3AUX_PCH_SDA_R100402LFCHIPCHIPCHIP33.21/16WCHIPUSB_OC1_REAR_N1/16WTHLFEMPTYTHLF0402LF0402LF100EMPTY1/16W33.233.233.21%CHIP1%1%1%IRQ_SML0_ALERT_R_N1%CHIP01/16W0402LF5%33.233.2CHIPIRQ_SML0_ALERT_N1%CHIPPD_PCH_GPPC_A_10PD_PCH_GPPC_C1010K10K10K10K10K1%1%1%1%1%CHIPCHIPFM_PCH_CRASHLOG_TRIG_R_NIRQ_SML1_PMBUS_ALERT_NFM_BIOS_DEBUG_EN_NIRQ_SML1_PMBUS_BMC_ALERT_NFM_PCH_CRASHLOG_TRIG_N10K1%10KCHIPCHIP1%CHIP10KCHIP2KCHIP2K2KCHIP2K2K2K1%2K0402LFPU_OC6_USB_NPU_OC5_USB_NPU_OC4_USB_NPU_OC3_USB_NPU_OC2_USB_NUSB_OC1_REAR_R_N10K1%10K1%10KCHIP
EMPTYIRQ_LPC_PIRQA_N_ESPI_ALERT0_N
1%
0402LF0402LF0E1S_0_CLKREQ_NRST_ESPI_RESET_NSMB_SML0_3V3AUX_PCH_SCLSMB_SML0_3V3AUX_PCH_SDACHIP10K33.21/16W
E1S_0_PRSNT_N49.9E1S_0_CLK_OE_NCHIPJTAG_TRC_PCH_PTI<13>JTAG_TRC_PCH_PTI<14>JTAG_TRC_PCH_PTI<15>JTAG_TRC_PCH_PTI<3>CONN3_210-HP1-030BR1PU_OC3_USB_NPU_OC2_USB_NUSB_OC1_REAR_R_NJTAG_TRC_PCH_PTI<4>SMB_SML1_PMBUS_3V3AUX_PCH_SDASMB_SML1_PMBUS_3V3AUX_PCH_SCL33.2CHIPFM_PCHHOT_R_NCHIPCHIPCHIP1%1%10KCHIP1%10K0402LF1/16W10K1%1/16W1%1%1%1%1%CHIPCHIPCHIPCHIPCHIP1%2KPU_SMB_SML3_3V3AUX_PCH_SDAPU_SMB_SML3_3V3AUX_PCH_SCLSMB_SML0B_3V3AUX_SDASMB_SML0B_3V3AUX_SCL10K0402LFPU_PCH_PLD_3V3AUX_ALERT_NPU_SMB_PCH_PLD_3V3AUX_SDAPU_SMB_PCH_PLD_3V3AUX_SCLIRQ_BMC_PCH_NMI0402LFCHIPCHIPCHIP1%1%10K10KPD_PCH_GPPC_A_18PD_PCH_GPPC_A_150402LF1/16WCHIP1/16W1%1%CHIP1%IRQ_SML0_ALERT_NFM_PMBUS_ALERT_B_ENPU_SMB_SML4_3V3AUX_PCH_SCLPU_SMB_SML4_3V3AUX_PCH_SDA4.75K
R1269
R4766
R4504
R4505
R4100
R4101
R4102
R4099
R4098
R4097
R4096
R4095
R4083
R4084
R3938
R2971
R913
R770
R727
R635
R1268
R474
R1827
R1828
R1659
R1657
R1656
R1601
R1600
R1487
R6993
2
1
3
2
1
JP9
JP4
U4
5/11
GPP_D_9_PME_N
GPP_D_8_CRASHLOG_TRIG_N
GPP_D_7
GPP_D_6
GPP_D_2_HS_SMBALERT_N_DMA_SMBALERT_N
GPP_D_23
GPP_D_22_USB2_OCB_7
GPP_D_21_GLB_RST_WARN_N
GPP_D_20_CATERR_N
GPP_D_1_HS_SMBDATA_DMA_SMBDATA
GPP_D_19_MSMI_N
GPP_D_18_MEMTRIP_N
GPP_D_17_THERMTRIP_N
GPP_D_16_ADR_ACK
GPP_D_15_VRALERT_N
GPP_D_14_ADR_TRIGGER_N
GPP_D_13_ADR_COMPLETE
GPP_D_12_PCHHOT_N
GPP_D_11_PLTRST_N
GPP_D_10_BM_BUSY_N_SX_EXIT_HOLDOFF_N
GPP_D_0_HS_SMBCLK_DMA_SMBCLK
GPPC_C_9_ME_SML2CLK
GPPC_C_8_ME_SML1ALERT_N
GPPC_C_7_ME_SML1DATA
GPPC_C_6_ME_SML1CLK
GPPC_C_5_ME_SML0BALERT_N
GPPC_C_4_ME_SML0BCLK
GPPC_C_3_ME_SML0BDATA
GPPC_C_2_ME_SML0ALERT_N
GPPC_C_21_MC_SMBALERT_N
GPPC_C_20_MC_SMBDATA
GPPC_C_1_ME_SML0DATA
GPPC_C_19_MC_SMBCLK
GPPC_C_18
GPPC_C_17_ME_SML4ALERT_N
GPPC_C_16_ME_SML4DATA
GPPC_C_15_ME_SML4CLK
GPPC_C_14_ME_SML3ALERT_N
GPPC_C_13_ME_SML3DATA
GPPC_C_12_ME_SML3CLK
GPPC_C_11_ME_SML2ALERT_N
GPPC_C_10_ME_SML2DATA
GPPC_C_0_ME_SML0CLK
GPPC_B_9_USB2_OCB_4
GPPC_B_8_USB2_OCB_3
GPPC_B_7_USB2_OCB_2
GPPC_B_6_USB2_OCB_1
GPPC_B_5_USB2_OCB_0
GPPC_B_4_GSXCLK
GPPC_B_3_GSXRESET_N
GPPC_B_2_GSXDIN
GPPC_B_23
GPPC_B_22
GPPC_B_21
GPPC_B_20
GPPC_B_1_GSXSLOAD
GPPC_B_19_HS_UART1_CTS_N
GPPC_B_17_HS_UART1_TXD
GPPC_B_16_HS_UART1_RXD
GPPC_B_15_HS_UART0_CTS_N
GPPC_B_14_HS_UART0_RTS_N
GPPC_B_13_HS_UART0_TXD
GPPC_B_12_HS_UART0_RXD
GPPC_B_11_USB2_OCB_6
GPPC_B_10_USB2_OCB_5
GPPC_B_0_GSXDOUT
GPPC_A_9_ESPI_CLK
GPPC_A_8_ESPI_RESET_N
GPPC_A_7_ESPI_CS1_N
GPPC_A_6_ESPI_CS0_N
GPPC_A_5_ESPI_IO_3
GPPC_A_4_ESPI_IO_2
GPPC_A_3_ESPI_IO_1
GPPC_A_2_ESPI_IO_0
GPPC_A_1_ESPI_ALERT1_N
GPPC_A_19_SRCCLKREQ_N_9
GPPC_A_18_SRCCLKREQ_N_8
GPPC_A_17_SRCCLKREQ_N_7
GPPC_A_16_SRCCLKREQ_N_6
GPPC_A_15_SRCCLKREQ_N_5
GPPC_A_14_SRCCLKREQ_N_4
GPPC_A_13_SRCCLKREQ_N_3
GPPC_A_12_SRCCLKREQ_N_2
GPPC_A_11_SRCCLKREQ_N_1
GPPC_A_10_SRCCLKREQ_N_0
GPPC_A_0_ESPI_ALERT0_N
GPPC_B_18_HS_UART1_RTS_N
1
2
3
1
2
3
21R4768
21
21 21
21 21 21
21 21 21 21 21
21
21
21
21
21 21 21 21
21
21
21
21
21 21
21
21
21
21
R1583
21R1581 21R1582
21R1546
21R1545
21
21R1454
21R1453
21R1452
21R1451
21
DESIGN NOTE:
AN2AT1AL1AL5AL3AV1BA2AW2AY1AN4AV3AP3AR2AR4AW4AP1AT3BB3AU4AU2BA4BC4BD23BE22BF23BE24BF25BD25BF27BE26BD27BF29BE28BD29BG22BG24BG26BG28BG30BG32BF31BE30BD31BF33BE32BD33
BG14BF11BF13BD11BE14BE12BF15BG16BG18BD17BD13BF17BE16BE20BD19BE18BF19BG12BD15BG20
W1AA3AA1AG3Y4AF4Y2AD4AC3AH4AC1AH2AB4AB2AJ3AE3AG1AJ1AD2AE1AF2
SHEETDATE
DEPARTMENT
SIZE
PROJECT DOCUMENT NUMBER REV
REVIEWER
DESIGNER
123
7 3 2 1 6 5 4
E
A
B
C
E
D
C
B
A
7 6 5 4
D
OUT
ININ
INININININ
BI
OUT
OUTINININOUTININ
OUT
IN
INBIOUT
BIOUT
ININ
INININ
IN
INBIOUT
BIOUT
IN
OUTOUTOUTOUT
BIBIBIBI
IN
OUT
OUT
IN
IN
BI
OUT
IN OUT BI
OUTOUTOUT
OUT
IN
ININ
OUTOUTOUTOUTOUT
OUT
IN
ININ
OUT
ININ
IN
IN
OUT
IN
OUT
IN
IN
IN
BI
OUT
BI
IN
OUTIN
OUT
IN
IN
OUTOUT
OUT
OUT
OUTOUTOUT
IN
OUT
INININ
OUT
OUT
IN OUT
OUT
OUT
OUT
OUT IN
OUT
OUT
OUT
OUT
OUT
OUTIN
OUTOUT
OUT
OUT
IN OUT
OUT
OUTOUT
OUTOUT
IN
IN
IN
OUTOUT
OUTOUT
IN
C



20211130 ADD 10K OHM PDPCIE10SATACONFIG
20210602 MODIFY FOR GT
10GPP_E_7 GPP_E_620220801 ADD R4722 10K OHM PUFri Aug 25 14:02:56 2023N/AN/AN/AN/AV05184 OF 312
P3V3_AUXP3V3_AUX
EMMITSBURG - GPIO/JTAG (6/10)184184184215184184215184184184184184204 2152002012012001951951951951951951952011841414184184184184184184184184184184184184184184184184184199199195200213204215204215184184190184199204200200199190 184184204215204205184184184184184184184199200PD_GPP_M_8PD_GPP_M_15CHIPCHIPFM_PCH_BMC_RST_R_NCHIP1%10KPD_GPP_M_161%10KCHIP10K1%CHIPFM_PCH_BMC_RST_R_NTP_GPP_L_8PD_GPP_I_13PD_GPP_I_14PD_GPP_I_15PD_GPP_I_16PD_GPP_I_17IRQ_TPM_SPI_NTP_GPP_L_7TP_GPP_L_2FM_BIOS_ADV_FUNCTIONSFM_ME_RCVR_NFM_PASSWORD_CLEAR_NFM_MFG_MODE
10K1%1%CHIPCHIPCHIPCHIPCHIPFAB_REV_ID1FAB_REV_ID2FM_BOARD_SKU_ID0FAB_REV_ID0FM_BOARD_SKU_ID1FM_BOARD_SKU_ID2FM_BOARD_SKU_ID4FM_PCH_BIOS_RCVR_MODETP_GPP_M_12PD_GPP_M_16H_CPU0_PMSYNC_PCH_R2H_CPU0_PMDOWN_PCHPD_GPP_M_17PD_GPP_M_15PD_GPP_M_8PD_PCH_GPP_E_111%CHIPPD_GPP_M_17PD_GPP_I_16PD_GPP_I_17PD_PCH_GPP_E_14PD_GPP_I_15PD_PCH_GPP_E_13PD_PCH_GPP_E_12PD_PCH_GPP_E_8PD_PCH_GPP_E_10PD_PCH_GPP_E_9PD_GPP_I_13PD_GPP_I_14PD_PCH_GPP_E_310KCHIP1%10K1%1%CHIP10K10K1%CHIP10K1%CHIP10K1%CHIP1%10K10KCHIP10K1%1%10K10K1%10K1%CHIP10K1%10KFM_PCH_VISA_DEFAULTFM_PCH_IO_EXPANDERFM_BOARD_SKU_ID3ICFM_PCH_MCRO_LDOFM_TPM_PRSNT_NSMLFGFNOCPU04302300-QV2N-MM#99A1WTEMPTY10K1%10K1/16WEMPTY1%EMPTY0402LF1K1/16W0402LF1K1%0402LFFM_ME_AUTHN_FAILFM_DEBUG_PORT_PRSNT_R_NTP_EDSFF1B_TYPE_IDTP_EDSFF1A_TYPE_IDPD_PCH_GPP_E_3FM_M2_SSD0_E7_PEDETFM_M2_E1S_E6_PEDETTP_PCH_GPP_E_2TP_PCH_GPP_E_1TP_PCH_GPP_E_0FM_LT_KEY_DOWNGRADE_NPU_PCH_PMCALERT_NFM_PCH_XTAL_INPUT_MODE_MGPIO_TEST3FM_PCH_RING_OSC_BYPASS_MGPIO_TEST2FM_PCH_EXTERNALCLKMODEFM_M2_SSD0_E7_PEDET1%1/16W1/16WEMPTY0402LFFM_M2_E1S_E6_PEDETFM_ME_BT_DONEFM_PS_PWROK_DLY_R_SELPD_PCH_GPP_E_14PD_PCH_GPP_E_9PD_PCH_GPP_E_8PD_PCH_GPP_E_10PD_PCH_GPP_E_11PD_PCH_GPP_E_12PD_PCH_GPP_E_13TP_PCH_MGPIO_TEST1FM_PCH_XTALSELFM_PCH_DFXTESTMODE
R4722
U4
6/11
GPP_M_8
GPP_M_7
GPP_M_6
GPP_M_5
GPP_M_4
GPP_M_3
GPP_M_2
GPP_M_17
GPP_M_16
GPP_M_15
GPP_M_12
GPP_M_11
GPP_M_1
GPP_M_0
GPP_L_8
GPP_L_7
GPP_L_6
GPP_L_5
GPP_L_4
GPP_L_3
GPP_L_2
GPP_L_1_PM_DOWN_0
GPP_L_0_PM_SYNC_0
GPP_I_23
GPP_I_22
GPP_I_21
GPP_I_17_HDA_SDI_1
GPP_I_16_HDA_SDI_0
GPP_I_15_HDA_SDO
GPP_I_14_HDA_SYNC
GPP_I_13_HDA_RST_N
GPP_I_12_HDA_BCLK
GPP_E_9_SATA0_SLOAD_SATA0_DEVSLP
GPP_E_8_SATA0_SCLOCK_SATA0_LED_N
GPP_E_7_SATA0_USB3_XPCIE_1
GPP_E_6_SATA0_USB3_XPCIE_0
GPP_E_5_SATA0_XPCIE_3
GPP_E_4_SATA0_XPCIE_2
GPP_E_3_SATA1_XPCIE_3
GPP_E_2_SATA1_XPCIE_2
GPP_E_1_SATA1_XPCIE_1
GPP_E_19_ERR2_N
GPP_E_18_ERR1_N
GPP_E_17_ERR0_N
GPP_E_16_SATA2_SDATAOUT_SATA2_DEVSLP
GPP_E_15_SATA2_SLOAD_SATA2_GP
GPP_E_14_SATA2_SCLOCK_SATA2_LED_N
GPP_E_13_SATA1_SDATAOUT_SATA1_DEVSLP
GPP_E_12_SATA1_SLOAD_SATA1_GP
GPP_E_11_SATA1_SCLOCK_SATA1_LED_N
GPP_E_10_SATA0_SDATAOUT_SATA0_GP
GPP_E_0_SATA1_XPCIE_0
GPPC_H_7
GPPC_H_6
GPPC_H_19
GPPC_H_18_PMCALERT_N
GPPC_H_17_FLEX_CLK_OUT_2
GPPC_H_16_FLEX_CLK_OUT_1
GPPC_H_15_FLEX_CLK_OUT_0
GPPC_H_1
GPPC_H_0
21
21
21
21R4117
21R4116
21R4113
21R4114
21R4111
21R4112
21R4110
21R4115
21
21
21
21R4103
21R4104
21R4106
21R4105
2
1
2
1
2
1
2
1
DESIGN NOTE:
R4565
R4564
R4107
R4108
R4109
L4J4H3G2J2K3L2K1G4
W13N10T8U7R7W10AB11R10V8W7AA10AA7AA13N7
AE10AC7AG10AB8AG7AF11AC10AE7AF8
R4P3N4V4U1R2P1N2U3
BB31BA20BA36AW29AW20BB34BA32BB28AV34AV31BA29AW36AW32BB24AV28AV24BB21AW23BA23BA26
SHEETDATE
DEPARTMENT
SIZE
PROJECT DOCUMENT NUMBER REV
REVIEWER
DESIGNER
123
7 3 2 1 6 5 4
E
A
B
C
E
D
C
B
A
7 6 5 4
D
ININ
IN
IN
IN
OUTOUT
IN
ININ
IN
ININ
IN
INININ
IN
IN
OUT
OUT
OUT
OUT
IN
ININ
INININ
INININ
IN
ININININ
OUT
OUT
OUT
OUT
OUT
OUT
OUT
OUT
OUT
IN
OUT
OUT
IN
OUT
OUT
OUT
OUT
OUT
OUT
INININ
IN
OUT
OUT
ININ
ININ
IN
ININ
INOUT
R2511
R2510
R2509
R2508
C



20220729 POP R4712,R471320220729 POP Q3520220725 POP Q34ADD 22 OHM ON SCM BD20211130 CHANGE TO 0 OHMBATTERY
Fri Aug 25 14:02:57 2023V05N/AN/A185 OF 312N/AN/AP3V3_RTC_AUXP3V_BAT_RP3V3_AUXP3V3_RTC_AUXP3V3_AUX
EMMITSBURG - GPIO/SPI (7/10)222185185185185198131198205199199
201 185
204 205185213185131198213204 205
213185185240240185185185185185240240240240240
185185 201200198214 240200185185185185185185185222RST_PFR_OVR_SRTC2N7002KCHIP1/16W1%IC0402LF100KSMLF0402LF1/16WSPI_PCH_CLKRST_SRTCRST_NIC5%2N7002KSMLF0402LFC04020402LF 1/16W05%CHIPCHIPCHIP5%5%1%CHIPFM_EUP_LOT6_NIOTHLFCONN2_AAA-BAT-029-Y19P3V_BAT1/16WEMPTY1%RST_SRTCRST_NICGFNOCPU04302300-QV2N-MM#99A1WTSMLF
ICSMLFBAS70-05-7-FC0402X6S1UF25V10%1UF10%X6S25VP3V_BAT_RFM_SPI_3V3_1V8_VOLTAGEFM_ADR_MODE0TP_PCH_CGC_DUT_DETECTEDTP_PCH_GPP_N_4TP_PCH_GPP_N_1FM_JTAG_ODT_DISABLEFM_ESPI_CS_SWIZZLE
RST_RTCRST_N
IRQ_SMI_ACTIVE_NFM_SUSACK_NFM_EUP_LOT6_NFM_PCH_CONSENT_STRAP_NFM_PCH_PRSNT_NIRQ_PCH_CPU_NMI_EVENT_R_N
0 FM_SUSACK_N05%0402LF
1%10K1/16WCHIP0402LF
1KCHIP0402LF 1/16W1/16W0402LFCHIP20K1%SPI_PCH_CS0_R_N SPI_SYS_CS0_N33.2SPI_TPM_CS_N1%1/16W1%5%1/16W0SPI_PCH_IO2SPI_PCH_IO1SPI_PCH_IO305%0CHIP0402LF00402LFCHIPCHIPCHIP0402LF1/16W33.2SPI_PCH_TPM_CS_N0402LF1/16W1/16W0402LF33.2SPI_PCH_IO0SPI_SYS_MISOSPI_SYS_WP_IO2SPI_SYS_HOLD_IO3SPI_SYS_CLKSPI_SYS_MOSI
RST_SRTCRST_NRST_RTCRST_NFM_XTAL_INPUT_FREQUENCY_1_MGPIO_TEST5FM_PCH_SPKRFM_XTAL_INPUT_FREQUENCY_0_MGPIO_TEST4SPI_PCH_CLKTP_SPI_PCH_CS1_R_NSPI_PCH_CS0_R_NSPI_PCH_TPM_CS_NSPI_PCH_IO1SPI_PCH_IO0SPI_PCH_IO3SPI_PCH_IO2EMPTYCHIP1/16W100K1%RST_PFR_OVR_RTC240
U62
G
G
S D S D
R917
R918
R916
R915
R499
R1395
R501
R1840
R1839
R1461
R1203
G
G
2 1
S D S D
Q35
Q34
BT1
U4
C
A
B2 1
7/11
VSS_A41
SRTCRST_N
SPI0_TPM_CS_N
SPI0_MISO_IO_1
SPI0_MOSI_IO_0
SPI0_IO_3
SPI0_IO_2
SPI0_FLASH_1_CS_N
SPI0_FLASH_0_CS_N
SPI0_CLK
RCTRST_N
NC_CGC_DUT_DETECT_N
GPP_N_4
GPP_N_1
GPPC_S_9_SMI_N
GPPC_S_8_NMI_N
GPPC_S_7_SUSACK_N
GPPC_S_6_SUSWARN_N_SUSPWRDNACK
GPPC_S_5_CPU_GP_3
GPPC_S_4_CPU_GP_2
GPPC_S_3_CPU_GP_1
GPPC_S_2_CPU_GP_0
GPPC_S_1_SPKR_TIME_SYNC_1
GPPC_S_11
GPPC_S_10
GPPC_S_0_TIME_SYNC_0
S
G
D
S
G
D
2
1
2
1
21
21
21
21
21
21
21
21
21
21
2
1
2
1
2
1
21
2
1
31
2
A41
BF9
BB11
BA13AW16
BA16AV15
BA10AW13
BB15
BD7
BG3
BB8AW10AV18AP15BA7AR13AT18AU13AV11AR16AU16BB18
V11
T11
SHEETDATE
DEPARTMENT
SIZE
PROJECT DOCUMENT NUMBER REV
REVIEWER
DESIGNER
123
7 3 2 1 6 5 4
E
A
B
C
E
D
C
B
A
7 6 5 4
D
OUT
OUT
OUT
OUT
OUT
OUT
OUT
IN
OUT
OUT
IN
IN OUT
OUT
IN
IN
OUT
IN
OUT
OUT
OUTOUT
OUT
IN
OUT
ININ
IN
OUTIN
IN
IN
OUT
OUT
OUT
OUT
IN
IN
IN
IN
IN
IN
IN
R4713
R4712
R1202
C610
C611
R498
C



Fri Aug 25 14:02:58 2023N/AN/AN/AN/AV05186 OF 312
P3V3_AUXP3V3_AUXP1V8_PCH_AUXP1V8_PCH_PLL_AUXP1V05_PCH_AUXP1V05_PCH_AUXP1V05_PCH_PLL_AUXP3V3_RTC_AUX
EMMITSBURG - POWER (8/10)
TP_PCH_RSVD<15>TP_PCH_RSVD<16>ICGFNOCPU04302300-QV2N-MM#99A1WTSMLF
U4
8/11
VSS_BG40
VCCRTC
VCCP_VNN_AF20
VCCP_VNN_AF22
VCCP_VNN_AG20
VCCP_VNN_AG22
VCCP_VNN_AJ20
VCCP_VNN_AJ22
VCCP_VNN_AL20
VCCP_VNN_AL22
VCCP_VNN_AN23
VCCP_VNN_AP21
VCCP_VNN_AR23
VCCP_GPPI_1P8_3P3
VCCP_GPPE_1P8_3P3
VCCP_GPPD_1P8_3P3
VCCP_3P3_DSW_V15
VCCP_3P3_DSW_AD15
VCCP_3P3_AK15
VCCP_3P3_AF17
VCCP_3P3_AG17
VCCP_3P3_AJ17
VCCP_3P3_AL17
VCCP_3P3_P21
VCCP_1P8_FILTERED_AB31
VCCP_1P8_FILTERED_W27
VCCP_1P8_FILTERED_U29
VCCP_1P8_FILTERED_W29
VCCP_1P8_FILTERED_AB34
VCCP_1P8_U17
VCCP_1P8_U19
VCCP_1P8_U20
VCCP_1P8_U22
VCCP_1P8_U24
VCCP_1P8_N20
VCCP_1P05_FILTERED_R23
VCCP_1P05_FILTERED_R26
VCCP_1P05_FILTERED_AA29
VCCP_1P05_FILTERED_U27
VCCP_1P05_FILTERED_R29
VCCP_1P05_FILTERED_AE29
VCCP_1P05_FILTERED_AG29
VCCP_1P05_FILTERED_AL25
VCCP_1P05_P15
VCCP_1P05_M24
VCCP_1P05_AR26
VCCP_1P05_N23
VCCP_1P05_N26
VCCP_1P05_FILTERED_AB27
VCCP_1P05_AD25
VCCP_1P05_AD27
VCCP_1P05_AF25
VCCP_1P05_AF27
VCCP_1P05_AG25
VCCP_1P05_AG27
VCCP_1P05_AJ25
VCCP_1P05_AJ27
VCCP_1P05_AB19
VCCP_1P05_AB20
VCCP_1P05_AB22
VCCP_1P05_AB24
VCCP_1P05_W17
VCCP_1P05_W19
VCCP_1P05_W20
VCCP_1P05_W22
VCCP_1P05_W24
RSVD_AN26
RSVD_AF15
BG40
AH15
AR23AP21AN23AL22AL20AJ22AJ20AG22AG20AF22AF20
AD17AN20T15
P21
V15AD15
AL17
AK15
AJ17AG17AF17
U24U22U20U19U17N20
W29
W27U29
AB34
AB31
W24W22W20W19W17
P15
N26N23
M24
U27R29
R26R23
AL25AG29AE29
AB27
AA29
AR26
AJ27AJ25AG27AG25AF27AF25AD27AD25
AB24AB22AB20AB19
AN26AF15
SHEETDATE
DEPARTMENT
SIZE
PROJECT DOCUMENT NUMBER REV
REVIEWER
DESIGNER
123
7 3 2 1 6 5 4
E
A
B
C
E
D
C
B
A
7 6 5 4
D
C



Fri Aug 25 14:02:59 2023N/AN/AN/AN/AV05187 OF 312EMMITSBURG - RSVD (9/10)
0402LFCHIP1/16W1%200TP_PCH_RSVD<0>TP_PCH_RSVD<1>TP_PCH_RSVD<2>TP_PCH_RSVD<6>TP_PCH_RSVD<7>TP_PCH_RSVD<12>TP_PCH_RSVD<13>PD_RCOMP_1P8_3P3SMLFGFNOCPU04302300-QV2N-MM#99A1WTIC
U4
9/11
RSVD_H1
RSVD_F1
RSVD_A4
RSVD_P18
RSVD_BB43
RSVD_N13
RSVD_L13
GPIO_RCOMP_1P8_3P3
2
1
P18
N13L13 H1 F1
BB43
A4
AC13
SHEETDATE
DEPARTMENT
SIZE
PROJECT DOCUMENT NUMBER REV
REVIEWER
DESIGNER
123
7 3 2 1 6 5 4
E
A
B
C
E
D
C
B
A
7 6 5 4
D
R497
C



188 OF 312V05Fri Aug 25 14:03:00 2023N/AN/AN/AN/AEMMITSBURG - GND (10/10)
SMLFGFNOCPU04302300-QV2N-MM#99A1WTICICGFNOCPU04302300-QV2N-MM#99A1WTSMLF
U4U4
11/11
VSS_A20
VSS_A22
VSS_A24
VSS_A26
VSS_AA17
VSS_AA19
VSS_AA20
VSS_AA22
VSS_AA24
VSS_AA25
VSS_AA27
VSS_AA32
VSS_AA36
VSS_AA39
VSS_AA5
VSS_AB15
VSS_AB17
VSS_AB25
VSS_AB37
VSS_AC29
VSS_AC32
VSS_AC36
VSS_AC39
VSS_AC5
VSS_AD11
VSS_AD19
VSS_AD20
VSS_AD22
VSS_AD24
VSS_AD31
VSS_AD34
VSS_AD8
VSS_AE13
VSS_AE39
VSS_AE5
VSS_AF19
VSS_AF24
VSS_AF31
VSS_AF40
VSS_AF42
VSS_AG13
VSS_AG19
VSS_AG24
VSS_AG39
VSS_AG5
VSS_AH31
VSS_AH8
VSS_AJ19
VSS_AJ24
VSS_AJ29
VSS_AJ36
VSS_AJ39
VSS_AJ5
VSS_AK11
VSS_AK2
VSS_AK37
VSS_AK4
VSS_AL19
VSS_AL24
VSS_AL27
VSS_AL29
VSS_AL39
VSS_AM15
VSS_AM31
VSS_AM8
VSS_AN13
VSS_AN16
VSS_AN29
VSS_AN32
VSS_AP11
VSS_AP18
VSS_AP24
VSS_AP28
VSS_AP37
VSS_AP39
VSS_AP5
VSS_AR20
VSS_AR32
VSS_AT11
VSS_AT15
VSS_AT21
VSS_AT24
VSS_AT28
VSS_AT31
VSS_AT34
VSS_AT39
VSS_AT5
VSS_AT8
VSS_AU20
VSS_AU23
VSS_AU26
VSS_AU29
VSS_AU32
VSS_AU36
VSS_AV37
VSS_AV39
VSS_AV5
VSS_AV8
VSS_AW7
VSS_AY11
VSS_AY15
VSS_AY18
VSS_AY21
VSS_AY24
VSS_A38
VSS_A40
VSS_A6
VSS_BB1
VSS_BG38
VSS_BG4
VSS_BG6
VSS_F43
VSS_BC2
VSS_BC42
VSS_BD3
VSS_BD41
VSS_D3
VSS_D41
VSS_E2
VSS_E42
VSS_BD1
VSS_BD43
VSS_BE1
VSS_BE3
VSS_BE41
VSS_BE43
VSS_BG41
VSS_C3
VSS_C41
VSS_C43
VSS_D1
VSS_D43
10/11
VSS_E8
VSS_B39
VSS_C38
VSS_AY3
VSS_BC36
VSS_BD5
VSS_E40
VSS_F41
VSS_AY39
VSS_AY28
VSS_AY31
VSS_AY34
VSS_AY37
VSS_AY5
VSS_AY8
VSS_B13
VSS_B29
VSS_B9
VSS_BB39
VSS_BB5
VSS_BC10
VSS_BC12
VSS_BC14
VSS_BC16
VSS_BC18
VSS_BC20
VSS_BC22
VSS_BC24
VSS_BC26
VSS_BC28
VSS_BC30
VSS_BC32
VSS_BC34
VSS_BC38
VSS_BC6
VSS_BC8
VSS_BD21
VSS_BD39
VSS_BE10
VSS_BE34
VSS_BF21
VSS_BG10
VSS_BG34
VSS_C20
VSS_C22
VSS_C24
VSS_C26
VSS_C4
VSS_D13
VSS_D29
VSS_D5
VSS_D9
VSS_E10
VSS_E12
VSS_E14
VSS_E16
VSS_E18
VSS_E20
VSS_E22
VSS_E24
VSS_E26
VSS_E28
VSS_E30
VSS_E32
VSS_E34
VSS_E36
VSS_E38
VSS_E6
VSS_F15
VSS_F24
VSS_F31
VSS_F34
VSS_F39
VSS_G13
VSS_G20
VSS_G26
VSS_H39
VSS_H5
VSS_H8
VSS_J13
VSS_J20
VSS_J26
VSS_K11
VSS_K15
VSS_K24
VSS_K34
VSS_K39
VSS_K5
VSS_L10
VSS_L16
VSS_L20
VSS_L23
VSS_L26
VSS_L29
VSS_L36
VSS_M1
VSS_M11
VSS_M15
VSS_M18
VSS_M21
VSS_M28
VSS_M3
VSS_M31
VSS_M34
VSS_M37
VSS_M39
VSS_M5
VSS_N16
VSS_N32
VSS_P11
VSS_P24
VSS_P28
VSS_P31
VSS_P37
VSS_P39
VSS_P41
VSS_P43
VSS_P5
VSS_P8
VSS_R13
VSS_R16
VSS_R20
VSS_R36
VSS_T31
VSS_U10
VSS_U13
VSS_U25
VSS_U39
VSS_U5
VSS_V2
VSS_V31
VSS_W25
VSS_W3
VSS_W39
VSS_W5
VSS_Y11
VSS_Y15
VSS_Y31
VSS_Y34
VSS_Y8
BC14
F43
E42E2
D43
D41D3
D1C43C41C3BG41
BG38
BG6BG4
BE43BE41BE3BE1BD43
BD41BD3
BD1
BC42BC2
BB1
AY24AY21AY18AY15AY11AW7
AV39AV37
AV8AV5
AU36AU32AU29AU26AU23AU20
AT39AT34AT31AT28AT24AT21AT15AT11
AT8AT5
AR32AR20
AP39AP37AP28AP24AP18AP11
AP5
AN32AN29AN16AN13
AM31AM15
AM8
AL39AL29AL27AL24AL19
AK37
AK11
AK4
AK2
AJ39AJ36AJ29AJ24AJ19
AJ5
AH31AH8
AG39AG24AG19AG13
AG5
AF42AF40AF31
AF24AF19
AE39AE13
AE5
AD34AD31AD24AD22AD20AD19AD11
AD8
AC39AC36AC32AC29
AC5
AB37AB25AB17AB15
AA39AA36AA32AA27AA25AA24AA22AA20AA19AA17
AA5
A40A38
A26A24A22A20
A6
Y34Y31Y15Y11
Y8
W39
W25
W5
W3
V31V2
U39U25U13U10
U5
T31R36R20R16R13
P43P41P39P37P31P28P24P11
P8P5
N32N16
M39M37M34M31
M28M21M18M15M11
M5
M3
M1L36L29L26L23L20L16L10
K39K34K24K15K11
K5
J26J20J13
H39
H8H5
G26G20G13F41F39F34
F31F24F15
E40E38E36E34E32E30E28E26E24E22E20E18E16E14E12E10
E8E6
D29D13
D9D5
C38C26C24C22C20
C4
BG34BG10BF21BE34BE10
BD39BD21
BD5
BC38BC36BC34BC32BC30BC28BC26BC24BC22BC20BC18BC16
BC12BC10
BC8BC6
BB39BB5
B39B29B13
B9
AY39AY37AY34AY31
AY28
AY8AY5
AY3
SHEETDATE
DEPARTMENT
SIZE
PROJECT DOCUMENT NUMBER REV
REVIEWER
DESIGNER
123
7 3 2 1 6 5 4
E
A
B
C
E
D
C
B
A
7 6 5 4
D
C



P1V8_PCH_PLL_AUX DECOUPLING CAPSP1V8_PCH_AUX DECOUPLING CAPS
P3V3_AUX DECOUPLING CAPSP1V05_PCH_AUX DECOUPLING CAPSP1V05_PCH_AUX DECOUPLING CAPSP1V05_PCH_PLL_AUX DECOUPLING CAPS20220815 ADD R4803
Fri Aug 25 14:03:01 2023N/AN/AN/AN/AV05189 OF 312
P1V05_PCH_PLL_AUXP1V05_PCH_AUXP1V05_PCH_PLL_AUX
P3V3_AUXP1V8_PCH_PLL_AUXP1V05_PCH_PLL_AUXP1V05_PCH_AUX
P1V8_PCH_PLL_AUXP1V8_PCH_AUXP1V8_PCH_PLL_AUXP1V05_PCH_AUXP1V05_PCH_AUXP1V8_PCH_AUX P1V8_PCH_AUXP1V05_PCH_AUXP1V05_PCH_AUXP3V3_AUX
P1V05_PCH_AUXP1V05_PCH_AUXP3V3_AUXP1V8_PCH_PLL_AUXP1V05_PCH_PLL_AUX
EMMITSBURG - DECOUPLING CAPS
CHIPBLM15PX121SN1D/2A0402LF0402LF 1/16W05%1/16WCHIP05%6.3VEMPTY6.3V10%10%0402C0603 C0603X6S20%C040210UF20%X6S10UF6.3V20%X6SC0402
10UF6.3V20%X6S
C060320%6.3V10UFC060320%X6S6.3VC0402X6S20%
6.3V20%C040204021UFEMPTY6.3V10%10%1UF6.3V0402EMPTYX6S20%6.3V10UFC0603SMLFEMPTY10%1UF6.3V0402EMPTYEMPTY10%6.3V1UF040222UFC0603X6S20%4VX6S22UFC06034V20%C0603X6S20%22UFC060322UF4V20%X6S6.3V20%X6S10UF20%X6SC060322UF4VC0603X6S22UF20%4V4VC060320%X6S22UFC04026.3V10UF20%X6S10UF20%6.3VX6SC0402 C0402C040210%X6S2.2UF10V2.2UFC040210V10%X6SC040210%10V2.2UFX6S
20%X6S4V22UFC0603
2.2UF10V10%C0402X6SC040210%10V2.2UFX6S10%2.2UFC040210VX6S
4V20%X6S22UFC0603
10UFX6S
C0603X6S20%22UF4V
20%C06036.3V22UFX6SX6S22UF6.3V20%C0603X6SC060320%6.3V22UF05%CHIP1/16W10UF20%C080547UFX6S4V
C0402 C08054V47UFX6S10UFC0805C080547UF6.3VX6S10UF20%X6SX6S20%4V47UF20%X6S4V47UF20%4VC080547UFX6S20%4V20%X6S20%4VC080547UF6.3V10UF20%X6S20%4VC080547UFX6SX6S6.3V10UFX6S6.3V20%C0805X6S4V47UF
20%6.3VC0402X6S47UFC08056.3V20%C0805X6S20%47UF6.3V
4VC0402BLM18PG121SN1D/2000MA0402LFC0805EMPTY10UF6.3V20%X6SC060304021UF10UF6.3V1UFSMLFEMPTY
R4803
C1245C1243
C1272
C1259
C1258
C1249
C1248C1246C1244
C1273
R1464
R1463
C1266C1252 C1255 C1263
C1254C1251 C1262
C1184 C1191 C1201 C1206
C1242C1214C1204C1200C1189C1183
C1231C1203 C1210C1198C1182 C1187
C1197 C1202C1181 C1186
C1228C1205C1192C1185C1178
21
L2
L10
1 2
1 2
21
2
1
2
1
2
1
2
1
2
1
2
1
2
1
2
1C1247
2
1
2
1
2
1
2
1
2
1
21
2
1
2
1
2
1C1250
2
1C1256
2
1C1264
2
1C1260
21
2
1
2
1
2
1
2
1
2
1
2
1
2
1
2
1
2
1
2
1
2
1
2
1
2
1
2
1
2
1
2
1
2
1
2
1
2
1
2
1
2
1
2
1
2
1
2
1
2
1
2
1
2
1
2
1
2
1
2
1
2
1
2
1
2
1
21
SHEETDATE
DEPARTMENT
SIZE
PROJECT DOCUMENT NUMBER REV
REVIEWER
DESIGNER
123
7 3 2 1 6 5 4
E
A
B
C
E
D
C
B
A
7 6 5 4
D
C1253 C1257 C1261 C1265
C1207
C



20211130 CHANGE TO P3V3_M2_020210904 MODIFY FOR GT
20211201 PU TO P3V3_AUX20211201 PU TO P3V3_M2_020211201 PU TO P3V3_AUX20211201 PU TO P3V3_AUX20220818 CHANGE R2113 TO 33.2 OHMTO SCM HDD ACTIVITY LEDFri Aug 25 14:03:03 2023N/AN/AN/AV0501010101190 OF 312N/AP3V3_AUXP3V3_AUX
P3V3_AUXP3V3_M2_0P3V3_AUXP3V3_AUX
P3V3_AUX
P3V3_M2_0P3V3_M2_0P3V3_AUXP3V3_AUX
PCH - M.2 - 0 CONN
P3E_PCH_M2_TX_C_DN<2:0>NC_M2_0_NC3NC_M2_0_NC7NC_M2_0_NC10SMB_M2_P0_1V8AUX_SCLNC_M2_0_NC15NC_M2_0_NC181/16WEMPTY1%CLK_100M_PE_M2_0_DNPD_M2_0_DEVSLPP3E_PCH_M2_RX_DN<3>CHANGE CH4101KEE02 TO CH4101KEE010402LF0.1UF25VEMPTYSMLFSCONN75K_APCI0155-P004ACLK_100M_PE_M2_0_DPP3E_PCH_M2_RX_DP<3>
190190214 240190194194181190215190183215
155161182183190 190190181181181181184190181181181190179179
SMLFPJT138K0402LFRST_PCIE_PCH_DEV_0_NCHIP0402LFCHIP1%PU_BUFFER_HDD_ACTIVITYHDD_ACTIVITY_BUFIC1/16WLED_HDD_ACTIVITY_B_NCHIPLED_M2_SSD_0_ACT_N10KNC_M2_0_NC4NC_M2_0_NC5NC_M2_0_NC6NC_M2_0_NC8NC_M2_0_NC9NC_M2_0_NC11SMB_M2_P0_1V8AUX_SDAHDD_ACTIVITY_BUF_N0402LF1/16WNC_M2_0_NC14NC_M2_0_NC16NC_M2_0_NC17PU_BUFFER_HDD_ACTIVITYLED_HDD_ACTIVITY_NSN74LVC2G07DCKR4.7K1%1/16WCHIPPCIE_M2_SSD0_PRSNT_NM2_0_PEWAKE_N
5%ICSMLFM2_SSD0_CLKREQ_EN_N10%RST_PCIE_PCH_DEV_PERST_M2_R_N25V04021/16W10%1%CHIP4.7KIC4.7KSMLF1%5%0402LFCHIP0402LF0402LF5%IRQ_LVC3_WAKE_NM2_SSD0_CLKREQ_EN_NCHIP0 PD_M2_0_DEVSLP0402LFCHIP10K1%CHIP040225V0.1UF22UF20%X6SC060320%6.3V6.3V22UF20%X6S0.1UF10%25VX7RNC_M2_0_SUSCLKNC_M2_0_NC1
1UFX7R4.7K1/16WNC_M2_0_NC2P3E_PCH_M2_TX_C_DP<2:0>P3E_PCH_M2_RX_DN<2:0>P3E_PCH_M2_RX_DP<2:0>C06036.3V22UFC0603X6S1/16W25V0402X7R0.1UF1% X7R10% 10%04021K1%1/16WCHIP4.7KCHIP0FM_M2_SSD0_E7_PEDET0402LF0402LF
X6SC0402
5%CHIP5%0
NC_Q95_S2NC_Q95_D2ICPJT138KRST_PCIE_PCH_DEV_BUF_M2_0_PERST_N
1K1/16W1%CHIP0402LF2.LANE REVERSAL1.DP/DN SWAP TX[0:3]
1/16WNC_Q95_G2SMLF010K1/16W74LVC1G126SE-7NC_M2_0_NC19FM_M2_SSD_0_PEDETLED_M2_SSD_0_ACT_NP3E_PCH_M2_TX_C_DP<3>P3E_PCH_M2_TX_C_DN<3>RST_PCIE_PCH_DEV_0_NM2_SSD0_CLKREQ_EN_N_BUFCHIP1%33.2
CHIP33.21%
G2
G1
S2 D2D1S1
R2113
R3301
KEY M
R2121
R2526
R487
R1396
5
2
52
43
61
4
1
2
2
1
0
0
0
1
1
2
1
0
2
2
4 31 653
Q95
Q95
U259
U239
R5377
J59
VCCGND
2Y
1Y
2A
1A
OE
Y
A
REFCLKP
REFCLKN
PETP1
PETN1
PERP1
PERN1
PETP2
PETN2
PERP2
PERN2
PETP3
PETN3
PERP3
PERN3
GND10
GND9
GND8
GND7
GND6
GND5
GND4
GND3
GND2
GND1
NC4
NC5
NC6
NC7
NC8
NC9
NC11
NC12
NC13
NC14
NC15
NC16
NC17
NC10
NC3
NC2
NC1
G2
G1
GND14
GND13
GND12
PEDET
NC19
GND11
PETP0||SATA-A+
PETN0||SATA-A-
PERP0||SATA-B-
PERN0||SATA-B+
3.3V_9
3.3V_8
3.3V_7
SUSCLK
NC18PEWAKE#
CLKREQ#
PERST#
DEVSLP
3.3V_6
3.3V_5
3.3V_4
3.3V_3
DAS_DSS#||LED1#
3.3V_2
3.3V_1
GND VCC
21
2
1
2
1
2
1
21
2
1
2
1
2
1
2
1
21
21
2
1
R478
2
1
21
2
1
21R486
2
1
2
1
2
1
2
1
2
1
2
1
2
1
BOM NOTE:
DESIGN NOTE:
68
5553
54
13
25
37 49
11
23
35 47
50
7
19
31 43
5
17
29 41
69
675856484644424036343230282624222086
7573715751453933272115931
G2G1
38 10
52
7472701816141242
SHEETDATE
DEPARTMENT
SIZE
PROJECT DOCUMENT NUMBER REV
REVIEWER
DESIGNER
123
7 3 2 1 6 5 4
E
A
B
C
E
D
C
B
A
7 6 5 4
D
IN OUT
IN
IN
IN
OUT
OUT
OUT
OUT
OUT
OUTOUT
IN
OUT
OUT
OUTOUT
ININ
ININ
IN
IN
IN
BI
OUT
IN
C2007
R3296
R3294
R3295 C1873
R3298
R3297
R491
R1605
C1925C1924C1923C1922C1921C1920
C



20220804 DEPOP R3773
20210904 MODIFY FOR GT20220804 POP R167320220804 CHANGE TO P3V3_E1S_020220805 CHANGE TO P3V3_E1S_0
PUSH PULL OUTPUT20220805 ADD C2378,R4767,U336
Fri Aug 25 14:03:04 2023N/AN/AN/AN/AV05191 OF 312P3V3_AUX
P12V_E1S_0
P3V3_AUX
P3V3_E1S_0P3V3_E1S_0P12V_E1S_0
P3V3_AUXP3V3_AUXP3V3_AUXP3V3_AUXP3V3_E1S_0
P3V3_E1S_0P3V3_E1S_0P3V3_E1S_0
PCH - E1S - 0 CONN216181181183191224192 193191183215191
179181181191
194
179215183191215191194
215154161227231233236245
194214
HP_E1S_0_P3V3_PWRGD HP_E1S_0_P3V3_PWRGD_PLDP3E_PCH_E1S_RX_DN<3:0>P3E_PCH_E1S_RX_DP<3:0>0402LFE1S_0_PERST1_CLKREQ_N10KCHIP1%1/16W1/16WDP/DN SWAP TX[0:1] RX[0]RST_PCIE_PCH_E1S_PERST_NTP_CLK_100M_E1S_0_DNTP_CLK_100M_E1S_0_DPAPX809-29SAG-70.1UF25V040210%X7RCHIP49.9ICSMLFE1S_0_PWRDIS1%1/16WCHIP1K0402LF1%1/16WCHIP0402LF10KFM_PS_EN_PLD_BUF1 FM_PS_EN_PLD_BUF1_R1E1S_0_ENE1S_0_PRSNT_NE1S_0_PRSNTCHIP5%010KCHIP1/16W1%0402LF0402LFCHIP1/16W1%10KX7R10%0.1UF25V04021%CHIP1/16W100K74LVC1G126SE-7SMLFIC2N7002KSMLF0402LFICEMPTY1/16W0402LFCHIPRST_SMB_E1S_0_N5%1/16W4.7K
1/16W1%10K5%CLK_100M_E1S_0_DNP3E_PCH_E1S_TX_C_DN<3:0>P3E_PCH_E1S_TX_C_DP<3:0>E1S_0_PWRDISPU_E1S_0_DUALPORT_EN_NTP_E1S_0_RFU22UF20%C0805
0402LFRST_SMB_E1S_N
040210%0402X7R25V0.1UF10%X7R04020.1UF25V25V10%X7R
IC4.7K5%0402X7R0.1UF25V10%CHIP5%01/16WCHIP5%00402LFCHIPSMB_PCIE_E1S_ISO_EN_R2 SMB_PCIE_E1S_ISO_ENRST_SMB_BUF_E1S_0_NSMLF20%X6S10%16VSMLFIOSCONN56_1-2327679-31/16WCHIP1% 1%1/16WEMPTY0402LF25V10K0CLK_100M_E1S_0_DP0.1UF16VX7R04021000402LFRST_PCIE_PCH_DEV_PERST_E1S_R_NE1S_0_PRSNT_N22UFRST_SMB_E1S_0_N0402LFCHIPPLACE THE BULK CAPS CLOSE TO SLOTTP_E1S_0_MFG SMB_E1S_3V3AUX_ISO_SCLC0805X6S
RST_SMB_SWITCH_N
0.1UF
05%74LVC2G07DW-7
CHIP0402LFSMB_E1S_3V3AUX_ISO_SDAE1S_0_LED_ACT_N
G
S D
R4767
R2287R1673
R2426
R3779
R2114
R3772
R3773 R2125
R2457
3
2
1
A9
A8
A7
B8
A15B15
A14B14
B12 A12
B27
B24
B21
B18
B26
B23
B20
B17
A11
B10
A27
A24
A21
A18
A26
A23
A20
A17
B6
B5
B4
B3
B2
B1
B11
B7
A10
B28
B25
B22
B19
B16
B13
A28
A25
A22
A19
A16
A13
A6
A5
A4
A3
A2
A1
G2 G1
B9
G
52
43
61
4
1
2
2
3
2
0
1
1
3
0
3
2
1
1
0
0
3
2
S D53
U336
J90
Q46
U134
R3771
R2317
U145
GND
RESET_L
VCC
G1G2
PER_p3
PER_n3
PER_p2
PER_n2
PER_p1
PER_n1
PER_p0
PER_n0
REFCLK_p1
REFCLK_n1
GND_A28
GND_A25
GND_A22
GND_A19
GND_A16
GND_A13
PRSNT0#
PERST1#_CLKREQ#
PERST0# LED#_ACTIVITY
SMBRST#
SMBDAT
SMBCLK
PET_p3
PET_n3
PET_p2
PET_n2
PET_p1
PET_n1
PET_p0
PET_n0
REFCLK_p0
REFCLK_n0
GND_B28
GND_B25
GND_B22
GND_B19
GND_B16
GND_B13
PWRDIS
P3V3_AUX
DUALPORTEN#
RFU
MFG
GND_A6
GND_A5
GND_A4
GND_A3
GND_A2
GND_A1
P12V_B6
P12V_B5
P12V_B4
P12V_B3
P12V_B2
P12V_B1
S
G
D
VCCGND
2Y
1Y
2A
1A
OE
Y
A
GND VCC
21
2
1
2
1
2
1
2
1
21
21
2
1
21
21
2
1
2
1
2
1
2
1
2
1
2
1C1276
2
1C1278
2
1C1279
2
1C1282
2
1C1283
2
1C1277
2
1
2
1
2
1
2
1
21R2350
DESIGN NOTE:
CAD NOTE:
SHEETDATE
DEPARTMENT
SIZE
PROJECT DOCUMENT NUMBER REV
REVIEWER
DESIGNER
123
7 3 2 1 6 5 4
E
A
B
C
E
D
C
B
A
7 6 5 4
D
OUT
IN
IN OUT
OUT
OUT
ININ
ININ
IN
OUTOUT
IN
OUT
IN
OUT
BIIN
OUT
IN
IN
C2378
R3775
C1592
R2296
C1614
R2282
R2304
C



OVP: 3.89VUVP: 2.63V
DESIGN SPECIFICATIONOCP=MAX*1.3=2.71AIMAX=2.083AP3V3_E1S_0_RIMAX=0.025AOCP=0.75AP12V_E1S_0UVP: 10.17VOVP: 14.91VVIMON(MAX)= 1.641V @ IOUT=2.79AVIMON(MAX)= 1.604V @ IOUT=0.75ASTART UP TIME:3.94MSSTART UP TIME:8.21MS
Fri Aug 25 14:03:06 2023192 OF 312V05N/AN/AN/AN/AP12V_AUXP3V3_AUXP12V_AUXP12V_AUX
P3V3_AUXP3V3_E1S_0_RP3V3_E1S_0_RP3V3_AUXP12V_E1S_0
E1S_HSC
191193 193216250250P3V3_E1S_EN_1_RP3V3_E1S_0_EN_GP3V3_E1S_UV_0_RE1S_0_ENP12V_E1S_EN_0_RP12V_E1S_0_EN_GP12V_E1S_UV_0_RP3V3_E1S_UV_0P3V3_E1S_CB_0P3V3_E1S_VCC_0P3V3_E1S_OV_0P3V3_E1S_REG_0P3V3_E1S_FAULT_0P3V3_E1S_GATE_0P3V3_E1S_PWRGD_0P3V3_E1S_SENSE_0TP_P3V3_E1S_PWRGD_0P12V_E1S_VCC_0P12V_E1S_REG_0P12V_E1S_CB_0P12V_E1S_GATE_0P12V_E1S_FAULT_0P12V_E1S_PWRGD_0P12V_E1S_SENSE_0HP_LVC3_E1S_0_HSC_PWRGDP12V_E1S_0_ISENSE_MAM_MAMP12V_E1S_0_ISENSE_MAM_TICP12V_E1S_UV_0P12V_E1S_OV_0
E1S1_P3V3_BOM11/16WCHIP0402LF05%PJT138KSMLFE1S1_P3V3_BOM1ICPJT138KSMLFE1S1_P3V3_BOM1ICE1S1_P3V3_BOM1CHIP1/16W0402LF1%10K4.7K5%CHIP1/16W0402LFE1S1_P12V_MAM_MAM_BOM1SMLFPJT138KEMPTYE1S1_P3V3_BOM1CHIP1/16W0402LF15K1%E1S1_P3V3_BOM17.15K1/16W0402LFCHIP1%CHIP05%E1S1_P3V3_BOM10402LF1/16WE1S1_P3V3_BOM1C0402X6S1UF25VE1S1_P3V3_BOM10402LF25.5K1%1/16WCHIP05%1/16W0402LFCHIPEMPTY0402LF1/16W10K1%E1S1_P12V_MAM_MAM_BOM1E1S1_P12V_MAM_MAM_BOM1SMLFPJT138KEMPTYE1S1_P12V_MAM_MAM_BOM10402LF5%0EMPTY 1/16WEMPTYE1S1_P12V_MAM_MAM_BOM10402LF15K1%1/16WX6S1UF25VC0402E1S1_P12V_MAM_MAM_BOM11/16WEMPTY0402LF1%160K
E1S1_P3V3_BOM12.49K1/16WCHIP1%0402LFICSMLFMAX15090BEWI+TE1S1_P3V3_BOM1E1S1_P3V3_BOM11UFC040225VX6SE1S1_P3V3_BOM11UF25VC0402E1S1_P3V3_BOM1100402LFCHIP1/16W1%E1S1_P3V3_BOM11/16W1%9.76KCHIP0402LFC0402EMPTY50V0.01UF1/16W0402LFCHIPE1S1_P3V3_BOM11%10ME1S1_P3V3_BOM1CHIP1/16W0402LF5%050VE1S1_P3V3_BOM1C04026800PFICB340A-13-F0402LFCHIPE1S1_P3V3_BOM11/16W100K1%E1S1_P3V3_BOM10402LFCHIP1/16W1%100KX7R040225V0.1UFX6SC080510UF16VE1S1_P12V_MAM_MAM_BOM11UFEMPTYC040225VE1S1_P12V_MAM_MAM_BOM11/16WEMPTY9.31K1%0402LFE1S1_P12V_MAM_MAM_BOM1EMPTYC040225V1UF0402LFE1S1_P12V_MAM_MAM_BOM1EMPTY1/16W101%EMPTYE1S1_P12V_MAM_MAM_BOM1MAX15090BEWI+TSMLFE1S1_P12V_MAM_MAM_BOM10402LFEMPTY1/16W2.67K1%R3974/R3975 CO-LAYOUT0402LF5%E1S1_P12V_MAM_TIC_BOM20EMPTY1/16WC0402E1S1_P12V_MAM_MAM_BOM150VEMPTY3900PFE1S1_P12V_MAM_MAM_BOM10402LF5%0EMPTY1/16W1/16WE1S1_P12V_MAM_MAM_BOM10402LF5%0EMPTYEMPTY50V0.01UFC04021%E1S1_P12V_MAM_MAM_BOM11/16W0402LFEMPTY10MB340A-13-FICE1S1_P12V_MAM_MAM_BOM1100K1/16WEMPTY1%0402LF0.1UFX7R25V0402E1S1_P12V_MAM_MAM_BOM11/16WEMPTY1%100K0402LFC080510UFX6S16VC0805X6S10UF16VSMF14AICE1S1_P12V_MAM_MAM_BOM10402LF1/16W6.8K1%EMPTY
G2
G1
G2
G1
CAS2 D2D1S1S2 D2D1S1
2
1 PR3961
PD114
2
1
R3976
2
1 PR3970
2
1 PR3968
PC2211
PC2213
2
1 PR3960
21
R3958
5 Q127
2 Q127
PC2219
2
1
R3978
2
1 PC2217
2
1 PC2214
PC2207
2
1 PR3962
2
1
R4074 21R3972
PC2215
21
R3975
2
1
PC2209
2
1
R4073
PD112
2
1
PR4528
21
R3974
A2
D2
D1 D7
D3
D6
D4
C6
C4
B6
B4
A4
A1
D5
C5
C3
B5
B3
A5
A3
C2
C1
B2
A6
C7
B7
A7B1
PU294
2
1 PR3966
R4064
CA214 31 6
21CA
PC2218
PC2212
PR3963
R3959
R3979
R3973
PR3971
PC2210
PC2208
PR3964
PR3965
R4072
R4063
R3977
PC2216
PR3967
PR3969
PC2280
PC2220
A2
D2
D1 D7
D3
D6
D4
C6
C4
B6
B4
A4
A1
D5
C5
C3
B5
B3
A5
A3
C2
C1
B2
A6
C7
B7
A7B1
2
5
1 64 3
PU295
Q126
Q126
PD113
PG
FAULT#
GND_C2
GND_C1
GND_B2
CDLY
GATE
OUT_D6
OUT_D4
OUT_C6
OUT_C4
OUT_B6
OUT_B4
OUT_A4
ISENSEOV
UV
REG
EN#
CB
IN_D5
IN_C5
IN_C3
IN_B5
IN_B3
IN_A5
IN_A3
VCC
PG
FAULT#
GND_C2
GND_C1
GND_B2
CDLY
GATE
OUT_D6
OUT_D4
OUT_C6
OUT_C4
OUT_B6
OUT_B4
OUT_A4
ISENSEOV
UV
REG
EN#
CB
IN_D5
IN_C5
IN_C3
IN_B5
IN_B3
IN_A5
IN_A3
VCC
CACA
2
1
2
12
1
21
2
1
21
2
1
2
1
2
1
2
1
2
1
2
1
2
1
2
1
2
1
CAD NOTE:
2121CA
SHEETDATE
DEPARTMENT
SIZE
PROJECT DOCUMENT NUMBER REV
REVIEWER
DESIGNER
123
7 3 2 1 6 5 4
E
A
B
C
E
D
C
B
A
7 6 5 4
D
OUT
OUT
OUT
IN
PR4527
C



START UP TIME:8.62MSVIMON(MAX)= 1.569V @ IOUT=2.8APOPPOPMP5025A/MP5022ADE-POPDE-POPDE-POPDE-POPMP5022CMP5025C/POPPOPDE-POPPOPVTH>1.391V(HIGH)TFAULT: 1.27MSTDELAY: 6.29MSPR3950PC2205PR3952PR3953PR3957PU292 OPTIONAL BOMENABLE:IMAX=0.025A
START UP TIME:4.7MS
DESIGN SPECIFICATIONOCP=MAX*1.3=2.71AIMAX=2.083AP3V3_E1S_0_ROCP=0.75AP12V_E1S_0
CURRENT LIMIT=0.75A193 OF 312V05Fri Aug 25 14:03:07 2023N/AN/AN/AN/A
P12V_AUXP3V3_AUXP3V3_AUXP12V_AUXP12V_E1S_0P3V3_E1S_0_RP3V3_AUXE1S_HSC_CO_LAYOUT
191192193193192216250250193191192193E1S1_P12V_MPS_MAM_BOM3EMPTY5%0402LFCHIP1/16W 0402LFE1S1_P12V_MPS_TIC_BOM401/16W5%0E1S1_P12V_MPS_MAM_BOM3R3955/R3956 CO-LAYOUTE1S_0_ENP12V_E1S_TIMER_0P12V_E1S_ISET_0_RP12V_E1S_ISET_0P12V_E1S_EN_0_R2P12V_E1S_SS_0P12V_E1S_IMON_0P12V_E1S_AVIN_PD_0P12V_E1S_FLTB_0P12V_E1S_OV_FB_0HP_LVC3_E1S_0_HSC_PWRGDP12V_E1S_0_ISENSE_MPS_TICP12V_E1S_0_ISENSE_MPS_MAMP12V_E1S_AVIN_PD_016VX7R04020.22UFE1S1_P12V_MPS_MAM_BOM3E1S1_P12V_MPS_MAM_BOM3CHIP1/16W1%0402LF46.4KE1S1_P12V_MPS_MAM_BOM3560PF50VX7RC0402E1S1_P12V_MPS_MAM_BOM30402LF20K1%CHIP1/16WE1S1_P12V_MPS_MAM_BOM30402LF05%1/16WCHIP0.047UFE1S1_P12V_MPS_MAM_BOM325VC0402X7RICRS31312RE1S1_P12V_MPS_MAM_BOM325VC0402X6S1UFE1S1_P12V_MPS_MAM_BOM3E1S1_P12V_MPS_MAM_BOM356K1%1/16WCHIP0402LFCHIPE1S1_P12V_MPS_MAM_BOM30402LF1/16W1%10K0402LFEMPTY1001/16W1%50V100NFX7RC0402CHIP1/16W0402LFE1S1_P12V_MPS_MAM_BOM310K1%71.5K0402LFEMPTY1%E1S1_P12V_MPS_MAM_BOM3CHIP1/16W120K0402LF1%10KCHIP1%E1S1_P12V_MPS_MAM_BOM31/16W0402LFE1S1_P12V_MPS_MAM_BOM316VC0603X7R2.2UF20%E1S1_P12V_MPS_MAM_BOM31%1/10WCHIP0603LF49.9E1S1_P12V_MPS_MAM_BOM30.1UF10%0402X7R25VE1S1_P3V3_BOM210UF16VC0805EMPTYE1S1_P3V3_BOM2100PF0402EMPTY50V5%P3V3_E1S_GATE_0_PU293E1S1_P3V3_BOM2SMLFMP5016GQH-L-ZEMPTYE1S1_P3V3_BOM20402EMPTY16V0.068UFP3V3_E1S_EN_0_R2P3V3_E1S_DVDT_0E1S1_P3V3_BOM2P3V3_E1S_ILIMIT_0P3V3_E1S_MODE_0E1S1_P3V3_BOM21UFC0402EMPTY25V5%0402LFEMPTY0402LF2.8K1%1/16WE1S1_P3V3_BOM2E1S1_P3V3_BOM20EMPTY0402LFEMPTY71.5K1%C040239PFEMPTYE1S1_P3V3_BOM250VE1S_0_EN
2
1 PC2206
2
1 PR3957
PC2205
21
R3955
21
R3956
2
1 R3948
PR3953
2
1 PR3952
PR3954
2
1 PR3950
2
1 PR3949
2
1 PR4541
PR3947
PC2202
PR3951
PC2198
PC2281
2
1 PC2341
2
1 PR3944
PC2196
1_2 6_7
5
4
3
8
9
10
PU293
PC2203
PC2201
21R3946
PR3945
21
R3943
PC2204
PC2200
PC2197
20
19
18
17
16
15
14
13
26
25
24
23
21_22
4
6
10
11
2
5
87
9
3
1
12
PU292
GND
SS
ISET
TIMER
ENTM
LOADEN
EN
VIN_26
VIN_25
VIN_24
VIN_23
IMON
FLTB
PG
OV
VOUT_13
AVIN
VOUT_14
VOUT_15
VOUT_16
VOUT_17
VOUT_18
VOUT_19
VIN_21_22
VOUT_20
SOURCE
GATE
DV_DT
VCC
GND
ILIMIT
MODE
EN
CAD NOTE:
SHEETDATE
DEPARTMENT
SIZE
PROJECT DOCUMENT NUMBER REV
REVIEWER
DESIGNER
123
7 3 2 1 6 5 4
E
A
B
C
E
D
C
B
A
7 6 5 4
D
OUT
OUT
OUT
OUT
IN
IN
IN
C



20211130 CHANGE R3529 TO 10K OHM
20210616 MODIFY FOR GT
20210607 MODIFY FOR GT
Fri Aug 25 14:03:08 2023N/AN/AN/AN/AV05194 OF 312P3V3_AUXP3V3_E1S_0P3V3_AUXP1V8_PCH_AUXP3V3_E1S_0P3V3_AUXP1V8_PCH_AUX
PCH - SATA / RAID KEY231231231231191191191183
263 222 252190190
EMPTY1%2.21K0402LF1/16W1/16WSMB_E1S_3V3AUX_ISO_SDA_RSMB_SENSOR_E1S_3V3AUX_SDASMB_PCIE_E1S_ISO_EN_RX7R10K0402LFSMB_SENSOR_E1S_3V3AUX_SCLPCA9617ADPSMB_E1S_3V3AUX_ISO_SCL_R0.1UFCHIP10%0.1UF1%25V0402SMB_PCIE_M2_0_ENSMB_M2_P0_1V8AUX_SCL_R1/16WCHIP0402LF0402LFSMB_M2_P0_1V8AUX_SDA_R0402200K1/16WCHIPX7RIC10%25VX7RSMLFPCA9306DP1SMB_SENSOR_M2_P0_3V3AUX_SCLSMB_SENSOR_M2_P0_3V3AUX_SDASMB_PCIE_E1S_ISO_ENSMB_E1S_3V3AUX_ISO_SDASMB_E1S_3V3AUX_ISO_SCL0402LF 1/16W200K1%EMPTY10%X7R25V04021/16W5%0402LFCHIP4.7KCHIP1/16W0402LF5%4.7KCHIP33.21%1%CHIP33.20402LF 1/16WSMLFICFM_PCH_SATA_RAID_KEY
PWRGD_P1V8_PCH_AUX1%1%SMB_M2_P0_1V8AUX_SCLSMB_M2_P0_1V8AUX_SDA25V04020.1UF10%0402LF1%0.1UF1/16W200K1%EMPTY5%4.7K1/16W4.7K5%CHIP0402LFCHIP33.20402LF 1/16W33.2 CHIP
R3529 R3530 R3532
R3534
R3533
R1700
R2411
R2410
R1703R1702
8 1
6 3
7 2
45
7 2
5 4
6 3
1 8
U98
U279
GND
SCLB
SDAB SDAA
SCLA
VCCB VCCA
EN
GND EN
VREF2
SCL2
SDA2 SDA1
SCL1
VREF1
2
1
21R3531
2
1
2
1
2
1
2
1
21
21
2
1
21R2476
21 21
2
1
2
1
2
1
2
1
2
1
SHEETDATE
DEPARTMENT
SIZE
PROJECT DOCUMENT NUMBER REV
REVIEWER
DESIGNER
123
7 3 2 1 6 5 4
E
A
B
C
E
D
C
B
A
7 6 5 4
D
IN
IN
BI OUT
BI
IN
BI
OUTBIINBI
C1997 C1998
C1305 C1323
R1271
C



ID1ID00120220113 ADD ID PIN CONNECT TO FPGA
0ID41INTEL PLATFORMBRD_SKUAMD PLATFORM01010001100011ID2ID30 0000100000110111100100000111BRD_SKUHSC-MODULE + ADC-TIC + VR-SNIHSC-MODULE + ADC-MAM + VR-MPSHSC-MODULE + ADC-MAM + VR-TICHSC-REEDSEMI + ADC-MAM + VR-MPSHSC-REEDSEMI + ADC-MAM + VR-TICHSC-REEDSEMI + ADC-TIC + VR-SNIHSC-REEDSEMI + ADC-TIC + VR-RTT20211208 MODIFY FOR GTHSC-MODULE + ADC-TIC + VR-RTT101HSC-MPS5990 + ADC-TIC + VR-RTTHSC-MPS5990 + ADC-TIC + VR-SNIHSC-MPS5990 + ADC-MAM + VR-MPSHSC-MPS5990 + ADC-MAM + VR-TIC
MP 1 1 1PILOT 1 1 0PVT 1 0 1DVT2 1 0 0DVT 0 1 1EVT2 0 1 0EVT 0 0 1POC 0 0 0FAB_REV ID2 ID1 ID020220113 ADD ID PIN CONNECT TO FPGAFri Aug 25 14:03:09 2023N/AV05N/AN/AN/A195 OF 312
P3V3_AUXP1V05_PCH_AUXP3V3_AUXP1V05_PCH_AUX
BOARD IDS
0402LFEMPTYCHIP1/16W1%1K1/16W10K1%0402LFFAB_REV_ID1FAB_REV_ID0FAB_BMC_REV_ID2FAB_BMC_REV_ID1FAB_BMC_REV_ID01%1/16W1%10K0402LF1/16W10K1%CHIP1K1/16W0402LFEMPTY1K1/16W0402LFCHIPFAB_REV_ID21%EMPTY0402LF1K1/16W0402LF1%EMPTYCHIP1%0402LF1/16W10K0402LF1%1/16WEMPTY1K1/16W1%1KEMPTY0402LF10K1%1/16WCHIP0402LFCHIP1/16W1%10K0402LF216216216184184184CHIPFM_BOARD_BMC_SKU_ID0FM_BOARD_BMC_SKU_ID4FM_BOARD_BMC_SKU_ID3FM_BOARD_SKU_ID3FM_BOARD_SKU_ID4FM_BOARD_BMC_SKU_ID1FM_BOARD_BMC_SKU_ID2FM_BOARD_SKU_ID2FM_BOARD_SKU_ID1FM_BOARD_SKU_ID0CHIP0402LF1K1%1/16W 1/16W1%1KCHIP0402LF10K1%0402LF1/16WEMPTY1%10K1/16WEMPTY0402LF1K1%1/16WCHIP0402LFCHIP1K1/16W1%0402LF10K1/16WEMPTY1%0402LF 0402LF10KEMPTY1/16W1%
1K1/16WCHIP0402LF1%1/16W0402LF1%1K0402LF1/16WCHIP1%1K216EMPTY0402LF1%10K1/16WEMPTY10K0402LF1/16W1%0402LF10KEMPTY1/16W1%0402LF1%1KCHIP1/16W1%1K0402LFCHIP1/16W0402LF1%1KCHIP1/16W2162162162161%1/16WEMPTY0402LF10K 10K1%1/16WEMPTY0402LF1/16W1%0402LFEMPTY10K184184184184184
2
1
2
1
2
1
2
1
2
1
2
1
2
1
2
1
2
1
2
1
2
1
2
1
2
1
2
1
2
1
2
1
2
1
2
1
2
1
2
1
2
1
2
1
2
1
2
1
2
1
2
1
2
1
2
1
2
1
2
1
2
1
2
1
DESIGN NOTE:
DESIGN NOTE:
SHEETDATE
DEPARTMENT
SIZE
PROJECT DOCUMENT NUMBER REV
REVIEWER
DESIGNER
123
7 3 2 1 6 5 4
E
A
B
C
E
D
C
B
A
7 6 5 4
D
OUT
OUT
OUT
OUT
OUT
OUT
OUT
OUT
OUT
OUT
OUT
OUT
OUT
OUT
OUT
OUT
R2232
R2978
R2974R2972
R2975R2973
R4579R4589
R4596
R2240R2979
R2241R2980
R4584R4582
R4598
R2976R2234
R2977R2235
R4591R4580
R4592
R4586
R4590R4588
R2242
R2243
R4597
R4585R4583R4581
C



20211208 MODIFY FOR GTUSB_HUB_I2C ONLY FOR EEPROM.
Fri Aug 25 14:03:10 2023N/AN/AN/AN/AV05196 OF 312
P3V3_AUXP3V3_AUXP3V3_AUXP3V3_AUX
P3V3_AUXPCH - USB EXT HUB
196227152 180196196196196180196196196196196196
196196196240240TUSB211IRWBR0402LFEMPTY1/16W1/16W10KEMPTYEMPTYUSB_HUB_2_OVCUR10402EMPTY10%25V0.1UF04020.1UF25V10%EMPTY040225V10%EMPTY0.1UF
C04021/16W0.1%47KEMPTY1/16W0402LFEMPTYEMPTYRST_USB_HUB_2_R_N33.2RST_USB_HUB_NEMPTYUSB_HUB_2_RREFNC_USB_HUB_2_DP30402LFC0402USB2_0_DN0NC_USB_HUB_2_DM4NC_USB_HUB_2_DP4NC_USB_HUB_2_DM3USB_HUB_2_DVDDUSB_HUB_2_OVCUR1USB_HUB_2_XTAL_OUTUSB_HUB_2_XTAL_INUSB2_PCH_0_R_DPUSB2_PCH_0_R_DNUSB_HUB_2_OVCUR4USB_HUB_2_PSELF6801%1/16WEMPTYEMPTY 0402LFEMPTY0402EMPTY10%EMPTYC040210%EMPTYEMPTY04020402C040210%EMPTY20%EMPTYEMPTY 0402LF1/16W1/16W1%10%25V1UF10K1%0402LF EMPTY0402LFNC_USB_HUB_2_DM2NC_USB_HUB_2_DP2USB2_HUB_2_EXT_DNEMPTYUSB2_0_DP00EMPTYUSB_HUB_2_OVCUR31/16WEMPTY100KUSB_HUB_2_OVCUR2SMLF1%10KUSB_HUB_2_PSELF0402LF0.1UF25V040225V1UFP3V3_AUX_USB_HUB_20.1UF25V040210%10%10%0.1UF25V10UF6.3V1UFEMPTY0.1UFUSB_HUB_2_OVCUR41%R4454/R4460,R4455/R4461 CO-LAYOUTUSB2_HUB_2_BUF_EXT_R_DP
USB_HUB_2_TESTNC_USB_HUB_2_SDA25V
USB2_HOST_PCH_0_DPSHORT THE NET USB2_HUB_2_EXT_R_DP/DN TO USB2_HUB_2_BUF_EXT_R_DP/DN10KEMPTYUSB_HUB_2_OVCUR30402LF0EMPTY0402LFCHIP05%00402LFCHIP0EMPTY10K10K0402LF1%0402LF
3.9K1/16W5%EMPTY0402LF
025V00.1UF25V10%EMPTYC0402
10%25V1UFC0402EMPTY0CHIP0402LFSMLFEMPTYCHIP00402LF
5%CHIP1/16W0402LFCHIP0EMPTY0402LF00402LFGL852G-OHY60EMPTY1/16W10K1%EMPTY0402LF50V12PF5%SMLF12MHZEMPTY50V12PF5%EMPTYC0402
EMPTY49.949.9EMPTYUSB2_HUB_2_EXT_DP
USB2_HUB_2_EXT_DNUSB2_HUB_2_EXT_DPPD_USB_HUB_2_RSTNTP_USB_HUB_2_TESTTP_USB_HUB_2_ENA_HSTP_USB_HUB_2_CDUSB2_HUB_2_BUF_EXT_R_DNUSB2_HUB_2_BUF_EXT_R_DPUSB_HUB_2_OVCUR2USB_HUB_2_PGANG
PD_USB_HUB_2_EQUSB2_HUB_2_BUF_EXT_R_DN USB2_HUB_2_BUF_EXT_DNUSB2_HUB_2_BUF_EXT_DPUSB2_HOST_PCH_0_DNPD_USB_HUB_2_VREG
R4471/R4473,R4472/R4474 CO-LAYOUT
196196196196
R4473 R4474
C2319C2318C2316C2313
R4464R4463
R4461
R4487R4486
C2327C2326
R4466
C2322C2320
R4462
C2315
C2314
R4450
R4452
R4453
R4456
R4457
R4458
R4459
R4460
31
42
11
10
28
27
TH
18
26
8
17
22
23
19
20
24
25
21
16
13
7
4
2
15
12
6
3
1
14
9
5
Y9
21R4472
21R4471
21R4467 21R4468
2
1C2324
2
1C2323
2
1C2325
U313
U312
R4454
R4455
R4451
R4465
2
1C2321
X2
G2G1
X1
DM4
DP4
DM3
DP3
DM2
DP2
DM1
DP1
DM0
DP0
RREF
PSELF
PGANG
RESET#
OVCUR4#
OVCUR3#
OVCUR2#||SMD
OVCUR1#||SMC
TH
DVDD
AVDD
AVDD
AVDD
V33
V5 SDA
TEST||SCL
X2
X1
GND
EQ
D2PD1P
D1M
CD
ENA_HS
VCCTEST
VREG
D2M
RSTN
2
1
2
1
2
1
2
1
21
2
1
2
1
2
1
2
1
2
1
21
2
1
2
1
2
1
2
1
2
1
21
2
1
2
1
2
1
21
21
21
21
2
1
2
1
21 21
2
1
2
1
2
1
CAD NOTE:
CAD NOTE:
CAD NOTE:
21
11123
5 106 9
7821
4
SHEETDATE
DEPARTMENT
SIZE
PROJECT DOCUMENT NUMBER REV
REVIEWER
DESIGNER
123
7 3 2 1 6 5 4
E
A
B
C
E
D
C
B
A
7 6 5 4
D
OUT
BIBI
BIBI
BIBI
BIBI
IN
OUT
OUT
OUT
ININ
ININ
OUT
IN
C2317
R4448
R4449
C



20211116 MODIFY FOR GT20211203 CHANGE R147,R148 TO 10K OHMFri Aug 25 14:03:11 2023N/AN/AN/AN/AV05197 OF 312
I35PVNN_TERM_CPU0PVNN_TERM_CPU0P3V3_AUXP3V3_AUX
PCH - PECI
2401821344 2282130402LF10K1%0402LFPECI_BMC0402LF5%1/16W00402LF1/16WPECI_PCHCHIP1%0402LF1/16WCHIP0402LFPECI_CPU_GTL1/16W49.9 CHIPPECI_BMC_RR148 IS FOR N-1 SUPPORT0402LFCHIP5%00402LF1/16W 1/16W0CHIP5%10KPECI_PCH_RPD ON SCM B/D0402LFEMPTY1/16W4.75K1%1/16WPECI_BMC_B1PECI_PCH_B11/16WEMPTY1%ICEMPTY100KPECI_BMC_ME1/16W5%EMPTY0EMPTY0402LF05%CHIPFM_PECI_MUX_SEL_N IS H : BMC TO CPUFM_PECI_MUX_SEL_N IS L : PCH TO CPU0402LF4.75K1%0402LF1%4.75K1/16WCHIP1/16W1%FM_PECI_MUX_SEL_NPECI_MUX_SEL_R25V1UFX6SC040210%NC7SB3157P6X
R2252
R2253
R143
5
6
2
1
3 4
S
B0
B1
VCCGND
A
U142
21
2
1
R147
2
1
R148
21
21
R2255
C1612
21
2
1
2
1
21
DESIGN NOTE:
DESIGN NOTE:
R1297
R149
SHEETDATE
DEPARTMENT
SIZE
PROJECT DOCUMENT NUMBER REV
REVIEWER
DESIGNER
123
7 3 2 1 6 5 4
E
A
B
C
E
D
C
B
A
7 6 5 4
D
BI
IN
BI
BI
BI
R144
R3064
R146
R145
C



20220727 POP R502,DEPOP R196220210929 MODIFY FOR GTFUNCTION:TLS CONFIDENTIALITYPCH INTERNAL: PULL DOWNGROUP: GPP_D_16PCH INTERNAL: 20KOHM PULL DOWNDEFAULT: 0 (DISABLE)FUNCTION:NO REBOOTPCH INTERNAL: PULL DOWNFUNCTION:BOOT BIOS STRAPPD BOOT HALT ENABLEGROUP: GPPC_S_4DEFAULT: 0 (SET TO P3V3)PU SPI BUFFER VOLTAGE IS 1.8VPD SPI BUFFER VOLTAGE IS 3.3V (DEFAULT)FUNCTION:SPI BUFFER VOLTAGEPU A0 DEBUG IS DISABLEDFUNCTION:FLASH SECURITY STRAPGROUP: GPP_D_6FUNCTION:PERSONALITY STRAPDEFAULT: 1 (DISABLE)GROUP: GPPC_S_3 GROUP: GPP_D_23DEFAULT: 0 (DISABLE)
DEFAULT: 1 (ENABLE)GROUP: GPPC_S_1DEFAULT: 0 (A0 DEBUG IS ENABLED)PCH INTERNAL: PULL UPPU BOOT HALT DISABLE(DEFAULT)GROUP: GPPC_S_5FUNCTION:CONSENT STRAPDEFAULT: 1 (DISABLE)GROUP: GPPC_C_18PD A0 DEBUG IS ENABLED (DEFAULT)DEFAULT: 0 (ENABLE)PCH INTERNAL: PULL DOWN
PCH INTERNAL: PULL DOWNFUNCTION:BOOT HALT STRAPPCH INTERNAL: NO INTERNAL TERMICATIONPCH INTERNAL: PULL DOWN
Fri Aug 25 14:03:12 2023N/AN/AN/AN/A198 OF 312V05
P3V3_AUXP3V3_AUX
P3V3_AUX
P3V3_AUXP3V3_AUXP3V3_AUX
P3V3_AUXP3V3_AUX
PCH SIDEBAND: HW STRAPS (1/4)
131 185
185215183 201 183183223131205185 183185214 240FM_PCH_CONSENT_STRAP_N0402LF
FM_SPI_3V3_1V8_VOLTAGEFM_ADR_ACK FM_FLASH_SECURITY_STRAPFM_ADR_MODE1FM_ADR_MODE0
1%1/16WCHIP1%0402LFCHIP1/16W10K1K1/16W0402LFCHIP1%
0402LF1/16WEMPTY1K1%
EMPTY0402LF1/16W1K1%0402LFCHIP1/16W1K1%0402LFEMPTY1/16W1K1%1/16W1KEMPTY0402LF1%
1K1/16W0402LF1%1%1/16WCHIP0402LF20KFM_PCH_BOOT_BIOS_STRAPCHIP10K0402LF1%1/16W1%1K0402LFEMPTYEMPTY1/16W1%10KCHIP1/16W0402LFFM_PCH_SPKR0402LF10K
20K1%1%0402LF20K1/16W1/16WCHIPEMPTYFOR POWER ON REQUEST, SET TO PD TO GND
2
1
2
1
2
1
R1809
2
1
2
1
2
1
2
1
2
1
2
1
2
1
2
1
2
1
2
1
2
1
2
1
DESIGN NOTE:
SHEETDATE
DEPARTMENT
SIZE
PROJECT DOCUMENT NUMBER REV
REVIEWER
DESIGNER
123
7 3 2 1 6 5 4
E
A
B
C
E
D
C
B
A
7 6 5 4
D
OUT
OUT
OUT
OUT
OUT
OUT
OUT
OUT
R3325
R1962R1810
R381
R380
R378
R379
R502
R375
R374
R372
R371
R369
R367
C



FOLLOW ARCHER CITY DESIGN TO RESERVEPCH INTERNAL: 20KOHM PULL DOWNDEFAULT: 0FUNCTION:RSVD (PCH TEST MODE)GROUP: GPP_I_23PCH INTERNAL: PULL DOWNDEFAULT: 0 (MASTER ATTACHED FLASH)GROUP: GPPC_H_0FUNCTION:VISA DEFAULTDEFAULT: 1 (NATIVE&GPI FUNCTION ARE ENABLED)PCH INTERNAL: 20K PULL DOWNFUNCTION:SKIP RTC CLOCKPUPD NO BYPASS (DEFAULT)
FOLLOW ARCHER CITY DESIGN TO RESERVEFUNCTION:JTAG ODT DISABLEDEFAULT: 1 (ODT IS ENABLED)GROUP: GPPC_S_10
PCH INTERNAL: PULL DOWNGROUP: GPPC_S_11DEFAULT: 0 (ISCLK USES 25MHZ XTAL)
GROUP: GPPC_H_19FUNCTION:RSVD (PCH TEST MODE)DEFAULT: 1FOLLOW ARCHER CITY DESIGN TO RESERVEGROUP: GPP_D_7FUNCTION:ESPI FLASH MODEPCH INTERNAL: PULL DOWNPCH INTERNAL: PULL DOWNDEFAULT: 0
PU 100MHZPD 25MHZ (DEFAULT)FUNCTION:EXTERNAL CLK MODEGROUP: GPPC_H_6DEFAULT: 0 (PCH MODE)GROUP: GPPC_H_1GROUP: GPP_O_7FUNCTION:I/O EXPANDERPCH INTERNAL: PULL DOWNFUNCTION:ESPI CS SWIZZLEDEFAULT: 0 (CS0/CS1 PINS NO SWIZZLE)STABILIZATION DELAYBYPASS/SKIP 95MS RTC CLOCKN/AFri Aug 25 14:03:14 2023N/AN/AN/AV05199 OF 312
P3V3_AUXP3V3_AUX
P3V3_AUXP3V3_AUXP3V3_AUXP3V3_AUXP3V3_AUX P3V3_AUX
P3V3_AUXPCH SIDEBAND: HW STRAPS (2/4)
184184183
184182185185184 184
1%1/16W1KEMPTY0402LF
1%EMPTY0402LF1/16W1K1%1K0402LFCHIP1/16W1%1K1/16WEMPTY0402LF1%CHIP1/16W0402LF1K1%0402LFEMPTY1K1/16W1%EMPTY1/16W1K0402LF
1%0402LFEMPTY1K1/16W1%1/16WCHIP1K0402LF1/16W0402LFCHIP1%10K
10KCHIP1/16W1%0402LF
1/16WEMPTY0402LF10K1%1/16W0402LF10K1%CHIP1/16W1%0402LFCHIP10KCHIP1/16W0402LF1%10K
1%1/16WCHIP0402LF10KFM_PCH_VISA_DEFAULTFM_LT_KEY_DOWNGRADE_NFM_ESPI_FLASH_MODE
FM_PCH_EXTERNALCLKMODEFM_PCH_SKIP_RTC_CLOCKFM_JTAG_ODT_DISABLEFM_ESPI_CS_SWIZZLEFM_PCH_IO_EXPANDER FM_PCH_XTALSEL
2
1
2
1
2
1
2
1
2
1
2
1
2
1
2
1
2
1
2
1
2
1
2
1
2
1
2
1
2
1
2
1
SHEETDATE
DEPARTMENT
SIZE
PROJECT DOCUMENT NUMBER REV
REVIEWER
DESIGNER
123
7 3 2 1 6 5 4
E
A
B
C
E
D
C
B
A
7 6 5 4
D
OUT
OUT
OUT
OUT
OUT
OUT
OUT
OUT OUT
R622
R621
R617
R618
R615
R619
R612
R611
R610
R609
R608 R614
R607 R613
R624
R623
C



FUNCTION:BIOS ADVANCE FUNCTIONSPD NORMAL OPERATION (DEFAULT)PU BIOS CORE EXECUTION TREEDEFAULT: 0GROUP: GPPC_H_16FUNCTION:MFG MODEDEFAULT: 0GROUP: GPP_L_6PCH INTERNAL: PULL DOWNGROUP: GPPC_S_2FUNCTION:XTAL_INPUT_FREQUENCY[1]DEFAULT: 0PCH INTERNAL:11 100MHZ(BI MODE)10 200MHZ(HVM MODE)01 RESERVED10 200MHZ(HVM MODE)DEFAULT: 1DEFAULT: 0GROUP: GPPC_H_7FUNCTION:MCRO_LDOPCH INTERNAL: NAPUCRYSTAL INPUTXTAL IS SINGLE-ENDEDPD XTAL IS ATTACHEDGROUP: GPP_O_0FUNCTION:SPARE0DEFAULT: 1PCH INTERNAL: 20K PULL DOWNGROUP: GPP_I_22FUNCTION:DFXTESTMODEPCH INTERNAL: NAGROUP: GPPC_L_3DEFAULT: 0PCH INTERNAL:
GROUP: GPPC_S_0FUNCTION:XTAL_INPUT_FREQUENCY[0]DEFAULT: 0PCH INTERNAL:11 100MHZ(BI MODE)PCH INTERNAL:PU RING OSC IS BYPASSEDFUNCTION:XTAL INPUT MODE00 25MHZ(SERVER MODE)(DEFAULT) 00 25MHZ(SERVER MODE)(DEFAULT)01 RESERVEDGROUP: GPPC_H_17DEFAULT: 0PCH INTERNAL:PD RING OSC IS NOT BYPASSEDFUNCTION:RING OSCILLATOR BYPASS
Fri Aug 25 14:03:15 2023N/AN/AN/AN/AV05200 OF 312P1V05_PCH_AUXP3V3_AUXP3V3_AUXP3V3_AUXP3V3_AUXP3V3_AUXP1V05_PCH_AUX
PCH SIDEBAND: HW STRAPS (3/4)184184
184182184 184184
185 185
CHIP1/16W1K1/16W0402LFCHIP5.11K1%1%1K1/16WCHIP0402LF1K1/16W0402LF1%EMPTY0402LFEMPTY1%1K1/16W1%1K1/16WEMPTY0402LFCHIP1%1/16W0402LF0402LF1K1%0402LFEMPTY1/16W1K1%
1%0402LFEMPTY1/16W1K CHIP0402LF1/16W1%10K1/16W1%0402LFCHIP10K0402LFCHIP1/16W10K1%0402LF10K1/16WCHIP1%
CHIP1/16W10K0402LF1%1/16W0402LFEMPTY12K1%FM_BIOS_ADV_FUNCTIONSFM_PCH_MCRO_LDO
FM_MFG_MODEFM_PCH_SPARE0FM_PCH_RING_OSC_BYPASS_MGPIO_TEST2 FM_PCH_XTAL_INPUT_MODE_MGPIO_TEST3FM_PCH_DFXTESTMODE
FM_XTAL_INPUT_FREQUENCY_0_MGPIO_TEST4 FM_XTAL_INPUT_FREQUENCY_1_MGPIO_TEST5
R1221
R1220
R3038 R1477R1475
R1476
2
1
2
1
2
1
2
1
2
1
2
1
2
1
2
1
2
1
2
1
2
1
2
1
2
1
2
1
2
1
R1478
SHEETDATE
DEPARTMENT
SIZE
PROJECT DOCUMENT NUMBER REV
REVIEWER
DESIGNER
123
7 3 2 1 6 5 4
E
A
B
C
E
D
C
B
A
7 6 5 4
D
OUTOUTOUT
OUT OUTOUT
OUTOUTOUT
R1499
R1498R1496
R1497
R1457R1311
R1298
R1299
C



GPPC_B_13
GPP_L_5
GPP_D_1320210922 MODIFY FOR GTGPP_D_19GPP_D_6GPP_M_11OFF(OPEN) NORMAL (DEFAULT)OPEN(SHORT) DISABLE ESPIOFF(OPEN) NORMAL (DEFAULT)OPEN(SHORT) RECOVER BIOSOFF(OPEN) DISABLE OVERRIDE (DEFAULT)OPEN(SHORT) ENABLE OVERRIDEOFF(OPEN) NORMAL (DEFAULT)OPEN(SHORT) BIOS IMAGE SWAPGPP_L_4OPEN(SHORT) CLEAR RTC REGISTERSOFF(OPEN) NORMAL RTC RESET (DEFAULT)OFF(OPEN) SECURITY DISABLE (DEFAULT)OFF(OPEN) NORMAL RTC RESET (DEFAULT)OPEN(SHORT) ME FORCE UPDATEOFF(OPEN) NORMAL (DEFAULT)OPEN(SHORT) PASSWORD CLEAROPEN(SHORT) SECURITY ENABLE201 OF 312V05N/AFri Aug 25 14:03:16 2023N/AN/AN/A
P1V05_PCH_AUXP3V3_AUXP3V3_AUXP1V05_PCH_AUXP3V3_RTC_AUX
PCH SIDEBAND: HW STRAPS (4/4)
184184198 183183183215184183131202185SW2 BIT3: ME FW UPDATE
SW1 BIT1: ESPI ENABLESW2 BIT1: FLASH SECURITY OVERRIDE STRAPSW2 BIT4: PASSWORD CLEARSW2 BIT2: CMOS CLEARSW1 BIT4: BIOS IMAGE SWAPSW1 BIT3: BIOS SWAP OVERRIDESW1 BIT2: BIOS RCVRCHIPPD_BIOS_IMAGE_SWAP_NPU_FLASH_SECURITY_STRAPPD_ME_RCVR_NPD_PASSWORD_CLEARPU_SWAP_OVERRIDE_NPU_BIOS_RCVR_BOOTPU_ESPI_ENABLE_STRAP1%FM_PASSWORD_CLEAR_NCHIP1K 1%CHIP1%1K1%CHIP1K1K1KCHIPCHIP1K1%1K1%1/16W0402LFCHIPFM_ME_RCVR_NFM_FLASH_SECURITY_STRAPFM_BIOS_IMAGE_SWAP_NFM_ADR_COMPLETEFM_PCH_BIOS_RCVR_MODEJTAG_TRC_PCH_PTI<6>CONN14_210-HP2-07GBR1IOTHLFPD_RST_RTCRST_NCHIP0402LF 0402LFCHIP10KCHIP1/16W1%1/16WCHIP10K1%0402LF1%10K1K1%CHIPCHIP20K1%1/16W10%25V1UF1/16W10K0402LFCHIP CHIP1/16W10K1%10K1/16W1%0402LF1%1/16WRST_RTCRST_NSMLFMECH0402LFC0402X6S0402LFSW4S_DTSM-61N-S-Q-T/R
4
3
2
1
R1335
R3039
R1333
R1325
R1320
R1317
R1324
R2133
1413
1211
109
87
65
43
21
4
3
2
1
J104
SW5
1413
1211
109
87
65
43
21
21 21
2
1
2
1
R1340
21
2
1
R1342
2
1
R1343
2
1
R2134
2
1
R1338
2
1
R1341
2
1
R1339
21
21 21
21
21
DESIGN NOTE:
DESIGN NOTE:
DESIGN NOTE:
DESIGN NOTE:
DESIGN NOTE:
DESIGN NOTE:
DESIGN NOTE:
DESIGN NOTE:
SHEETDATE
DEPARTMENT
SIZE
PROJECT DOCUMENT NUMBER REV
REVIEWER
DESIGNER
123
7 3 2 1 6 5 4
E
A
B
C
E
D
C
B
A
7 6 5 4
D
OUTOUT
OUT
OUTOUT
OUTOUT
OUT
C1177
C



20211130 CHANGE TO 10 OHM20211130 CHANGE TO 10 OHM
20211130 CHANGE TO 10 OHMN/A202 OF 312V05N/AN/AN/AFri Aug 25 14:03:17 2023
P3V3_AUXP3V3_AUXPGPPA_AUXPGPPA_AUXPGPPA_AUXPGPPA_AUXPCH SIDEBAND - ESPI/LPC202 257214202 257240240
240183201131223183204204183
240240183183240183240183240183183183FM_ESPI_PLD_R_EN_BUFNC_ESPI_PLD_R_EN_BUFEMPTY1/16W04021: ESPI1K1%1/16WFM_ESPI_PLD_R1_EN0402LF5%CHIPFM_ESPI_PLD_R_EN_BUFESPI_BMC_LPC_RST_N0402LF 1/16W0: LPC0IRQ_ESPI_LPC_SERIRQ_ALERT_R_N0402LF74LVC1G07SE-7EMPTY1%CHIP10K1/16WESPI_HOST_LPC_BMC_LFRAME_N1/16WJTAG_TRC_PCH_PTI<6>X7R1/16W0402LFICCHIP1%RST_PLTRST_B_MUX_NCHIP100402LFIRQ_LPC_SERIRQ_ESPI_CS1_NIRQ_LPC_PIRQA_N_ESPI_ALERT0_NIC25V10%10%NC7SB3157P6X0IRQ_LPC_PIRQA_N_ESPI_ALERT0_R_N1/16W1%IRQ_LPC_SERIRQ_ESPI_CS1_R_N1/16W100402LFRST_ESPI_RESET_N_R01%10K0402LFCHIP0402LF0402LF0402LF1/16W1%1/16W1%1%1/16W1%ESPI_LPC_LAD0_IO30402LFCHIP101/16W
1/16W0402
ESPI_HOST_LPC_BMC_CLKCLK_24M_66M_LPC0_ESPIESPI_LAD0_DATA_IO3ESPI_LPC_LAD0_IO2ESPI_LAD0_DATA_IO2ESPI_LPC_LAD0_IO1ESPI_LAD0_DATA_IO1ESPI_LPC_LAD0_IO0ESPI_LAD0_DATA_IO010CHIPCHIP10 1%CHIP1010CHIP
1%49.91/16WCHIPC0402SMLFNC7SB3157P6X0.1UFX7R10%25V1UF10%X6S25V0.1UF0402X7R25VC04021UFX6S0.1UF25VESPI OR LPC ENABLE SELECTIONFM_ESPI_PLD_EN
ESPI_LFRAME_N_BMC_CS0_N0402LF5%EMPTY0402LF1/16W1%10KCHIP
0402LFIRQ_ESPI_LPC_SERIRQ_ALERT_N10%IC0402LF1/16WRST_ESPI_RESET_N10 1%
0402LFCHIP5%
R4118
R1479
R2363
R1872
R1871
R1870
R1869
R1868
R2132
R1749
R1750
R1748
R1214
5
6
2
1
3 4
5
6
2
1
3 4
S
B0
B1
VCCGND
A
S
B0
B1
VCCGND
A
4
5
13
2
U154
U61
U60
NC1
Y
GND
A
VCC
21
21
21
21 21 21 21 21
2
1
21 2
1
2
1
2
1
2
1
21
2
1
2
1
21R1215
2
1
2
1
21
DESIGN NOTE:
SHEETDATE
DEPARTMENT
SIZE
PROJECT DOCUMENT NUMBER REV
REVIEWER
DESIGNER
123
7 3 2 1 6 5 4
E
A
B
C
E
D
C
B
A
7 6 5 4
D
IN
BI
OUTIN
BI
IN
BIBI
IN
OUTIN
BI
OUTIN
BI
OUT
OUTINBIBI
BI
BI
R2451 C1647
R1961
C606 C608
C605 C607
C



20211130 CHANGE TO 75 OHM
Fri Aug 25 14:03:19 2023N/AN/AN/AN/AV05203 OF 312
P1V05_PCH_AUXP3V3_AUX
PCH SIDEBAND - THERMTRIP & FIVRBREAK
182215183131239182
223H_THERMTRIP_LVC1_N1/16WCHIP0402LF751%1%1/16WFM_PCH_BMC_THERMTRIP_N1%1/16WFM_PLT_BMC_THERMTRIP_R_N33.2 CHIP0402LF0402LF10KCHIPFM_CPU_FBRK_DEBUG_NFM_PCH_CPU_PWR_DEBUG_N05%1/16W0402LFCHIP
FM_THERMTRIP_DLY_LVC1_N00402LF5%CHIP 1/16W
R1266
R1263
R1247
R1249
2
1
2
1
21
21
21
SHEETDATE
DEPARTMENT
SIZE
PROJECT DOCUMENT NUMBER REV
REVIEWER
DESIGNER
123
7 3 2 1 6 5 4
E
A
B
C
E
D
C
B
A
7 6 5 4
D
OUT
OUTIN
OUTIN
IN
R1820
C



GPIO BANK IGPIO BANK E GPIO BANK HGPIO BANK A
GPIO BANK S
GPIO BANK CGPIO BANK JGPIO BANK D
N/AN/AN/AN/AV05204 OF 312Fri Aug 25 14:03:20 2023P3V3_AUXP3V3_AUXP3V3_AUXP3V3_AUX
P3V3_AUXPGPPA_AUXP3V3_AUXP1V05_PCH_AUX
PCH TERMINATION(1/2)
183202183215183183202225182225182225182215184183
215184184184215184215184205185205185205
183205183205183183205183ESPI_ALERT1_N_LPC_RCIN_N0402LF1/16WCHIP1%1KIRQ_LPC_PIRQA_N_ESPI_ALERT0_N1/16W0402LFCHIP1%1K IRQ_PCH_SCI_WHEA_N0402LF1%CHIP1/16W1KIRQ_LPC_SERIRQ_ESPI_CS1_N1%CHIP10KH_CPU_ERR1_PCH_R_N10KEMPTY1%H_CPU_ERR0_PCH_R_N0402LF1/16W10KEMPTY1%H_CPU_ERR2_PCH_R_N1%10KEMPTYFM_DEBUG_PORT_PRSNT_R_N10K1%CHIPFM_PCHHOT_N10K1%CHIP
IRQ_TPM_SPI_NEMPTY0402LF1%10K1/16WPU_PCH_PMCALERT_N1%10KCHIP1/16W0402LFFM_ME_AUTHN_FAIL10K1%CHIPFM_ME_BT_DONECHIP10K1%FM_PS_PWROK_DLY_R_SEL10K1%0402LF1/16WCHIPIRQ_PCH_CPU_NMI_EVENT_R_NCHIP1%10KIRQ_SMI_ACTIVE_N0402LF1/16WCHIP1%10K
FM_THROTTLE_N1%CHIP10KFM_BIOS_POST_CMPLT_N10K1%CHIPPU_LPC_PME_N1%10KCHIPFM_PCH_GLB_RST_WARN_NCHIP1%10KPU_PCH_VRALERT_N1%10KCHIP
R2342
R401
R1554
R71
R8
R1459
R1458
R1450
R1449
21
21R1955
21
21R456
21
21
21
21
21
21
21
R1255
21R1254
21R1253
21R3042
21R1260
21R1262
21R1259
21R3041
21R1257
21R3040
SHEETDATE
DEPARTMENT
SIZE
PROJECT DOCUMENT NUMBER REV
REVIEWER
DESIGNER
123
7 3 2 1 6 5 4
E
A
B
C
E
D
C
B
A
7 6 5 4
D
OUT
OUT
OUT
OUT
OUT
OUT
OUT
OUT
OUT
OUT
OUT
OUT
OUT
OUTOUT
OUTOUT
OUT
OUT
OUT
OUT
C



Fri Aug 25 14:03:21 2023N/AN/AN/AN/AV05205 OF 312PCH TERMINATION(2/2)183183215214215228215183204183204131 198 185215185204215184204240185204215183204215 220FM_ADR_TRIGGER_R_NFM_CPU_RMCA_CATERR_DLY_NCHIPFM_BIOS_POST_CMPLT_BMC_N1/16W0402LF49.949.949.9 CHIPCHIPFM_CPU_RMCA_CATERR_DLY_LVT3_R_NFM_ADR_MODE0_R1%1/16W0402LFFM_BIOS_POST_CMPLT_HDR_NFM_PCH_PLD_GLB_RST_WARN_NFM_BIOS_POST_CMPLT_NCHIP1%1/16W0402LF33.233.20402LF 1/16W1%CHIPFM_PCH_GLB_RST_WARN_NFM_ADR_MODE01/16W0402LF33.21%CHIPIRQ_PCH_CPU_NMI_EVENT_NIRQ_PCH_CPU_NMI_EVENT_R_NCHIP33.21%0402LF 1/16WFM_PS_PWROK_DLY_SELFM_PS_PWROK_DLY_R_SEL1%0402LF 1/16WCHIP33.2IRQ_SMI_ACTIVE_BMC_NIRQ_SMI_ACTIVE_N33.21%0402LF 1/16WCHIPFM_THROTTLE_R_NFM_THROTTLE_N0402LF 1/16W1%CHIP33.21%FM_ADR_TRIGGER_N1%1/16W0402LF
R698
R1456
R1455
R1313
R1310
R1306
R1309
R1300
R1307
21
21
21
21
21
21
21
21
21
21
SHEETDATE
DEPARTMENT
SIZE
PROJECT DOCUMENT NUMBER REV
REVIEWER
DESIGNER
123
7 3 2 1 6 5 4
E
A
B
C
E
D
C
B
A
7 6 5 4
D
IN
OUT
OUT
OUTIN
INOUT
IN OUT
IN OUT
IN OUT
OUT
OUTIN
IN OUT
IN
R3065
C



DB2000 ADDRESS: 0XD820210603 MODIFY FOR GT
LOWCONTROLS OUTPUT ENABLESHIGHSIDEBAND INTERFACEENABLE BITS CONTROL OUTPUTSOE PINS AND SMBUS20210603 MODIFY FOR GTFri Aug 25 14:03:22 2023V05N/A206 OF 312N/AN/AN/A
P3V3P3V3P3V3_DB2000_VDDAP3V3P3V3_DB2000_VDDP3V3_DB2000_VDDRP3V3_DB2000_VDDP3V3_DB2000_VDDR
P3V3
P3V3P3V3_DB2000_VDDA
CLK- DB2000QL CLK BUFFER (1/2)20621521322320822321121120920920920920920920720744207207209211207207207444444442082081313131313132372371313206206206
206 444444207209206CHIP10K0402LF1/16W1%PD_DB2000_SMB_SA0CLK_SWB_OE_N10KCHIP1/16WCHIP0603LFINDSMLFBLM18SG331TN1D/1.5AP3V3_DB2000_FB_VDD1%0.1UF25V10%X7R04021%0402LFOCP_SFF_CLK_OE_NFM_DB2000_OE_N0402LFFM_PLD_CLKS_DEV_ENCLK_100M_GPU_SWB_REF_DPCLK_100M_OCP_SFF_0_R_DPCLK_100M_OCP_SFF_0_R_DNCLK_100M_OCP_SFF_1_R_DPCLK_100M_OCP_SFF_1_R_DNCLK_100M_OCP_SFF_2_R_DPCLK_100M_OCP_SFF_3_R_DPFM_DB2000_10_OE_NNC_CLK_100M_DB2000_NC8TP_CLK_100M_DIF18_DPCLK_100M_OCP_V3_2_D_R_DPCLK_100M_OCP_V3_2_D_R_DNTP_CLK_100M_DIF18_DNTP_CLK_100M_DIF19_DPTP_CLK_100M_DIF19_DNNC_CLK_100M_DB2000_NC2NC_CLK_100M_DB2000_NC3NC_CLK_100M_DB2000_NC4NC_CLK_100M_DB2000_NC1CLK_100M_DB2000_CPU1_BCLK2_DPTP_CLK_100M_DIF13_DPTP_CLK_100M_DIF13_DNCLK_100M_OCP_V3_2_A_R_DPCLK_100M_OCP_V3_2_A_R_DNFM_DB2000_8_OE_NCHIP1%0402LFCLK_100M_OCP_SFF_3_R_DNFM_DB2000_12_OE_NCHIP1%2K5%CHIPFM_DB2000_11_OE_N5%CLK_100M_GPU_SWB_REF_DNCLK_100M_OCP_V3_2_C_R_DNCLK_100M_OCP_V3_2_C_R_DPCLK_100M_OCP_V3_2_B_R_DNC0603CLK_100M_DB2000_CPU1_BCLK1_DNCLK_100M_DB2000_CPU1_BCLK1_DPCLK_100M_DB2000_CPU1_BCLK0_DNCLK_100M_DB2000_CPU1_BCLK0_DP0402LF49.91/16WCHIP1%4.7KCLK_100M_DB2000_DNCLK_100M_DB2000_DP0402C060325V6.3V1/10W0603LFCLK_100M_DB2000_CPU0_BCLK3_DNCLK_100M_DB2000_CPU0_BCLK3_DPCLK_100M_DB2000_CPU0_BCLK2_DN49.91/16WPORT 14-17 OCP_V3_2PORT 0-3/4-7: CPU0/CPU1
NC_CLK_100M_DB2000_NC18NC_CLK_100M_DB2000_NC17NC_CLK_100M_DB2000_NC15NC_CLK_100M_DB2000_NC14NC_CLK_100M_DB2000_NC13NC_CLK_100M_DB2000_NC9NC_CLK_100M_DB2000_NC7NC_CLK_100M_DB2000_NC6NC_CLK_100M_DB2000_NC5CLK_100M_DB2000_CPU0_BCLK0_DPCLK_100M_DB2000_CPU0_BCLK0_DNCLK_100M_DB2000_CPU0_BCLK1_DPSMB_HOST_DB2000_3V3AUX_SDASMB_HOST_DB2000_3V3AUX_SCLCLK_100M_DB2000_CPU0_BCLK2_DPCLK_100M_DB2000_CPU0_BCLK1_DN9QXL2001BNHGI8PORT 8: SWB BOARDPORT 9/10: GPU BOARD
4.7K
0.1UF25VFM_DB2000_VSBENIND0.1UF25VX7RC060310%10%10%X7R0402X6S10%04020402040210%X6SX7R2.2CHIPPD_DB2000_SMB_SA0PD_DB2000_SMB_SA1X6S1/10WX7R10UF20%NC_CLK_100M_DB2000_NC16
1%
NC_CLK_100M_DB2000_NC116.3VIC
FM_DB2000_VSBEN
6.3V10UF20%0.1UF25V0.1UF25VX7R0.1UFSMLFBLM18SG331TN1D/1.5A10UF2.220%SMLF1%1/16W0402LFCHIP4.7K1/16W1%1/16W0402LFEMPTY1%0402LFCHIP1/16W4.7K1%NC_CLK_100M_DB2000_NC12FM_DB2000_1_OE_NFM_DB2000_DEV_ENCLK_100M_DB2000_CPU1_BCLK3_DNCLK_100M_DB2000_CPU1_BCLK2_DNCLK_100M_DB2000_CPU1_BCLK3_DP1/16WNC_CLK_100M_DB2000_NC10CHIP0CHIP5%0CHIP5%00FM_DB2000_9_OE_NCLK_100M_OCP_V3_2_B_R_DPCLK_100M_OCP_SFF_2_R_DNCHIP5%00402LFPD_DB2000_SMB_SA14.7K0402LFCHIP1/16W1%EMPTY4.7K1/16W0402LF1%EMPTY
R4534
R575
R576
R3637
R3636
R2562
R1543
R106
E2
B10
C11
E11
E12
H11
K11
L10
L8
H2
L11
L2
B11
B2
B6
M6
L4
L5
L9
L3
L7
L6
K2
J11
J2
G11
G2
F11
F2
D11
D2
C2
B9
B7
B5
B3
TH
H1
G1
F1
E1
D1
C1
B1
A1
A2
A3
A4
A5
A6
A7
A8
A9
A10
A11
A12
B12
C12
D12
F12
G12
H12
J12
K12
L12
M12
M11
M10
M9
M8
M7
M5
M4
M3
M2
M1
L1
K1
J1
B8
B4
L4
L3
U38
1 2
1 2
DIF19#
DIF19
^vSADR1_tri
^vSADR0_tri
VDDR3.3
VDDO3.3_L11
VDDO3.3_L2
VDDO3.3_B11
VDDO3.3_B2
VDDA3.3
SMBDAT
SMBCLK
vOE12#
vOE11#
vOE10#||SHFT_LD#
vOE9#
vOE8#
vOE7#
vOE6#||CLK
vOE5#||DATA
vSBEN
DIF9#
DIF9
DIF8#
DIF8
DIF7#
DIF7
DIF6#
DIF6
DIF5#
DIF5
DIF4#
DIF4
DIF3#
DIF3
DIF2#
DIF2
NC6
NC5
NC4
NC3
NC2
NC18
NC17
NC16
NC7
NC9
DIF17#
DIF13
DIF11#
DIF_IN
DIF18
DIF16#
DIF16
DIF15#
DIF14#
DIF14
DIF13#
DIF12
DIF12#
DIF11
DIF10#
DIF10
DIF1#
DIF1
DIF0#
DIF0
NC13
NC15
NC14
NC11
NC8
EPAD
vCKPWRGD_PD#
DIF18#
DIF17
DIF15
NC10
NC1
NC12
DIF_IN#
2
1
2
1
21 21 21 21 21
2
1
21
21
2
1
2
1
2
1
2
1
2
1
2
1
2
1
2
1
2
1
2
1
2
1
2
1
2
1
2
1
21R571
21R572
21
DESIGN NOTE:
DESIGN NOTE:
21
21
SHEETDATE
DEPARTMENT
SIZE
PROJECT DOCUMENT NUMBER REV
REVIEWER
DESIGNER
123
7 3 2 1 6 5 4
E
A
B
C
E
D
C
B
A
7 6 5 4
D
IN
OUTOUT
OUTOUT
OUT
OUTOUT
OUT
OUTOUT
OUTOUT
OUTOUT
OUTOUT
OUTOUT
IN
BIIN
OUT
OUTOUT
OUT
OUTOUT
OUT
OUT
IN
OUT
OUTOUT
ININ
IN
IN
ININ OUT OUT
OUTOUT
OUTOUT
OUTOUT
R4517R4516
C1409
R574
R573
R570
R569R567
R568
C207C206C205C204
C210C208
C211C209
C



SWBGPU20210602 MODIFY FOR GT
20221215 CHANGE R3194,R3195,R3196,R3197,R3198,R3199,R3200,R3202 TO 22 OHMV05N/A207 OF 312N/AN/AN/AFri Aug 25 14:03:23 2023CLK- DB2000QL CLK BUFFER (2/2)
CLK_100M_GPU_2_R_DNCLK_100M_OCP_V3_2_B_R_DPCLK_100M_OCP_V3_2_B_R_DNCLK_100M_OCP_V3_2_C_R_DPCLK_100M_OCP_V3_2_C_R_DNCLK_100M_OCP_V3_2_A_R_DNCLK_100M_OCP_V3_2_D_R_DPCLK_100M_OCP_V3_2_A_R_DPCLK_100M_OCP_V3_2_D_R_DN
CLK_100M_SWB_R_DPCLK_100M_SWB_R_DNCLK_100M_GPU_1_R_DNCLK_100M_GPU_2_R_DPCLK_100M_GPU_1_R_DP
CLK_100M_OCP_V3_2_D_DNCLK_100M_OCP_V3_2_D_DPCLK_100M_OCP_V3_2_C_DNCLK_100M_OCP_V3_2_C_DPCLK_100M_OCP_V3_2_A_DNCLK_100M_OCP_V3_2_B_DPCLK_100M_OCP_V3_2_A_DPCLK_100M_OCP_V3_2_B_DN
CLK_100M_SWB_DPCLK_100M_SWB_DNCLK_100M_GPU_2_DNCLK_100M_GPU_1_DNCLK_100M_GPU_1_DPCLK_100M_GPU_2_DP
206206206206206206206206211
0402LF1/16W1%22CHIP220402LF1/16W1%CHIP0402LF1/16W1%22CHIP1%22CHIP 1/16W0402LF1/16WCHIP221%0402LFCHIP1%221/16W0402LFCHIP1%220402LF1/16W22CHIP1%0402LF1/16WCHIP05%0402LF1/16W211211211211211CHIP 1/16W5%00402LF5%00402LFCHIP 1/16WCHIP01/16W0402LF5%1/16W00402LFCHIP5%5%0CHIP 1/16W0402LF
159159159159159159159159143143143143143143
21
21
21
21
21
21
21
21
21
21
21
21
21
21
R2660
R2659
R3352
R3353
R3354
R3355
R3194
R3195
R3196
R3197
R3198
R3199
R3200
R3201
SHEETDATE
DEPARTMENT
SIZE
PROJECT DOCUMENT NUMBER REV
REVIEWER
DESIGNER
123
7 3 2 1 6 5 4
E
A
B
C
E
D
C
B
A
7 6 5 4
D IN
IN
IN
IN
IN
OUT
OUT
OUT
IN
OUT
OUT
OUT
OUT
OUT
OUT
OUT
OUT
OUT
OUT
IN
OUT
IN
IN
IN
IN
IN
IN
IN
C



20220331 CHANGE TO 8.2PF20211201 PU TO P3V3_AUX20210603 MODIFY FOR GT
Fri Aug 25 14:03:24 2023N/AN/AN/AN/A208 OF 312V05P3V3_AUXP3V3_AUX_CLK_GEN_VDD_CK440P3V3_AUX_CLK_GEN_VDDA25M_CK440P3V3_AUX_CLK_GEN_VDDXTAL_CK440P3V3_AUX_CLK_GEN_VDDA100M_CK440P3V3_AUX_CLK_GEN_VDDPT_CK440P3V3_AUXP3V3_AUX_CLK_GEN_VDDMXCK_CK440P3V3_AUXCLK- CK440Q CLK GEN241208208208208241208223208208223206211209209209209208208209209209209208206208208208208208208223 206 208211208208206208
8.2PF0.1P50V0.1P50VNP0C0402NP08.2PFC0402MISCSMB_HOST_CLK_3V3AUX_SCLCK440Q_OE_1FM_CLK_GEN1_OE0_NFM_CLK_CK440_SS_ENCLK_CK440_SMB_ADDR1CLK_CK440_SMB_ADDR0SMB_HOST_CLK_3V3AUX_SDAPU_CK440_SHFT_LD_NXTAL_CLK_GEN1_25M_X1XTAL_CLK_GEN1_25M_X1_R25MHZSMLFCHIP5%00402LF1/16W0402LFPU_CLK_PFT_LOST_NFM_PLD_CLK_25M_EN FM_CK440Q_DEV_25M_EN0402LFCHIPFM_PLD_CLKS_DEV_EN
CHIP1/16W
NC_CLK_CK440_MXCK7_DNNC_CLK_CK440_MXCK7_DPNC_CLK_CK440_MXCK6_DNNC_CLK_CK440_MXCK5_DPNC_CLK_CK440_MXCK5_DNNC_CLK_CK440_MXCK6_DPNC_CLK_CK440_MXCK4_DNNC_CLK_CK440_MXCK4_DPCLK_100M_CK440_PCH_EXTCLK_R_DNCLK_100M_CK440_PCH_EXTCLK_R_DPNC_CLK_CK440_MXCK1_DNNC_CLK_CK440_MXCK1_DPNC_CLK_CK440_MXCK0_DPNC_CLK_CK440_MXCK3_DPNC_CLK_CK440_MXCK3_DNNC_CLK_CK440_MXCK0_DNNC_CLK_CK440_MXCK8_DNNC_CLK_CK440_MXCK8_DPCLK_25M_CK440_ISCLK_REF_DNCLK_25M_CK440_ISCLK_REF_DPPD_CK440_SBI_CLKPD_CK440_SBI_DATA_INXTAL_CLK_GEN1_25M_X2TP_CLK_PFT_IN_DNCK440Q_OE_6CK440Q_OE_5CK440Q_OE_4CK440Q_OE_3CK440Q_OE_25%10KTP_CK440_SBI_DATA_OUTCHIPCHIPCHIPCHIP0402LFCHIP1/16W
TP_CLK_CK440_PFT_OUT_DPTP_CLK_CK440_PFT_OUT_DNMXCK3/3# & MXCK6/6# & 100M6/6# WILL NOT USE DUE TO PINOUT LIMITATIONNC_CLK_CK440_100M6_DNCLK_25M_CK440_CPU0_DPCLK_25M_CK440_CPU0_DNCLK_25M_CK440_CPU1_DPCLK_25M_CK440_CPU1_DNEMPTYFM_CK440_MXCK_25M_100MPORT 2:ISCLKNC_CLK_CK440_100M6_DPNC_CLK_CK440_100M5_DNNC_CLK_CK440_100M5_DPNC_CLK_CK440_100M4_DNNC_CLK_CK440_100M4_DPNC_CLK_CK440_100M3_DNNC_CLK_CK440_100M3_DPNC_CLK_CK440_100M2_DNNC_CLK_CK440_100M2_DPNC_CLK_CK440_100M1_DNNC_CLK_CK440_100M1_DP10K
NC_CK440_B41NC_CK440_B4410K1%0402LF
1%10K10K1%1%1%1%10K1%CHIP10KCHIP10K1/16W1% PORT 4/5/7/8: OCP_SFF(CPU0)PORT 2: PCHMXCK 100M:PORT 1:CPU1PORT 0:CPU0CLK 25M:CLK_100M_DB2000_DP1K4.75KPORT 0: CLK BUF- DB2000CHIPTP_CLK_PFT_IN_DP9SQ440NQQI8ICSMLFFM_CK440Q_DEV_25M_ENFM_CK440_MXCK_25M_100MPD_CK440_SBI_CLK0402LF0402LF 0402LF 0402LFCHIP CHIP1/16W0402LF 0402LFCHIP1/16W1%1K10K1/16W1%1/16WCHIPCLK_CK440_SMB_ADDR0CLK_CK440_SMB_ADDR1PU_CK440_SHFT_LD_NFM_PLD_CLKS_DEV_ENPD_CK440_SBI_DATA_INFM_CLK_CK440_SS_EN0402LFEMPTY4.75K0402LF1/16W1/16W 1/16W 1/16W0402LF1/16W
01/16W
4.75KEMPTYEMPTYCHIP1/16W1%4.75KEMPTY0402LF
0.1UF
SMBUS ADDRESS: 0XD2CLK_100M_DB2000_DN1%0402LF4.75K1/16W
25V10%
1/16W1%CHIP0402LF1%CHIP4.75K1%1/16W4.75KEMPTY4.75K0402LF1%0402LFEMPTY1%1%1%4.75K1K1%1K1%1KEMPTY1%1%EMPTY1/16W10K1%1/16WFM_CLK_GEN1_OE0_NNC_CK440_B22NC_CK440_B20NC_CK440_B18NC_CK440_B16NC_CK440_B13NC_CK440_B7NC_CK440_B5NC_CK440_B3NC_CK440_B2NC_CK440_A15NC_CK440_B24NC_CK440_B25NC_CK440_B26NC_CK440_B28NC_CK440_B30NC_CK440_B31NC_CK440_B33NC_CK440_B34NC_CK440_B36NC_CK440_B37NC_CK440_B39SMLF9SQ440NQQI8ICCLK 100M:0402
0402LF
R1680
R1724
R3643
R3642
R3641
R3640
R3639
R3638
R1958
R734 R953 R1196
R2481 R912 R1194
R1267 R1390 R1462
R1204 R1305
R1500 R1502 R1527 R1484
R1471
31
42
B44
B41
B39
B37
B36
B34
B33
B31
B30
B28
B26
B25
B24
B22
B20
B18
B16
B13
B7
B5
B3
B2
A15
Y2
U13
U13
X2
G2G1
X1
2/2NC_B44
NC_B41
NC_B39
NC_B37
NC_B36
NC_B34
NC_B33
NC_B31
NC_B30
NC_B28
NC_B26
NC_B25
NC_B24
NC_A15
NC_B2
NC_B3
NC_B5
NC_B7
NC_B13
NC_B16
NC_B18
NC_B20
NC_B22
1/2
VDD100M_B23
VDD100M_B21
VDDMXCK_B40
VDDMXCK_B35
VDDMXCK_B32
VDDMXCK_B29
XOUT
XIN_CLKIN
VDDXTAL
VDDPT
VDDA100M
VDDA25M
SS_EN_tri
SMB_ADR0_tri
SMBDATTA
SCLK
SBI_OUT
SBI_IN
PWRGD||PWRDN#
PFT_OUT
PFT_OUT#
PFT_LOST#
PFT_IN
PFT_IN#
OE6#
OE0#
NVGND
MXCK_SEL_100M#
MXCK8
MXCK8#
MXCK7
MXCK7#
MXCK6
MXCK6#
MXCK5
MXCK5#
MXCK4
MXCK4#
MXCK3
MXCK3#
MXCK2
MXCK2#
MXCK1
MXCK1#
MXCK0
MXCK0#
GNDS
100M6
100M6#
100M5
100M5#
100M4
100M4#
100M3
100M3#
100M2
100M2#
100M1
100M1#
100M0
100M0#
25MPG
25M2
25M2#
25M1
25M0
25M0#
OE5#
OE1#
OE4#
OE3#
OE2#
SHFT_LD#
SBI_CLK
SMB_ADR1_tri
GNDXTAL
EPAD
25M1#
2
1
2
1
21
21 21 21 21 21 21
2
1
2
1C1324
2
1
2
1
2
1
2
1
2
1
2
1
2
1
2
1
2
1
2
1
2
1
2
1
2
1
2
1
2
1
2
1
2
1
21
DESIGN NOTE:
DESIGN NOTE:
DESIGN NOTE:
DESIGN NOTE:
B11A13
A12
B6
B40B35B32B29
B17B1
B23B21
A16
B8
B9A11
B42
A10
A53B43A54
A17 A7 A6
B4
A9A8
B14B15B19A26A29A30B27
B12
B38
A35A36A37A38A39A40A41A42A43A44A45A46A47A48A49A50A51A52
A14B10
C1
A18A19A20A21A22A23A24A25A27A28A31A32A33A34
A1
A55A56A2A3A4A5
SHEETDATE
DEPARTMENT
SIZE
PROJECT DOCUMENT NUMBER REV
REVIEWER
DESIGNER
123
7 3 2 1 6 5 4
E
A
B
C
E
D
C
B
A
7 6 5 4
D
OUT
IN
OUTOUT
OUT
OUTOUTOUTOUTOUT
OUTOUT
IN
IN
BI
OUTOUT
IN
INININ
IN
IN
ININ
IN
OUTOUTOUT
OUTOUT
OUT
OUT
C2037C2036
R1483
C



PCHSFF_OCP20210602 MODIFY FOR GT20221215 CHANGE R563,R564,R565,R566,R1273,R1274,R1275,R1276 TO 22 OHM
V05N/A209 OF 312N/AN/AN/AFri Aug 25 14:03:25 2023CLK- CK440Q CLK GEN (2/2)CLK_25M_CK440_ISCLK_REF_DPCLK_25M_PCH_CPU1_DNCLK_25M_CK440_CPU1_DNCLK_25M_PCH_CPU1_DPCLK_25M_CK440_CPU1_DPCLK_25M_CK440_ISCLK_REF_DN
CLK_100M_OCP_SFF_3_R_DNCLK_25M_CK440_CPU0_DPCLK_25M_PCH_CPU0_DNCLK_25M_CK440_CPU0_DNCLK_25M_PCH_CPU0_DPCLK_100M_OCP_SFF_3_R_DPCLK_25M_CK440_CPU0_R_DNCLK_25M_CK440_CPU1_R_DPCLK_25M_CK440_CPU0_R_DPCLK_25M_PCH_REF_NS_DPCLK_25M_CK440_CPU1_R_DNCLK_25M_PCH_REF_NS_DN
CLK_100M_OCP_SFF_3_DPCLK_100M_OCP_SFF_3_DNCLK_25M_NSSC_CPU0_DPCLK_25M_NSSC_CPU0_DNCLK_25M_NSSC_CPU1_DPCLK_25M_NSSC_CPU1_DN
CLK_100M_OCP_SFF_0_R_DNCLK_100M_OCP_SFF_2_R_DPCLK_100M_OCP_SFF_1_R_DNCLK_100M_OCP_SFF_0_R_DPCLK_100M_OCP_SFF_2_R_DNCLK_100M_OCP_SFF_1_R_DPCLK_100M_OCP_SFF_2_DNCLK_100M_OCP_SFF_2_DPCLK_100M_OCP_SFF_1_DPCLK_100M_OCP_SFF_0_DPCLK_100M_OCP_SFF_0_DNCLK_100M_OCP_SFF_1_DNCLK_100M_CK440_PCH_EXTCLK_R_DNCLK_100M_CK440_PCH_EXTCLK_R_DPCLK_100M_CK440_PCH_EXTCLK_DNCLK_100M_CK440_PCH_EXTCLK_DP
208208179208179208CHIP5%00402LF1/16W5%0402LF1/16W0CHIPEMPTY5%01/16W0402LF1/16WCHIP5%00402LF1/16W0402LF5%0EMPTY05%CHIP0402LF1/16W179208179208206206EMPTY5%01/16W0402LF0402LF1/16WCHIP5%0EMPTY5%0402LF1/16W01/16W0402LF0CHIP5%CHIP221/16W1%0402LF221/16W1%0402LFCHIP
1791790402LF1/16WCHIP05%0402LFCHIP5%01/16W1/16W0402LFCHIP05%05%CHIP0402LF1/16W1531534444131320620620620620620622CHIP 1/16W0402LF1%221%0402LFCHIP 1/16W0402LFCHIP 1/16W221%1/16W1%220402LFCHIPCHIP1%221/16W0402LF1/16WCHIP1%220402LF153153153153153153208208CHIP5%1/16W00402LFCHIP0402LF1/16W5%0179179
R1020
R1021
R1022
R1023
R1012
R1013
R1014
R1015
R1016
R1017
R1018
R1019
R1010
R1011
21R553
21R554
21
21
21
21
21
21
21
21
21
21
21
21
21
21
21
21
21
21
21
21
21
21
R563
R564
R565
R566
R1273
R1274
R1275
R1276
SHEETDATE
DEPARTMENT
SIZE
PROJECT DOCUMENT NUMBER REV
REVIEWER
DESIGNER
123
7 3 2 1 6 5 4
E
A
B
C
E
D
C
B
A
7 6 5 4
D
OUT
IN
OUT
IN
IN
OUT
OUT
OUT
OUT
OUT
IN
OUT
IN
IN
IN
IN
IN
IN
IN
OUT
OUT
OUT
OUT
OUT
OUT
IN
OUT
OUT
IN
IN
IN
IN
IN
IN
IN
IN
C



N/AN/AN/AN/AV05210 OF 312Fri Aug 25 14:03:26 2023P3V3_AUX_CLK_GEN_VDDMXCK_CK440P3V3_AUX_CLK_GEN_VDDA25M_CK440P3V3_AUXP3V3_AUX_CLK_GEN_VDDXTAL_CK440P3V3_AUX_CLK_GEN_VDD_CK440P3V3_AUXP3V3_AUX_CLK_GEN_VDDPT_CK440P3V3_AUX_CLK_GEN_VDDA100M_CK440P3V3_AUX
CLK- CK440 POWER FILTER
PAIR EACH 0.047UF CAP WITH A PWR PIN. FOR ALL FILTERSX6S20%6.3V10UFPLACE EACH 0.047UF CAP AT LESS THAN 150 MILS FROM RESPECTIVE PWR PIN0.047UF6.3V20%IND10UF25V10%C040225V25V0.047UF1UFX7R10%C0402X7R10%25V0.047UFX7RC0402X7R10%25VC04020.047UFX7R10%25VC04020.047UFX6S0.047UFC040225V10%X7R6.3V0.047UFC040225V10%X7R20%25V0.047UFC040210%X7R25V10%0.047UFC040210%X6SX6S1UFSMLFINDFCM2012KF-601T/0.5A25VX6SC040225V10%C0402X7RX6SX7R10%25VC04020.047UF0.047UF10%C0402X7R1CHIP1%1/10W0603LFCHIP11/10W1%0603LF1CHIP1%1/10W0603LFSMLFINDFCM2012KF-601T/0.5A10UFC0603X6S20%6.3V10UFC060310%X6S25V1UFC040210UFC0603C06036.3VC060320%10UFFCM2012KF-601T/0.5ASMLF6.3VC0603X6S20%
L14
L13
L1
1 2
1 2
1 2
2
1
2
1
2
1
2
1
2
1
2
1
2
1
2
1
2
1
2
1
2
1C171
2
1
2
1
2
1
21
2
1
2
1
2
1
2
1
2
1
2
1 CAD NOTE:
CAD NOTE:
21
21
21
SHEETDATE
DEPARTMENT
SIZE
PROJECT DOCUMENT NUMBER REV
REVIEWER
DESIGNER
123
7 3 2 1 6 5 4
E
A
B
C
E
D
C
B
A
7 6 5 4
D
C115 C116 C117 C119 C120
C107
C111 C112 C114
C173C110
C1310 C1312
R447
C1314
C1313C1309 C1311
R442
C108
R519
C172
C



9ZXL045 ADDRESS: 0XDE
20211210 MODIFY FOR GT
Fri Aug 25 14:03:27 2023N/AN/AN/AN/AV05211 OF 312
P3V3_9ZXL045_VDDAP3V3_9ZXL045_VDDP3V3_9ZXL045_VDDRP3V3P3V3P3V3_9ZXL045_VDDR
P3V3
P3V3P3V3_9ZXL045_VDDP3V3_9ZXL045_VDDAP3V3
P3V3CLK - 9ZXL045 CLK BUFFER
206211208223206207207207207215215215207207206237237211 211211FCM2012KF-601T/0.5AINDSMLFX7R0402FCM2012KF-601T/0.5AP3V3_9ZXL045SMLFIND10UFCLK_100M_GPU_SWB_REF_DNCLK_9ZXL045_SADR0FM_9ZXL045_DEV_ENFM_PLD_CLKS_DEV_ENCLK_100M_SWB_R_DNCLK_100M_GPU_1_R_DPCLK_100M_GPU_1_R_DNCLK_100M_SWB_R_DP0402LFCHIP10K1/16W1%1/16W10K 10KCHIP0402LFCLK_SWB_BUF2_OE_N0402LFFM_9ZXL045_0_OE_N33.21%CHIPCLK_GPU_2_OE_NCLK_GPU_1_OE_NTP_CLK_100M_BUF_DIF3_DNCHIP1/16W1%1%FM_9ZXL045_2_OE_NFM_9ZXL045_1_OE_NFM_9ZXL045_3_OE_NTP_CLK_100M_BUF_DIF3_DPCLK_100M_GPU_2_R_DNCLK_100M_GPU_2_R_DP33.233.210KCHIPCLK_100M_GPU_SWB_REF_DPSMB_HOST_9ZXL045_3V3AUX_SCLSMB_HOST_9ZXL045_3V3AUX_SDA20%X6S1/10WIC10UFX6S20%10%0603LF25V10%X6SC06036.3VX7R040210%
4.75K1%1/16WCHIP0402LFEMPTY0402LF4.75K1%CLK_9ZXL045_SADR0CHIP1/16W1%10K1%1/16WCHIP0402LF
SMLF1%49.9CLK_9ZXL045_HIBW1/16W
C0603C060304026.3V25V25V20%0402 0402X7R0.1UF10%10%10%X7R1/16W0402X7R10%25V0.1UF25V0.1UF0.1UF0.1UF6.3V1CHIP1%0603LF
0402LF
X7R04020.1UF25V1/10WCHIP1%1 10UF0.1UFX7RNC_U314_FBOUTNC_U314_FBOUT_NNC_U314_NC0NC_U314_NC1NC_U314_NC2NC_U314_NC31%CHIP10KCHIP0402LF9ZXL0451EKILFT1%CHIP1%CLK_9ZXL045_HIBW25V
R4476
R4520R4519R4518
R4479
R4478
R4477
R4494
R4493
R4475
21
21
5
26
24
18
15
2
31
29
25
21
16
12
6
7
30
17
11
10
8
9
33
4
3
28
27
23
22
20
19
14
13
32
1
L20
L19
U314
1 2
1 2
vSADR0_tri
NC2
NC3
VDD0
DIF3
DIF1
EPAD_GND
^HIBW_BYPM_LOBW#
VDD1
VDDA
NC0
DIF3#
DIF2#
vOE2#
DIF2
DIF1#
vOE1#
DIF0
DIF0#
^CKPWRGD_PD#
VDD2
SMBCLK
FBOUT_NC#
NC1
SMBDAT
vOE3#
vOE0#FBOUT_NC
VDD4
VDD3
VDDR
DIF_IN#
DIF_IN
2
1
2
1
2
1
21 21 21
2
1
21
2
1
2
1
2
1
2
1
2
1
2
1
2
1
2
1
21
2
1
2
1
2
1
21
21
2
1
2
1
SHEETDATE
DEPARTMENT
SIZE
PROJECT DOCUMENT NUMBER REV
REVIEWER
DESIGNER
123
7 3 2 1 6 5 4
E
A
B
C
E
D
C
B
A
7 6 5 4
D
INININ
ININ
IN
OUT
OUTOUT
OUTOUT
OUTOUT
IN
ININ
IN
OUT
C2339
C2335
C2334
C2336C2333C2330C2329
R4492
R4491
R4490
R4489
C2328
C2332
C2331
C



ADDRESS: 0XD420 MATO GPU FPGA13 MATO BMC20211129 U248 CHANGE TO OR GATE
20210602 MODIFY FOR GT20220620 CHANGE TO 8.2PF
Fri Aug 25 14:03:29 2023N/AN/AN/AN/AV05212 OF 312
P3V3_AUXVFG3P3_CLK_GENP3V3_AUXP3V3_AUXP3V3_AUXVFG_3P3A_CLK_GENP3V3_AUXP3V3_AUX
VFG_3P3A_CLK_GENVFG3P3_CLK_GEN
P3V3_AUXCLK-GEN(NON SSC)
FG_SS_ENP3V3_PWRGD_CLKGENCHIPCHIP241CLK_GEN2_GPU_OE_NCLK_100M_GPU_FPGA_DN_RCLK_100M_GPU_FPGA_DP_RCLK_100M_BMC_RC_DN_RCLK_100M_BMC_RC_DP_RCLK_GEN2_BMC_RC_OE_R3_NSMB_HOST_CLK_GEN2_3V3AUX_SDASMB_HOST_CLK_GEN2_3V3AUX_SCLCLK_GEN2_SMB_SADRCLK_GEN2_XTAL_OUTCLK_GEN2_XTAL_INSMLFIC9FGL0251DKILFTNP0C04020402LF8.2PF215166212167166 167212241212212212212212240240143143214148 212MISCC040250V0.1P50V8.2PFCLK_GEN2_BMC_RC_OE_NCLK_GEN2_GPU_FPGA_OE_OR_N25MHZ0.1PNP0CLK_GEN2_XTAL_IN_RSMLF0402LF1/16WCHIP10K1%0402LF5%01/16WCHIP
CLK_GEN2_GPU_FPGA_OE_R2_NGPU_FPGA_READY_R_NCHIP1/16W0402LF0SMLF74LVC1G32GW04021%4.7K1/16W0402LFCLK_GEN2_GPU_FPGA_OE_OR_NEMPTYIC0402LF10%FG_SS_EN1/16W0402LF0CHIPCHIPCHIP0.1UFX7RX7R040210%10%0402X7R10%10%C080525V10%
CHIP1/16W10K0402LFCHIP1/16W1%10K0402X7R25V 25V10%25V25VX6S10UF10%04020.1UF 0.1UF 0.1UFC0402X6S25V25V0.1UF1UF0402X7R0402LF1/16W11%PLACE CLOSE TO U247 ALL VDD PINS5%CHIP0402LF1/16W
CHIP
0402LF0402LF10K1%1%1%1/16W10KCHIP0001/16W0FCM2012KF-601T/0.5AINDSMLF
EMPTY5%P3V3_PWRGD_CLKGENX7R0.1UF25V4.7K1%0CHIP0402LFCLK_100M_BMC_RC_DNCLK_100M_BMC_RC_DPCLK_100M_GPU_FPGA_DNCLK_100M_GPU_FPGA_DPCHIP5%1/16WCLK_GEN2_GPU_FPGA_OE_NGPU_FPGA_READY_N0 10K1%CLK_GEN2_SMB_SADREMPTY1/16W
C2256C2255
R4501
R4075
R4076
R4080
R4081
R4082R4079
R4078
C2258
C1884R4077
R3327
R3326
C1882
R3338
R3337
R3336
R3335
C1889C1886
1
2
4
19
12
3
7
16
20
11
25
9
8
24
5
6
15
21
10
18
17
14
13
23
22
31
42
5
4
2
1
3
21
U247
Y3
U248
L17
TH_GND
GNDXTAL
^vSS_EN_tri
^CKPWRGD_PD#
GND_21
VDD3.3_20
vOE1#
DIF1#
DIF1
VDDA3.3
GNDA
DIF0#
DIF0
vOE0#
VDD3.3_11
GND_10
SDATA_3.3
SCLK_3.3
VDDDIG3.3
GNDDIG
GNDREF
vSADR||REF3.3
VDDXTAL3.3
X2
XIN||CLKIN_25
X2
G2G1
X1
GND
O
I1
VCC
I0
1 2
2
1
2
1
2
1
2
1
21
2
1
R3322
21 21
2
1
2
1
2
1
2
1
2
1
2
1C2259
2
1
2
1C2257
2
1
21
21
21
2
1
21 21
21 21
2
1
2
1
2
1C1883
DESIGN NOTE:
SHEETDATE
DEPARTMENT
SIZE
PROJECT DOCUMENT NUMBER REV
REVIEWER
DESIGNER
123
7 3 2 1 6 5 4
E
A
B
C
E
D
C
B
A
7 6 5 4
D
IN
IN
OUTOUT
OUTOUT
OUT
IN
IN
IN
ININ
OUT
OUT OUT
OUTBI
R4521
R4514
C



20220823 CHANGE R4714,R4715 TO 33 OHM.20220727 ADD R4714,R4715
20210902 MODIFY FOR GT
20220304 ADD R462520220504 ADD R4697Fri Aug 25 14:03:30 2023N/AN/A213 OF 312V05N/AN/AP5V_AUX_VCC
P3V3_AUXP3V3_AUXP3V3_AUX P3V3_AUX
MAIN FPGA / PFR (1/5)21321321321321313124113124125814721321315015014914714714921316415819721321315804680213183183182220213213213213183228
213213213240213147213147147150 149185213151242206184213241241278 253222213260266 253282132253262300 254222222153153153222222222222222222160213159159213220159159153305305213213148213213213213213248213213151213213213213213246213148153154148213148301305159160213148148
213245213213213213185213213213213213213234234213213
213213147227213
266 253281253299 254213213213213213213213213213213GPU_FPGA_EROT_RST_R_NGPU_NVS_PWR_BRAKE_R_NGPU_FPGA_THERM_OVERT_ISO_R_NSMB_HOST_3V3AUX_PLD_SCLSMB_HOST_3V3AUX_PLD_SDACHIPCHIP33.2PJT138KSMLFSMB_HOST_3V3AUX_SCL_R433.2SMB_HOST_3V3AUX_SDA_R4CHIP33.2PWRGD_P5V_AUXGPU_FPGA_THERM_OVERT_ISO_NGPU_BASE_STBY_EN_RGPU_BASE_HMC_READY_ISO_RGPU_NVS_PWR_BRAKE_NGPU_FPGA_EROT_RST_NGPU_BASE_STBY_ENGPU_BASE_HMC_READY_ISOGPU_HMC_PRSNT_ISO_NGPU_FPGA_BOOT_ENICPJT138K0402LFPWRGD_P5V_AUX_R2ICCHIP
OCP_V3_2_AUX_PWR_PLD_ENOCP_SFF_AUX_PWR_PLD_ENFM_PECI_MUX_SEL_NFM_OCP_V3_2_PWR_GOOD_RFM_OCP_SFF_PWR_GOOD_RFM_S3M_CPU0_CPLD_CRC_ERRORFM_S3M_CPU1_CPLD_CRC_ERROROCP_SFF_CLK_OE_R_NIRQ_SML1_PMBUS_BMC_ALERT_NIRQ_SML1_PMBUS_PLD_ALERT_NFM_SLP_SUS_RSM_RST_NGPU_BASE_HMC_READY_ISO_RGPU_FPGA_EROT_RST_R_NGPU_NVS_PWR_BRAKE_R_NGPU_FPGA_THERM_OVERT_ISO_R_NPU_RST_DEDI_BUSY_PLD_NIRQ_SML0_ALERT_R_N5%1/16WGPU_WP_HW_CTRL_R_NGPU_PRSNT_N_ISO_RGPU_FPGA_EROT_FATALERR_ISO_R_NRST_SRST_PLD_BMC_NGPU_FPGA_EROT_RECOV_R_NCHIP33.233.2GPU_FPGA_EROT_FATALERR_ISO_NGPU_FPGA_OVERT_ISO_R_NGPU_WP_HW_CTRL_NGPU_FPGA_OVERT_ISO_NGPU_FPGA_EROT_RECOV_N
SMLFLCMXO3LF-9400C-5BG484CIC1%4.7K1/16WEMPTY0402LF1%4.7K0402LFEMPTY1/16W
33.2 CHIP0402LF1%CHIP1/16W1005%0CHIP05%CHIP05%EMPTYCHIP33.233.2 CHIPCHIP33.2CHIP33.233.2 CHIPCHIP33.2CHIP33.2CHIP33.2CHIP33.2CHIP33.2CHIP33.233.2 CHIPCHIP33.2
CHIP10K1%0402LF1/16W
33.2 CHIPCHIP33.2 CHIPCHIPCHIP33.2CHIP33.233.2 CHIPCHIP33.2CHIP5%0 FM_SWB_PWR_EN_RFM_SUSACK_NBIC_MONITER_ISO_RBMC_MONITER_RVIRTUAL_RESEAT_FPGA_NOCP_SFF_CLK_OE_NFM_TPM_PRSNT_NJTAG_BMC_SW_PLD_OESMB_1_PLD_3V3AUX_SCL_R1SMB_1_PLD_3V3AUX_SDA_R1PWRGD_PVCCD_HV_CPU0PWRGD_P3V3_AUX_PLDPWRGD_P5V_AUX_R2PWRGD_P3V3PWRGD_PVCCIN_CPU0PWRGD_PVNN_MAIN_CPU0PWRGD_PVNN_PCH_AUXPWRGD_PVNN_MAIN_CPU1SGPIO_DEBUG_PLD_CLKSGPIO_DEBUG_PLD_DOUTSGPIO_OCP_SFF_DATAINSGPIO_OCP_SFF_CLKSGPIO_OCP_SFF_DATAOUTSGPIO_DEBUG_PLD_LD_NSGPIO_DEBUG_PLD_DINSGPIO_BMC_DOUTSGPIO_BMC_CLKSGPIO_BMC_LD_NSGPIO_BMC_DIN_RFM_NCSI_OCP_V3_2_R_OEGPU_FPGA_READY_ISO_RSGPIO_OCP_V3_2_DATAINSGPIO_OCP_V3_2_LD_NNC_FPGA_PT41DJTAG_BMC_SW_PLD_OEPU_MAIN_FPGA_CONFIG_DONESGPIO_OCP_V3_2_CLKSGPIO_OCP_V3_2_DATAOUTSGPIO_OCP_SFF_LD_NP12V_HSC_T_CRIT_R_NP12V_HSC_TEMP_ALERT_R_NNC_FPGA_PT44BNC_FPGA_PT43BNC_FPGA_PT43ARST_SRST_PLD_BMC_R_NNC_FPGA_PT42DNC_FPGA_PT43CNC_FPGA_PT44ANC_FPGA_PT43DFM_SWB_PWR_ENBIC_MONITER_ISOBMC_MONITERFM_BMC_SUSACK_R_NVIRTUAL_RESEAT_FPGA_R_NFM_TPM_PRSNT_R_NOCP_SFF_CLK_OE_R_NJTAG_BMC_SW_OEFM_OCP_V3_2_PWR_GOOD_RIRQ_HSC_FAULT_R1_NFM_GPU_PWR_EN_RFM_GPU_PWRGD_ISO_RFM_OCP_SFF_PWR_GOOD_RFM_SWB_BIC_READY_ISO_R_NFM_SWB_PWRGD_ISO_RGPU_FPGA_READY_ISO_RFM_GPU_HSC_ENRST_BMC_FROM_SWB_ISO_R_NFM_GPU_PWRGD_ISOFM_OCP_SFF_PWR_GOODGPU_FPGA_READY_ISOFM_GPU_PWR_ENFM_SWB_BIC_READY_ISO_NIRQ_HSC_FAULT_NFM_OCP_V3_2_PWR_GOODFM_GPU_HSC_EN_RRST_BMC_FROM_SWB_ISO_NFM_SWB_PWRGD_ISO
FM_SWB_PWRGD_ISO_RFM_FAN_PWR_ENFM_BMC_SUSACK_R_NIRQ_HSC_FAULT_R1_NVIRTUAL_RESEAT_FPGA_R_NFM_TPM_PRSNT_R_NFM_PCH_PRSNT_NFM_SWB_PWR_ENFM_GPU_PWR_ENFM_GPU_PWRGD_ISO_RFM_GPU_HSC_EN_RFM_SWB_BIC_READY_ISO_R_NRST_BMC_FROM_SWB_ISO_R_NSMB_BMC_SWB_ENSMB_BMC_GPU_ENBMC_MONITERBIC_MONITER_ISO_R
GPU_FPGA_BOOT_EN_RGPU_HMC_PRSNT_ISO_R_NGPU_PRSNT_N_ISORST_SRST_PLD_BMC_R_NCHIP4.7K1%1/16WEMPTY10K0402LFPWRGD_PVCCFA_EHV_FIVRA_CPU0PWRGD_PVPP_HBM_CPU0PWRGD_PVPP_HBM_CPU1GPU_BASE_STBY_EN_RGPU_HMC_PRSNT_ISO_R_N33.233.24.7K5%1/16WCHIP0402LFSMLFCHIP33.2SMB_HOST_3V3AUX_PLD_SDASMB_HOST_3V3AUX_PLD_SCLGPU_FPGA_BOOT_EN_RGPU_FPGA_EROT_RECOV_R_NGPU_FPGA_OVERT_ISO_R_NGPU_WP_HW_CTRL_R_NGPU_PRSNT_N_ISO_RGPU_FPGA_EROT_FATALERR_ISO_R_NPWRGD_P5V_AUX_R1
G2G1
S2 D2D1S1
R1547
R1853
R2071
R4715
R4714 R2846
R2939
R4495
R4625
R2845
R2661
R2663
R2664
R2844
R3230
R1606
R3324
R2847
R1681
R3477
R3476
R3479
R3478
R3481
R3480
R3483
R3482
R3485
R3484
R3505
R3486
R4697
R2662
R3043
B22
A21
C20
C19
B21
A20
G15
F15
B20
A19
D18
C18
B19
A18
D17
E16
B18
A17
D16
C17
B17
A16
D15
C15
B15
A15
F14
G14
D14
C14
B14
A14
D13
C13
B13
A13
F13
E13
F12
G12
A12
B12
E12
D12
D11
E11
A11
B11
F11
G11
A10
B10
E10
F10
G9
F9
A9
B9
D9
C9
A8
B8
D8
C8
D7
C6
A7
B6
E7
D6
A6
B5
C5
D5
A5
B4
G8
F8
A4
B3
C4
C3
A3
B2
F7
E6
A2
B1
2 5
1 64 3
U249
Q50 Q50
3/7
BANK 0
PT43D
PT43C
PT42D
PT42C
PT42B
PT42A
PT41D
PT41C
PT40D
PT40C
PT40B
PT40A
PT39D
PT39C
PT39B
PT39A
PT38D
PT38C
PT38B
PT38A
PT30D
PT30C
PT30B
PT30A
PT29D
PT29C
PT29B
PT29A
PT28D
PT28C
PT27B
PT27A
PT24D
PT24C
PT24B
PT24A
PT23D
PT23C
PT21D
PT21C
PT21B
PT21A
PT20D
PT20C
PT20B
PT20A
PT14D
PT14C
PT14B
PT14A
PT13D
PT13C
PT13B
PT13A
PT12D
PT12C
PT12B
PT12A
PT10D
PT10C
PT10B
PT10A
PT11D
PT11C
PT22B
PT22A
PT11B
PT11A
PT15A
PT9A||L_GPLLT
PT9C
PT9B||L_GPLLC
PT9D
PT15B
PT23A||PCLKT0_1
PT23B||PCLKC0_1
PT44A||R_GPLLT
PT44B||R_GPLLC
PT27C||SCL||PCLKT0_0
PT27D||SDA||PCLKC0_0
PT28A
PT28B
PT31A
PT31B
PT41A
PT41B
PT43A||R_GPLLT
PT43B||R_GPLLC
21
21
2
1
21
21
2
1
21
21
21
21
21
21
21
21
21
21
21
21
21
21
2
1
2
1
2
1
2
1
21
21
21
21
21
21
21
21
21
21
21
21
21
21
21
SHEETDATE
DEPARTMENT
SIZE
PROJECT DOCUMENT NUMBER REV
REVIEWER
DESIGNER
123
7 3 2 1 6 5 4
E
A
B
C
E
D
C
B
A
7 6 5 4
D
IN
IN
IN
IN
IN
OUT
ININ
OUT
OUT
OUT
OUT
IN
IN
IN
OUT
OUT
ININOUTOUT
OUT
OUTIN
IN
OUTOUT
OUT
INININ
OUT
IN
OUT
OUT
ININ
IN
OUTOUTOUT
OUT
IN
IN
IN
OUTOUT
IN
ININOUT
OUT
IN
IN
OUT
IN
IN
IN
OUT
OUT
IN
IN
OUT
IN
IN OUT
OUT
OUT
IN
BIIN
BI
IN
OUT
BI
IN
OUT
OUT
OUT
OUT
OUT
OUT
ININ
INBIIN
ININ
INOUTIN
ININ
INOUTIN
OUTIN
IN
OUT
INOUT
OUT
OUTOUT
OUTIN
OUT
INOUT
INOUT
INOUT
ININOUT
IN
OUT
IN
IN
OUT
IN
IN
IN
OUT
OUT
OUT
OUT
OUT
OUT
OUT
OUT
OUT
OUT
OUT
OUT
OUT
IN
IN
IN
IN
IN
IN
IN
IN
R1467 R1551
R2346R2344
R2343
C



20220224 ADD R4606,R4607,R4608,R4609,R4610,R4611,R4612
20210902 MODIFY FOR GT
20220113 ADD R4599,R4600
Fri Aug 25 14:03:31 2023N/AN/A214 OF 312N/AN/AV05P3V3_AUXP3V3_AUXMAIN FPGA / PFR (2/5)0274172172172240171292171220222255220222255222262252224220244296254284254292254274253292254214214214214214159153115115115115115115115115224 26022321420522022028426621444 11944 11944 119240214214219 22321424021421421413119131191311944 11944 11913119214214222222162163164214156157158244306307182
219278219222219222219222214202224 252215214
219222214214214190240214214214185198240191214301305247259240228 240214239214148214170
274253219263281299219222219222219262214284254300219222219222219296219 223219 22313119282241241260
239212134151214148IRQ_PVCCFA_CPU0_VRHOT_R_NOCP_V3_2_P3V3_ADC_ALERTM2_0_P3V3_ADC_ALERTP12V_SCM_ADC_ALERTNC_FPGA_PR14ANC_FPGA_PR14BFM_UARTSW_LSB_NOCP_SFF_P3V3_ADC_ALERTIRQ_PVCCFA_CPU1_VRHOT_R_NE1S_0_P3V3_ADC_ALERTPWRGD_PCH_PWROK_RPWRGD_SYS_PWROK_RPWRGD_P1V8_PCH_AUX_PLDPWRGD_P1V05_PCH_AUXPWRGD_PS_PWROK_PLD_ISO_RFM_PFR_DSW_PWROK_NPWRGD_PVCCD_HV_CPU1PWRGD_PVCCFA_EHV_FIVRA_CPU1PWRGD_PVCCINFAON_CPU1PWRGD_PVCCINFAON_CPU0PWRGD_PVCCFA_EHV_CPU1E1S_0_LED_ACT_R_NFM_SMB_2_ALERT_GPU_ISO_R_NFM_SMB_1_ALERT_GPU_ISO_R_NHP_LVC3_OCP_V3_1_HSC_PWRGD_PLD_RHP_LVC3_OCP_V3_2_HSC_PWRGD_PLD_ROCP_V3_2_MAIN_PWR_ENOCP_SFF_MAIN_PWR_ENPWRGD_FAIL_CPU1_GH_RPWRGD_FAIL_CPU1_EF_RPWRGD_FAIL_CPU1_CD_RPWRGD_FAIL_CPU1_AB_RPWRGD_FAIL_CPU0_GH_RPWRGD_FAIL_CPU0_EF_RPWRGD_FAIL_CPU0_CD_RPWRGD_FAIL_CPU0_AB_RFM_PS_EN_PLD_RFM_SLPS4_PLD_NFM_JTAG_BMC_MUX_SEL_RFM_CPU_RMCA_CATERR_DLY_LVT3_R_NFM_RST_PERST_BIT1FM_RST_PERST_BIT0NC_FPGA_PR13AIRQ_PVCCIN_CPU1_VRHOT_R_NIRQ_PVCCIN_CPU0_VRHOT_R_NPWRGD_DSW_PWROK_R3FM_CPU1_PKGID2FM_CPU1_PKGID1FM_CPU1_PKGID0FM_SOL_UART_CH_SELFM_THERMAL_ALERT_R_NLED_HDD_ACTIVITY_B_PLD_N0402LFRST_PERST_SWB_NHP_LVC3_OCP_V3_2_HSC_PWRGD_PLD_RFM_UARTSW_MSB_NNC_FPGA_PR30DFM_PCH_SPKR_RFM_BMC_CPU_FBRK_OUT_R_NCLK_GEN2_GPU_FPGA_OE_R_NFM_CPU0_PKGID2FM_CPU0_PKGID1FM_CPU0_PKGID0FM_CPU1_PROC_ID1FM_CPU1_PROC_ID0FM_CPU0_PROC_ID1FM_JTAG_TCK_MUX_SEL_RGPU_FPGA_RST_NFM_CPU0_SKTOCC_LVT3_PLD_NFM_CPU1_SKTOCC_LVT3_PLD_NHP_LVC3_OCP_V3_2_P12V_PWRGD1/16WHP_LVC3_OCP_V3_1_HSC_PWRGD_PLD_RCHIPHP_LVC3_OCP_V3_1_P12V_PWRGDPWRGD_DSW_PWROK1/16W0402LFCHIP05%FM_PVCCD_HV_CPU0_ENFM_PVCCFA_EHV_CPU0_R_ENFM_PVCCFA_EHV_CPU1_R_ENFM_PVCCFA_EHV_FIVRA_CPU1_R_ENPWRGD_DSW_PWROK_R3FM_ESPI_PLD_R1_ENPWRGD_PS_PWROK_PLDCHIP5%0CLK_25M_OSC_MAIN_FPGACHIP1%33.2PLACE ALL RS RESISTORS WITHIN 0.5 INCHES FROM OSC.CLK PINLENGHT MATCH MAIN AND DEBUG PLD CLOCKS +/- 25 MILSFM_JTAG_TCK_MUX_SEL_R
FM_PVCCFA_EHV_FIVRA_CPU0_R_ENNC_FPGA_PR16DFM_SMB_2_ALERT_GPU_ISO_R_NFM_SMB_1_ALERT_GPU_ISO_R_NGPU_FPGA_RST_NLED_HDD_ACTIVITY_B_NFM_BMC_CPU_FBRK_OUT_R_NCLK_GEN2_GPU_FPGA_OE_R_N0402LF1/16WFM_PCH_SPKR_RCHIP33.20402LFCHIP33.2CHIPSMLFCLK_25M_OSC_FPGA_R33.2PU_CLK25M_OSC_FPGA_EN0402LFCHIP1/16W1%10K040210%X7R25V0.1UF25MHZOSCFM_PCH_SPKRCHIPCHIPE1S_0_LED_ACT_NNC_FPGA_PR16CFM_ESPI_PLD_R_ENMB0_P12V_STBY_PWRGD0402LFFM_JTAG_BMC_MUX_SEL_FROM_BMC_R1/16WPWRGD_PS_PWROKCHIPFM_THERMAL_ALERT_R_NFM_JTAG_BMC_MUX_SEL33.2E1S_0_LED_ACT_R_N1%33.2EMPTY5%00CHIPFM_SMB_1_ALERT_GPU_ISO_N05%CHIP05%CHIPFM_JTAG_BMC_MUX_SEL_RCHIPFM_THERMAL_ALERT_N5%00CHIP5%05%CHIP0PWRGD_PVCCFA_EHV_CPU0FM_PCH_P1V8_AUX_ENFM_PVPP_HBM_CPU0_ENFM_PVPP_HBM_CPU1_ENFM_PVCCIN_CPU1_R_ENFM_PVCCIN_CPU0_R_ENFM_AUX_SW_ENFM_P1V05_PCH_AUX_ENFM_ESPI_PLD_R_ENPWRGD_PVCCIN_CPU1FM_PVNN_MAIN_CPU1_ENFM_PVCCINFAON_CPU1_R_ENFM_PVCCINFAON_CPU0_R_ENFM_PVCCD_HV_CPU1_ENICRST_PCIE_CPU0_DEV_PERST_NRST_PCIE_CPU1_DEV_PERST_NFM_CPU0_PROC_ID0FM_PVNN_MAIN_CPU0_ENSMB_2_PLD_3V3AUX_SDA_R1SMB_2_PLD_3V3AUX_SCL_R1LCMXO3LF-9400C-5BG484CSMLF
5%FM_P5V_EN05%CHIPFM_BMC_CPU_FBRK_OUT_NCLK_GEN2_GPU_FPGA_OE_NFM_JTAG_TCK_MUX_SEL1%1/16W33.25%5%CHIPGPU_FPGA_RST_R_NLED_HDD_ACTIVITY_B_PLD_NFM_SMB_2_ALERT_GPU_ISO_N
R4607
R4606
R3067
R1833
R4600
R3048
R3047
PR30D
PR30C
PR28D
PR28C
PR28B
PR28A
PR27D
PR27C
PR27B
PR27A
PR26D
PR26C
PR26B
PR26A
PR25D
PR25C
PR24D
PR24C
PR24B
PR24A
PR21D
PR21C
PR21B
PR21A
PR20D
PR20C
PR19D
PR19C
PR18D
PR18C
PR18B
PR18A
PR17D
PR17C
PR16D
PR16C
PR14D
PR14C
PR13D
PR13C
PR13B
PR13A
PR12D
PR12C
PR12B
PR12A
PR11D
PR11C
PR11B
PR11A
PR10D
PR10C
PR10B
PR10A
PR7D
PR7C
PR6D
PR6C
PR6B
PR6A
PR5D
PR5C
PR5B
PR5A
PR4B
PR4A
PR4D
PR4C
PR3D
PR3C
PR2D
PR2C
PR2A||R_GPLLT_FB
PR2B||R_GPLLC_FB
PR3A||R_GPLLT_IN
PR3B||R_GPLLC_IN
PR7A
PR7B
PR14A
PR14B
PR16A
PR16B
PR17A||PCLKT1_0
PR17B||PCLKC1_0
PR19A
PR19B
PR20A
PR20B
PR25A
PR25B
PR29A
PR29C
PR29B
PR29D
PR30A
PR30B
R3066
R4088
R4599
R4259
R2452
R2412
Y20
W19
W20
V18
V19
U17
Y21
AA22
U18
U19
W21
Y22
U20
T17
T18
T19
T20
R16
R17
R18
R19
R20
W22
V22
U21
U22
P16
P17
P18
P19
T21
T22
P20
P22
R21
R22
N19
N20
P21
N22
N18
N17
N16
M16
M19
M20
M21
M22
M17
L22
L21
K22
L20
L19
L16
L17
K16
K17
K18
K19
K20
J20
J22
J21
J19
J18
J17
J16
H16
H17
H18
H19
H20
G17
H21
H22
G18
G19
G20
G21
F19
F18
G22
F22
E20
E19
E21
E22
D20
D19
D21
D22
G16
F17
C22
C21
OSC2
U249
VDD OUT
GNDOE
7/7
BANK 1
21R4612
21R4611
21R4610
21R4609
21R4608
21
21
21
21
21
21
21
21
21
2
1 2
1
21R1100
21
21
21
21
CAD NOTE:
4 3
1 2
SHEETDATE
DEPARTMENT
SIZE
PROJECT DOCUMENT NUMBER REV
REVIEWER
DESIGNER
123
7 3 2 1 6 5 4
E
A
B
C
E
D
C
B
A
7 6 5 4
D
IN
IN
BIBI
IN
OUT
OUT
OUT
OUT
IN
OUTOUTINININ
IN
OUT
OUT
INININ
ININ
OUTOUTOUTOUT
OUT
OUTOUT
OUTOUT
OUTOUTOUT
OUTOUT
OUT
BI
OUTOUTOUTOUTOUTOUT
BIBI
BI
BI
IN
BIBI
OUT
OUTIN
INOUT
IN
ININ
OUTIN
IN OUT
IN
OUT
IN OUT
OUT
IN
IN
OUT
OUT
IN OUT
IN
OUT
IN OUT
OUT
IN OUT
IN
IN
OUT
OUT
IN OUT
OUTIN
ININ
IN
IN
IN OUT
ININ
IN
IN
IN
OUT
OUT
ININ
IN
IN
OUTIN
OUTOUTIN
IN
INININ
ININ
ININ
IN
OUT
IN
IN
IN
R1099
C1320
C



20220801 ADD R472320220727 CONNECT TO CPLD.V1720220103 ADD R4563
FORCE_PWRON_JUMPER1-2 ENABLE20220224 ADD JP152-3 DISABLE (DEFAULT)20210902 MODIFY FOR GT
20211130 ADD RES TO FPGAFri Aug 25 14:03:34 2023N/A215 OF 312V05N/AN/AN/A
P3V3_AUXP3V3_AUXP3V3_AUXP3V3_AUX_FPGA_VCCIO2
MAIN FPGA / PFR (3/5)215146227215215215215215215215215215215215215215215215215215215146227146145145146227146144227215146146215215218220215239214
215215184145215204184215246215
215222215215204184296205266222301306215145215215204183198 183190215
215215184204215 219219 2231551612202292231452151911831831842042182202202051822051312151832202222221541611912272312332362452162232812991902052201832012052232152781832232192234343183154205220240205240 220223183215219 223 252206211211215215191151245215306307215146203215239215215215212306307211
183215215219224134
215
228301305183215215215CHIP33.21%GPU_3V3IO_RSVD1_FFU_ISO_RPRSNT_CABLE_GPU_B3_ISO_NPRSNT_CABLE_GPU_A1_ISO_R_NPRSNT_CABLE_GPU_A1_ISO_R_NGPU_3V3IO_RSVD1_ISO_RGPU_3V3IO_RSVD5_FFU_ISO_RPRSNT_CABLE_GPU_A2_ISO_R_NGPU_3V3IO_RSVD3_ISO_RGPU_3V3IO_RSVD4_ISO_RCHIPGPU_3V3IO_RSVD1_ISO_RPRSNT_SWB_ISO_R_NGPU_3V3IO_RSVD0_FFU_ISO_RPRSNT_CABLE_GPU_B3_ISO_R_NGPU_3V3IO_RSVD3_FFU_ISO_RPRSNT_CABLE_GPU_A2_ISO_R_NGPU_3V3IO_RSVD5_FFU_ISO_R1%33.2GPU_3V3IO_RSVD3_FFU_ISO_RPRSNT_CABLE_GPU_B3_ISO_R_NGPU_3V3IO_RSVD1_FFU_ISO_RGPU_3V3IO_RSVD0_FFU_ISO_RNC_FPGA_PB22BPRSNT_CABLE_GPU_A1_ISO_NGPU_3V3IO_RSVD5_FFU_ISOGPU_3V3IO_RSVD1_ISOGPU_3V3IO_RSVD3_ISOPRSNT_CABLE_GPU_A2_ISO_NGPU_3V3IO_RSVD3_FFU_ISOCHIP1%PRSNT_SWB_ISO_NPRSNT_SWB_ISO_R_NGPU_3V3IO_RSVD0_FFU_ISOGPU_3V3IO_RSVD1_FFU_ISO33.2 CHIPHSC_D_OC_R1FM_FORCE_PWRON_LVC3FM_PLD_HEARTBEAT_LVC3FM_DEBUG_PORT_PRSNT_NJTAG_DBP_BMC_PRDY_R_NCLK_25M_OSC_MAIN_FPGA0CHIPCHIPFM_DEBUG_PORT_PRSNT_NFM_PCH_BMC_RST_NFM_PCH_BMC_RST_R_N1%CHIPGPU_3V3IO_RSVD4_ISO5%CHIP33.2FM_PDB_BUF_ENFM_DEBUG_PORT_PRSNT_R_NFM_REMOTE_DEBUG_DETHPDB_HSC_PWRGD_ISOGPU_3V3IO_RSVD3_ISO_R
0402LFPD_FORCE_PWRONFM_FORCE_PWRON_LVC3ICLCMXO3LF-9400C-5BG484CSMLF10K1%1/16WEMPTY0402LFIRQ_BMC_CPU_NMI_R1RST_SGPIO_RESET_N_RIRQ_PSU_ALERT_R_NIRQ_PCH_SCI_WHEA_R_NIRQ_TPM_SPI_NIRQ_PVCCD_CPU1_VRHOT_LVC3_NIRQ_PCH_CPU_NMI_EVENT_NIRQ_PSYS_CRIT_NIRQ_SGPIO_INTR_N_R5%CHIP33.21%33.2CHIP1%33.21%HSC_D_OC1%CHIPCHIP1%CHIP1%1%CHIPHGX_DETECT_N_RHGX_DETECT_NHPDB_HSC_PWRGD_ISO_R0CHIP5%0 005%1/16W05%IRQ_PSU_ALERT_R_NIRQ_PCH_SCI_WHEA_NFM_ADR_ACK1%CHIPRST_PCIE_PCH_DEV_PERST_M2_R_N1%FM_ADR_ACK_R
FM_UV_ADR_TRIGGER_R_NFM_ADR_ACK_RPU_FORCE_PWRONCHIP1/16W1K0402LF1%1%10K1/16WCHIPIOFM_ME_BT_DONERST_PCIE_PCH_DEV_PERST_NNC_FPGA_PB32DRST_PLTRST_PLD_B_NFM_SYS_THROTTLE_R_NFM_SPD_REMOTE_EN_RRST_PLTRST_PLD_N1%CHIPCHIPCHIP1%33.2SWB_HSC_EN5%1/16W
THLFHSC_D_OC_R1E1S_0_PRSNT_NUSB_OC1_REAR_NFM_ME_AUTHN_FAILFM_CPU_RMCA_CATERR_LVT3_R_NFM_RST_PERST_BIT2FM_PS_PWROK_DLY_SELFM_BMC_RSTBTN_OUT_NFM_BIOS_POST_CMPLT_BMC_NFM_BMC_DBP_PRESENT_R_NFM_REMOTE_DEBUG_DETFM_PCH_CRASHLOG_TRIG_R_NFM_DIS_PS_PWROK_DLYRST_PFR_OVR_SRTC_RRST_PFR_OVR_RTC_RRST_SMB_SWITCH_NRST_MB_STBY_R_NFM_HBM2_HBM3_VPP_SELPCIE_M2_SSD0_PRSNT_NFM_ADR_TRIGGER_NFM_ADR_COMPLETEFM_ADR_MODE0_RFM_ADR_MODE1_RIRQ_UV_DETECT_R_NNC_FPGA_PB7DIRQ_PVCCD_CPU0_VRHOT_LVC3_NIRQ_BMC_PCH_NMI_RFM_PLD_CLKS_DEV_R_ENFM_PLD_CLK_25M_R_ENPWRGD_PLT_AUX_CPU0_LVT3_RPWRGD_PLT_AUX_CPU1_LVT3_RFM_BIOS_DEBUG_EN_NFM_NCSI_OCP_V3_1_R_OEFM_THROTTLE_R_NFM_DIMM_12V_CPS_SX_NVIRTUAL_RESEATFM_PCH_PLD_GLB_RST_WARN_NROT_P1_RST_IND_N_RFM_SLPS3_PLD_NFM_PCHHOT_R_NFM_BMC_READY_R_PLD_NRST_RSMRST_PLD_R_NNC_FPGA_PB35BCONN3_210-HP1-030BR1CLK_SWB_OE_NCLK_GPU_2_OE_NCLK_GPU_1_OE_NIRQ_UV_DETECT_R_NFM_UV_ADR_TRIGGER_R_N5%RST_PCIE_PCH_DEV_PERST_E1S_R_N1/16W0402LF1%CHIP49.9040225V10%X7R0.1UF1/16W1%CHIP0402LF10K
0402LF33.25%CHIP00FM_PDB_BUF_EN_R33.2CHIPCHIPCHIPIRQ_PCH_SCI_WHEA_R_NIRQ_UV_DETECT_NSWB_HSC_PWRGD_ISO_RSWB_HSC_PWRGD_ISOCHIP0402LF1/16W
FM_PCH_BMC_THERMTRIP_NSWB_HSC_PWRGD_ISO_R33.233.233.233.2CHIP
JTAG_DBP_BMC_PREQ_R_N
5%0CHIPSWB_HSC_EN_RHPDB_HSC_PWRGD_ISO_RHGX_DETECT_N_RNC_FPGA_PB43DCLK_GEN2_BMC_RC_OE_NFM_UV_ADR_TRIGGER_NCLK_SWB_BUF2_OE_NFM_PLD_REV_NFM_PLD_REV_R_N0402LFCHIP1/16W10K1%
FM_BMC_READY_R_N
PULL_FPGA_PB46ANC_FPGA_PB46BFM_PDB_BUF_ENRST_PCIE_PCH_DEV_PERST_NFM_AC_PWR_BTN_PLD_ISO_N33.2CHIP33.2FM_REMOTE_DEBUG_DET_R
FM_PCH_BMC_RST_N33.233.2IRQ_SML1_PMBUS_ALERT_NFM_BMC_READY_R_PLD_NSWB_HSC_EN_R5%0GPU_3V3IO_RSVD4_ISO_RCHIP1%1%1%
R2348
R2347
R2792
R2155
R3049
R1944
R3046
R3045
R4056
R4057
R700
R4563
R4558
R4557
R4556
R4175
R4174
R1710
R1106
R1465
3
2
1
T16
V17
AA21
AB21
W18
Y19
AA20
AB20
U16
T15
AA19
AB19
W17
Y18
AA18
AB18
V16
Y17
AA17
AB17
U15
V15
AA16
AB16
W15
Y15
AA15
AB15
W14
Y14
AA14
AB14
V14
U14
T14
T13
W13
Y13
AA13
AB13
U13
V13
AA12
AB12
V12
U12
T12
Y12
Y11
V11
AB11
AA11
U11
T11
AB10
AA10
Y10
Y9
W10
V10
U10
T10
AB9
AA9
W9
Y8
AB8
AA8
W8
V9
U9
T9
U8
V8
AB7
AA7
V7
W6
AB6
AA6
Y6
Y5
AB5
AA5
T8
U7
AB4
AA4
W5
Y4
AB3
AA3
U6
V6
AB2
AA2
JP15
U249
1
2
3
2/7
BANK 2
PB21D
PB21C
PB46D
PB46C
PB44D
PB44C
PB43D
PB43C
PB41D
PB41C
PB41B
PB41A
PB40D
PB40C
PB40B
PB40A
PB38D
PB38C
PB38B
PB38A
PB35D
PB35C
PB32D
PB32C
PB32B
PB32A
PB33D
PB33C
PB30D
PB30C
PB29D
PB29C
PB27D
PB27C
PB27B
PB27A
PB22D
PB22C
PB19D
PB19C
PB19B
PB19A
PB18D
PB18C
PB16D
PB16C
PB13B
PB13A
PB11D
PB11C
PB11B
PB11A
PB35B
PB35A
PB46B||SI||SISPI
PB46A||SN
PB44B
PB44A
PB43B
PB43A
PB33B
PB33A
PB30B
PB30A
PB29B||PCLKC2_1
PB29A||PCLKT2_1
PB24D
PB24C
PB24B
PB24A
PB22B||PCLKC2_0
PB22A||PCLKT2_0
PB21B
PB21A
PB18B
PB18A
PB16B||SO||SPISO
PB16A||MCLK||CCLK
PB13D
PB13C
PB10D
PB10C
PB10B
PB10A
PB8B
PB8A
PB8D
PB8C
PB7D
PB7C
PB7B
PB7A||CSSPIN
PB5D
PB5C
PB5B
PB5A
21
21R4723
2
1
2
1
21
21
21
21
21
21
21
21
21
21
21
21
21
21
21
21R4172
21R4171
21R4170
21R4157
21R4147
21R4148
21R4146
21R4145
21R4144
21R4143
2
1
21
2
1C1325
21 2
1
2
1
SHEETDATE
DEPARTMENT
SIZE
PROJECT DOCUMENT NUMBER REV
REVIEWER
DESIGNER
123
7 3 2 1 6 5 4
E
A
B
C
E
D
C
B
A
7 6 5 4
D
IN
OUT
OUT
IN OUT
OUTIN
OUT
IN
IN
IN OUT
OUT
IN
IN
INININOUTOUTINOUTININ
OUT
OUTIN
OUTIN
ININ
OUTIN
INOUT
IN
OUTOUT
INOUTINOUTOUTOUTOUTOUTIN
INOUTOUT
ININ
INOUT
OUTOUT
OUTOUTINOUTINININININININ
IN
OUTIN
IN
OUTOUT
OUT
IN
IN
OUT
IN
IN OUT
OUT
IN
OUT
IN
OUT
OUT
OUT
IN
IN
OUT
OUT
OUT
IN
OUT
OUT
IN
IN
OUT IN
OUT
OUT IN
OUT
OUT
IN
IN OUT
IN OUT
IN
OUT
OUTOUT
OUT
OUT
IN
IN
IN
ININ
IN
IN
IN
OUT
OUT
OUT
OUT
IN
IN OUT
ININ
IN
IN
INININ
OUT
OUT
IN
IN
IN
IN
R1493
R1495
R4086
C



20210902 MODIFY FOR GT
Fri Aug 25 14:03:35 2023N/A216 OF 312N/AN/AN/A V05
P3V3_AUX
P3V3_AUXMAIN FPGA / PFR (4/5)158164242 216192193216216216
225225225123123121121226255216216125219125219125219125219195195195195195195124219124219124219125219130256124219122122123226124219125219124219130256130256130256129256129256129256225225225225225225225225129256223215195195122122121121226223220221221221221221162156216191183216HP_LVC3_OCP_V3_1_PWRGD_RHP_LVC3_OCP_V3_2_PWRGD_R33.2HP_LVC3_SCM_HSC_PWRGD1%CHIPHP_LVC3_SCM_HSC_PWRGD_PLDLCMXO3LF-9400C-5BG484CSMLFHP_LVC3_E1S_0_HSC_PWRGDCHIP1%ICHP_LVC3_OCP_V3_1_FUSE_PWRGDHP_LVC3_E1S_0_HSC_PWRGD_PLDCHIP1%33.2HP_LVC3_OCP_V3_2_FUSE_PWRGD
H_CPU_ERR0_LVC2_NH_CPU_ERR1_LVC2_NH_CPU_ERR2_LVC2_NH_CPU0_MEMTRIP_LVC1_NH_CPU1_MEMTRIP_LVC1_NH_CPU0_THERMTRIP_LVC1_NH_CPU1_THERMTRIP_LVC1_NPWRGD_CPUPWRGD_LVC2_R1HP_LVC3_OCP_V3_1_FUSE_PWRGDHP_LVC3_OCP_V3_2_FUSE_PWRGD1%
PWRGD_DRAMPWRGD_CPU1_AB_R_LVC1PWRGD_DRAMPWRGD_CPU1_CD_R_LVC1PWRGD_DRAMPWRGD_CPU1_EF_R_LVC1PWRGD_DRAMPWRGD_CPU1_GH_R_LVC1FM_BOARD_BMC_SKU_ID4FM_BOARD_BMC_SKU_ID3FM_BOARD_BMC_SKU_ID2FM_BOARD_BMC_SKU_ID1FM_BOARD_BMC_SKU_ID0FAB_BMC_REV_ID2PWRGD_DRAMPWRGD_CPU0_GH_R_LVC1PWRGD_DRAMPWRGD_CPU0_CD_R_LVC1PWRGD_DRAMPWRGD_CPU0_EF_R_LVC1PWRGD_CPU1_LVC1_RRST_PLD_CPU1_DRAM_GH_NPWRGD_DRAMPWRGD_CPU0_AB_R_LVC1H_CPU0_MEMHOT_OUT_LVC1_NH_CPU1_MEMHOT_OUT_LVC1_NH_CPU_NMI_LVC1_R_NH_CPU_RMCA_LVC2_R2_NRST_CPU0_LVC1_R_NRST_CPU1_LVC1_R_NPWRGD_CPU0_LVC1_RRST_PLD_CPU1_DRAM_EF_NRST_PLD_CPU1_DRAM_CD_NRST_PLD_CPU1_DRAM_AB_NRST_PLD_CPU0_DRAM_GH_NRST_PLD_CPU0_DRAM_EF_NRST_PLD_CPU0_DRAM_CD_NRST_CPU1_DRAM_GH_PLD_LVT3_NRST_CPU1_DRAM_EF_PLD_LVT3_NRST_CPU1_DRAM_CD_PLD_LVT3_NRST_CPU1_DRAM_AB_PLD_LVT3_NRST_CPU0_DRAM_GH_PLD_LVT3_NRST_CPU0_DRAM_EF_PLD_LVT3_NRST_CPU0_DRAM_CD_PLD_LVT3_NRST_CPU0_DRAM_AB_PLD_LVT3_NRST_PLD_CPU0_DRAM_AB_NIC 1/16WCHIP0402LF1%1KBIT0/1/2PERST FROM CPUPWRGDPERST FROM PLTRST_N (DEFAULT)SMLFLCMXO3LF-9400C-5BG484CRST_MB_STBY_R_NFAB_BMC_REV_ID1FAB_BMC_REV_ID0H_CPU0_MEMHOT_IN_LVC1_R_NH_CPU1_MEMHOT_IN_LVC1_R_NH_CPU0_PROCHOT_LVC1_R_NH_CPU1_PROCHOT_LVC1_R_NH_CPU_CATERR_LVC2_R2_NFM_THERMTRIP_DLY_LVC1_R_N1/16W10K0402LFJTAG_PLD_TDO_RJTAG_PLD_TDI_RJTAG_PLD_TCK_RNC_FPGA_PT44DJTAG_PLD_JTAGENJTAG_PLD_TMS_RHP_LVC3_OCP_V3_2_PRSNT2_PLD_NHP_LVC3_OCP_V3_1_PRSNT2_PLD_NCHIP33.2NC_FPGA_PT44CPU_FPGA_D12_PROGRAMNCHIP33.21%HP_LVC3_E1S_0_HSC_PWRGD_PLDHP_E1S_0_P3V3_PWRGD_PLDE1S_0_CLK_OE_NHP_LVC3_SCM_HSC_PWRGD_PLD
R4765
R4760
R4751
E17
F16
E15
E14
C10
D10
E9
E8
T7
V5
W4
Y3
Y2
W3
AA1
Y1
U5
V4
W2
W1
U4
U3
V1
U2
T6
T5
T4
T3
R7
R6
U1
T2
P7
R5
R4
R3
P6
P5
T1
R2
N7
N6
N5
P4
M7
P3
R1
P2
N4
N3
P1
N2
M5
M6
N1
M1
L4
L3
M2
L1
L5
L6
K1
K2
K3
K4
K5
L7
K6
K7
J1
J2
J3
J4
J5
H5
J6
J7
H1
H2
H3
H4
G1
G2
G4
G3
F1
E1
F4
E3
E2
D1
H6
G5
D2
C1
H7
G6
F5
E4
G7
F6
D4
D3
U249
U249
4/7
BANK 0
PT31C||JTAGENB
PT44D||DONE
PT44C||INITN
PT31D||PROGRAMN
PT22D||TMS
PT22C||TCK
PT15D||TDI
PT15C||TDO
1/7
BANK 5
BANK 4
BANK 3
PL12D
PL12C
PL12B
PL12A
PL11D
PL11C
PL11B
PL11A
PL10D
PL10C
PL10B
PL10A
PL7D
PL7C
PL7B||PCLKC5_0
PL7A||PCLKT5_0
PL30D
PL30C
PL30B
PL30A
PL29D
PL29C
PL29B
PL29A
PL28D
PL28C
PL28B
PL28A
PL27D
PL27C
PL27B||PCLKC3_0
PL27A||PCLKT3_0
PL19D
PL19C
PL19B
PL19A
PL18D
PL18C
PL18B
PL18A
PL17D
PL17C
PL17B
PL17A
PL26B
PL26A
PL25D
PL25C
PL24D
PL24C
PL24B
PL24A
PL25B
PL25A
PL6B
PL6A
PL6D
PL6C
PL16D
PL16C
PL14D
PL14C
PL26D
PL26C
PL21D
PL21C
PL21B
PL21A
PL20D
PL20C
PL20B
PL20A
PL16B||PCLKC4_0
PL16A||PCLKT4_0
PL14B
PL14A
PL13D
PL13C
PL13B
PL13A
PL5D
PL5C
PL5B
PL5A
PL4D
PL4C
PL4B||L_GPLLC_IN
PL4A||L_GPLLT_IN
PL3D
PL3C
PL3B||L_GPLLC_FB
PL3A||L_GPLLT_FB
PL2D
PL2C
PL2B
PL2A
21R4771
21
21
21
2
1
2
1
DESIGN NOTE:
SHEETDATE
DEPARTMENT
SIZE
PROJECT DOCUMENT NUMBER REV
REVIEWER
DESIGNER
123
7 3 2 1 6 5 4
E
A
B
C
E
D
C
B
A
7 6 5 4
D
IN
OUTIN
OUTININ
IN
OUT
OUT
IN OUT
IN
ININ
IN
OUTIN
OUT
ININININ
ININ
ININ
OUT
ININ
IN
ININININ
ININ
INININ
OUTINININ
OUT
OUTOUT
OUT
OUTOUTOUTOUT
INININININ
ININ
OUT
OUTOUTOUT
INOUTOUTINOUT
OUTOUT
OUT
OUT
OUTOUT
OUTOUT
OUT
R3249
R1823
C



20210902 MODIFY FOR GT120OHM
Fri Aug 25 14:03:37 2023N/AN/AN/AN/AV05217 OF 312
VCC_PLD_COREP3V3_AUXP3V3_AUX_FPGA_VCCIO0P3V3_AUXP3V3_AUX_FPGA_VCCIO1P3V3_AUXP3V3_AUXP3V3_AUX_FPGA_VCCIO2P3V3_AUX_FPGA_VCCIO5P3V3_AUXP3V3_AUX_FPGA_VCCIO3P3V3_AUXP3V3_AUX_FPGA_VCCIO4P3V3_AUX
P3V3_AUX_FPGA_VCCIO1P3V3_AUX_FPGA_VCCIO5VCC_PLD_COREP3V3_AUX_FPGA_VCCIO0P3V3_AUX_FPGA_VCCIO4P3V3_AUX_FPGA_VCCIO3P3V3_AUX_FPGA_VCCIO2
MAIN FPGA / PFR (5/5)
1X7R50V0.01UFC04020.01UF0.01UFCHIP1/10W0603LF1%1C040210UF6.3V20%X6SX7R10%25V0.1UF04020.01UF50V10%X7RC040210%0.01UF50VX7RC04020.01UF50VX7R10%0.1UF10%25VX7R040250V10%X7RC04020.01UF 0.01UFX7RC040210%50V 50V10%C0402X7R10%X7R50VC04020.01UFX7R10%50VC04020.01UF50V10%X7RC04020.01UF50V10%X7RC04020.1UFX7R25V10%04020.01UFC040250VX7R10%C040250VX7R10%0.01UFC040250VX7R10%0.01UF0.01UFC040210%X7R50VC0402X7R10%50V0.01UF10%0402X7R0.1UF25VC040250VX7R10%0.01UFC040210%C040250VX7R10%0.01UF10%0.1UF25VX7R040210UF20%6.3VX6SC040211%1/10WCHIP0603LF0.01UF6.3V10UF20%C0402X6S1%CHIP0603LF 1/10W10%0.1UF25VX7R0402C040210%0.01UF50VX7RX7R10%50V0.01UFC04020.01UF10%X7R50VC04020.1UF040225V10%X7R0.01UF10%X7R50VC040210%50VC04020.01UFX7R0.01UF10%X7RC040250V10%50VC0402X7R0.01UF10%X7R50VC0402CHIPX7R040210%25V0.1UF10%50V0.01UFC0402X7R X7R0.01UF10%C040250V0.01UFC040210%50VX7R11/10W0603LF1%25V0.1UF10%X7R04020.01UF50VC0402X7R10%0.01UFX7R50VC040210%0.01UF10%X7R50VC040250VC0402X7R10%0.01UF10%X7RC040250V0.01UFC040210UF6.3V20%X6S10603LF 1/10W1%CHIP6.3V20%X6SC040210UF25V0.1UF10%X7R04020.01UF50V10%X7RC0402C0402X7R10%0.01UF50V 50V10%C04020.01UFX7R0603LF1%CHIP11/10W10UFX6S20%C04026.3V0402X7R10%25V0.1UFX7R0.01UF10%C040250VC04020.01UF50V10%X7RC04020.01UFX7R50V10%0603LF1%11/10WCHIP6.3V10UFC040220%X6S040225V0.1UFX7R10%10%C040250V0.01UFX7RC04020.01UF50V10%X7R X7RC040250V0.01UF10%
LCMXO3LF-9400C-5BG484CSMLFICLCMXO3LF-9400C-5BG484CICSMLF
C1113 C1118
2
1
2
1
2
1
2
1
R3458
C1124
C1908 C1893 C1899
C1909 C1894 C1900
C1913
2
1
2
1
2
1
2
1
2
1
2
1
2
1
2
1
2
1
2
1
2
1
C1914 C1917 C1926 C1929
C1898 C1904
2
1
2
1
C1932
K8
J8
F3
M3
M8
L8
V3
P8
N8
W16
W11
W7
R14
R13
R12
R11
R10
R9
V20
P15
N15
M18
M15
L15
K15
J15
F20
H14
H12
H11
H9
G13
G10
C16
C12
C7
N13
N12
N11
N10
M12
M11
L12
L11
K13
K12
K11
K10
AB22
AB1
Y16
Y7
W12
V21
V2
R15
R8
P14
P13
P12
P11
P10
P9
N21
N14
N9
M14
M13
M10
M9
M4
L18
L14
L13
L10
L9
L2
K21
K14
K9
J14
J13
J12
J11
J10
J9
H15
H13
H10
H8
F21
F2
E18
E5
C11
C2
B16
B7
A22
A1
U249
U249
5/7
VCCIO0_5
VCCIO0_6
VCCIO0_9
VCCIO0_8
VCCIO0_7
VCCIO0_4
VCCIO0_3
VCCIO0_2
VCCIO0_1
VCCIO1_9
VCCIO1_8
VCCIO1_7
VCCIO1_6
VCCIO1_5
VCCIO1_4
VCCIO1_3
VCCIO1_2
VCCIO1_1
VCCIO2_9
VCCIO2_8
VCCIO2_7
VCCIO2_6
VCCIO2_5
VCCIO2_4
VCCIO2_3
VCCIO2_2
VCCIO2_1
VCCIO3_3
VCCIO3_2
VCCIO3_1
VCCIO4_3
VCCIO4_2
VCCIO4_1
VCCIO5_3
VCCIO5_2
VCCIO5_1
VCC12
VCC11
VCC10
VCC9
VCC8
VCC7
VCC6
VCC5
VCC4
VCC3
VCC2
VCC1
6/7
GND52
GND51
GND49
GND50
GND48
GND47
GND46
GND45
GND44
GND43
GND42
GND41
GND40
GND39
GND38
GND37
GND36
GND35
GND34
GND33
GND32
GND31
GND30
GND29
GND28
GND27
GND26
GND25
GND24
GND23
GND22
GND21
GND20
GND19
GND18
GND17
GND16
GND15
GND14
GND13
GND12
GND11
GND10
GND9
GND8
GND7
GND6
GND5
GND4
GND3
GND2
GND1
2
1
2
1
21
2
1
2
1
2
1
2
1
2
1
2
1
2
1
2
1
2
1
2
1
2
1
2
1
2
1
2
1
2
1
2
1C1945
2
1
2
1
2
1
2
1
2
1
2
1
2
1
2
1C1127 C1133 C1138 C1142
2
1C1911 C1896 C1902
2
1
C1910 C1895 C1901
2
1
2
1C1915 C1918 C1927 C1930
2
1
2
1
2
1
2
1
2
1
2
1
2
1
2
1
2
1
2
1
2
1
2
1
2
1
C1146
C1933
2
1
2
1
SHEETDATE
DEPARTMENT
SIZE
PROJECT DOCUMENT NUMBER REV
REVIEWER
DESIGNER
123
7 3 2 1 6 5 4
E
A
B
C
E
D
C
B
A
7 6 5 4
D
C1150 C1934
R3344
C1842 C1941 C1935
R3345
C1942
R3347
C1937 C1944
R3348
C1939 C1946
C1938
R3346
R3349
C1122
C1940 C1947
C1906
C1905
C1936 C1943 C1912 C1897 C1903 C1907 C1916 C1919 C1928 C1931 C1152 C1154
C



20210902 MODIFY FOR GT20220119 CHANGE TO BLUE LED20220119 CHANGE TO YELLOW LEDFri Aug 25 14:03:39 2023N/AN/AN/A218 OF 312V05N/A
I236P3V3_AUXP3V3_AUX
P3V3_AUXMAIN FPGA / PFR - LEDS
215220
2152201%1/16WLED_CPU_RMCA_CATERRLED_YELLOWLTST-C190KSKT-PIC
LED_BLUECHIP 1/16WPU_PLD_HEARTBEAT_LVC3FM_PLD_HEARTBEAT_LVC3FM_PLD_HEARTBEAT_LVC3_DSMLF
LED_CPU_RMCA_CATERR_R
0402LFLTST-C281TBKT-5ABSS138KSMLFCPU_RMCA_CATERR_LVT3_N5%CHIPSMLF
IC
221/16WFM_CPU_RMCA_CATERR_LVT3_R_N0402LFCHIP10K1%1/16W00402LF 1/16WCHIP5%IC
IC1%130
2N7002K0402LFCHIP0402LF249
G
S D
R1841
R1195
R365
R2339
G
S D
CA
CA
G
S D
D6
D0
Q33
U89
A C
A C
S
G
D
2
1
R366
21
2
1
21
21
SHEETDATE
DEPARTMENT
SIZE
PROJECT DOCUMENT NUMBER REV
REVIEWER
DESIGNER
123
7 3 2 1 6 5 4
E
A
B
C
E
D
C
B
A
7 6 5 4
D
IN
IN
C



20210902 MODIFY FOR GT
Fri Aug 25 14:03:40 2023V05219 OF 312N/AN/AN/AN/AMAIN FPGA / PFR - PU/PD1%215223215223252214223216124216124216124216124215214223214223214216124216125216125216125214222214222214222216125216124215223216125214278214296214222214222214263222182222182240216125214222214222214222
2K1%RST_PLTRST_PLD_B_NRST_RSMRST_PLD_R_NRST_PERST_SWB_N2KCHIP1%PWRGD_DRAMPWRGD_CPU0_AB_R_LVC1PWRGD_DRAMPWRGD_CPU0_CD_R_LVC1PWRGD_DRAMPWRGD_CPU0_EF_R_LVC1PWRGD_DRAMPWRGD_CPU0_GH_R_LVC1EMPTYRST_PCIE_PCH_DEV_PERST_NRST_PCIE_CPU1_DEV_PERST_NRST_PCIE_CPU0_DEV_PERST_N2KCHIP1%FM_AUX_SW_ENRST_CPU0_LVC1_R_NRST_CPU1_LVC1_R_NPWRGD_DRAMPWRGD_CPU1_AB_R_LVC1PWRGD_DRAMPWRGD_CPU1_GH_R_LVC12K1/16W2K1%EMPTYEMPTYCHIP1%FM_PVCCFA_EHV_FIVRA_CPU0_R_ENFM_PVCCFA_EHV_FIVRA_CPU1_R_ENFM_PVCCFA_EHV_CPU0_R_ENPWRGD_DRAMPWRGD_CPU1_EF_R_LVC12K2K2KPWRGD_CPU0_LVC1_RFM_PLD_CLK_25M_R_EN1%EMPTYEMPTYEMPTYEMPTYEMPTYEMPTYEMPTY1%1%2K2K2K1%2K1%2K2K1%1%1%1/16W0402LFCHIPEMPTYEMPTY1%2K0402LF2K2K1%2K1%PWRGD_DRAMPWRGD_CPU1_CD_R_LVC1FM_PVCCD_HV_CPU0_ENCHIP2K1%FM_PVCCD_HV_CPU1_EN2KCHIP1%1%CHIP2KFM_PVCCIN_CPU1_R_ENCHIP1%2KFM_PVCCIN_CPU0_R_ENCHIP2K1%FM_PCH_P1V8_AUX_EN1%2KCHIPPWRGD_PCH_PWROK2KCHIPPWRGD_SYS_PWROKPWRGD_CPU1_LVC1_RCHIP1%CHIPCHIP2K1%CHIP2K1%FM_PVCCFA_EHV_CPU1_R_EN1%2KCHIPFM_PVCCINFAON_CPU1_R_ENCHIP1%2KFM_PVCCINFAON_CPU0_R_ENCHIP2K1%
1%CHIPCHIP2K1%2K1%2KCHIP1%
21R4622
21R1413
21R1414
21R1412
21R1411
21R1409
21R1410
21R1408
21R1407
21R1406
21R1405
21R1404
21R1403
21R1402
21R1398
21R992
21R991
21
21R990
21
21
21
21
21
21
21
21R1421
21R1420
21R1419
21R1417
21R1418
21R1416
21R1415
R4533
R1388
R1330
R1329
R1327
R1328
R1302
R1326
SHEETDATE
DEPARTMENT
SIZE
PROJECT DOCUMENT NUMBER REV
REVIEWER
DESIGNER
123
7 3 2 1 6 5 4
E
A
B
C
E
D
C
B
A
7 6 5 4
D
IN
IN
IN
IN
IN
IN
IN
IN
IN
IN
IN
IN
IN
IN
IN
IN
IN
IN
IN
IN
IN
IN
IN
IN
IN
IN
IN
IN
IN
IN
IN
IN
IN
C



20220504 DEPOP R139
20210902 MODIFY FOR GT
2020518 DEPOP R1660,ADD R46742020624 DEPOP R1494,ADD R1492Fri Aug 25 14:03:41 2023N/AN/A220 OF 312V05N/AN/A
P3V3_AUXP3V3_AUXP3V3_AUX
MAIN FPGA / PFR - MISC/PU/PD
215218215155161205215214214214244215
214222255214222255215215218182213213216221215240215223182FM_CPU_RMCA_CATERR_LVT3_R_N1%EMPTY0402LF1%CHIP10K1/16WCHIP1%10K10KCHIP1%10K1%EMPTYEMPTY1%10KCHIP1%10KCHIP1%1K1K1%CHIP1%1K1%10K1%10K1%10K1%CHIPCHIP10K1%10K1/16WCHIP0402LF10K1%1%1/16W0402LFEMPTY1K
5%NPO5%
FM_SYS_THROTTLE_R_NFM_ADR_TRIGGER_NFM_RST_PERST_BIT0FM_RST_PERST_BIT1FM_PFR_DSW_PWROK_NFM_DIMM_12V_CPS_SX_N
PWRGD_PCH_PWROK_RPWRGD_SYS_PWROK_R100PF100PF1%10K1%EMPTY040250VPLACE THE 100PF CAPS FOR SI AND CLOSE TO MAIN PLDEMPTYFM_RST_PERST_BIT2FM_PLD_HEARTBEAT_LVC3FM_SLP_SUS_RSM_RST_NPU_MAIN_FPGA_CONFIG_DONEJTAG_PLD_TDO_R10KFM_DIS_PS_PWROK_DLY1K10K1%10K1%1/16WCHIP0402LFEMPTYEMPTYEMPTYCHIPCHIPROT_P1_RST_IND_N_RFM_BMC_PWRBTN_N
C1211
C1209
R1434
R1435
R1437
R1440
R139
R2244
R1741
R1473
R1474
R1492
R1742
R1308
R1312
R1494
R1399
R1401
R1558
R1660
2
1
21
21
21
21
21
21
21
21
21
21
21
21
21
21
21
21
21
21
2
1
2
1
21
21
CAD NOTE:
SHEETDATE
DEPARTMENT
SIZE
PROJECT DOCUMENT NUMBER REV
REVIEWER
DESIGNER
123
7 3 2 1 6 5 4
E
A
B
C
E
D
C
B
A
7 6 5 4
D
IN
IN
IN
IN
IN
IN
IN
IN
IN
IN
IN
IN
IN
IN
IN
OUT
IN
R4674
R735
R736
C



20210902 MODIFY FOR GT
FOR FPGA PROGRAMMING
JTAG
Fri Aug 25 14:03:42 2023N/AN/AN/AV05221 OF 312N/A
P3V3_AUXP3V3_AUXP3V3_AUX
MAIN FPGA / PFR - JTAG2212392392212212392212392162162202162162212392212392212392212392161/16WCHIP1/16WTP_PLD_CONN_P4JTAG_BMC_PLD_TDOJTAG_BMC_PLD_TDITP_PLD_CONN_P5JTAG_BMC_PLD_TMSJTAG_BMC_PLD_TCKCONN8_210-HP1-080BR1CHIP1%10K4.7K1/16WCHIPCHIP33.20402LF1%CHIP0402LF10K1/16W10K0402LF1%1/16WCHIP1%1/16W0402LFCHIP0402LF1/16W
1/16W1K1%1%CHIP33.21%JTAG_PLD_TCK_R1/16W0402LF33.21%JTAG_PLD_TDO_RCHIP0402LF1/16W33.21%JTAG_PLD_TMS_R0402LF1%JTAG_PLD_TDI_R JTAG_BMC_PLD_TDIJTAG_BMC_PLD_TMSEMPTYJTAG_BMC_PLD_TCKJTAG_BMC_PLD_TDO10KJTAG_PLD_JTAGEN0402LFTHLFIO0402LFX6S10%25VC080510UF040210%X7RSMLF25V0.1UFP3V3_AUX_BMC_D1N5819HWIC
21
8
7
6
5
4
3
2
1
D141
J43
CA
8
7
6
5
4
3
2
1
2
1
2
1
2
1
2
1
2
1
2
1
2
1
2
1
21
21
21
21
R806
R805
R804
R803
SHEETDATE
DEPARTMENT
SIZE
PROJECT DOCUMENT NUMBER REV
REVIEWER
DESIGNER
123
7 3 2 1 6 5 4
E
A
B
C
E
D
C
B
A
7 6 5 4
D
OUT
OUT
IN
OUT
OUT
IN
IN
OUT OUT
OUT OUT
OUT
OUT
C563
R920
R919
R930
R927 R928 R929
C554
C



SGPIO#1PWRGDSGPIO#020210902 MODIFY FOR GT
SKTOCCRTC & SRTC20211201 ADD RES TO PDBFri Aug 25 14:03:43 2023N/AN/AN/AN/AV05222 OF 312MAIN FPGA / PFR - SI (1/2)1413345133259244258214220255118226182219185215185215240240
263194252284284214219266214219274214219274214219240240240182219 240292214219292214219266214219
213214214220255214214246214219240240213213213215215240240213213213240213213
FM_CPU0_SKTOCC_LVT3_NFM_CPU1_SKTOCC_LVT3_N1/16WPWRGD_P3V3_AUXCHIPPWRGD_SYS_PWROK_RPWRGD_CPUPWRGD_LVC1_RPWRGD_CPUPWRGD_LVC133.21/16WCHIP0402LF1%PWRGD_PCH_PWROK1% RST_PFR_OVR_SRTCRST_PFR_OVR_SRTC_RCHIP33.21%0402LF 1/16WRST_PFR_OVR_RTCRST_PFR_OVR_RTC_RCHIP1%0402LF 1/16W33.21%33.2 CHIP0402LFCHIP33.21/16W0402LF1%SGPIO_DI_11%33.21/16W0402LFCHIP1%33.20402LFCHIPSGPIO_DO_00402LF 1/16W33.21%CHIP
CHIP0402LF1%33.2CHIP0402LF1%33.21/16WPWRGD_P1V8_PCH_AUX0402LF1%33.2CHIP 1/16WFM_PVCCFA_EHV_FIVRA_CPU1_EN1/16WCHIP0402LF33.21%FM_PVCCIN_CPU1_ENFM_PVCCIN_CPU1_R_EN1/16WCHIP0402LF33.21%FM_PVCCFA_EHV_FIVRA_CPU0_ENFM_PVCCFA_EHV_FIVRA_CPU0_R_ENCHIP0402LF1/16W33.21%FM_PVCCINFAON_CPU0_ENFM_PVCCINFAON_CPU0_R_EN0402LFCHIP 1/16W33.21%FM_PVCCFA_EHV_CPU0_ENFM_PVCCFA_EHV_CPU0_R_EN1/16WCHIP0402LF33.21%33.21/16W0402LFCHIPSGPIO_LD_1CHIP0402LF33.21%0402LF 1/16W1%33.2 CHIPSGPIO_DI_00402LF 1/16W33.2SGPIO_CLK_00402LF 1/16W33.21%CHIP1%33.21/16WCHIP0402LFPWRGD_SYS_PWROKCHIP0402LF33.21/16WFM_PVCCFA_EHV_CPU1_ENFM_PVCCFA_EHV_CPU1_R_EN1/16W0402LFCHIP33.21%FM_PVCCINFAON_CPU1_ENFM_PVCCINFAON_CPU1_R_EN0402LF1/16WCHIP33.21%FM_PVCCIN_CPU0_ENFM_PVCCIN_CPU0_R_EN1/16WCHIP0402LF33.21%
1%0402LFPWRGD_P3V3_AUX_PLDPWRGD_P1V8_PCH_AUX_PLDPWRGD_PCH_PWROK_RFM_CPU0_SKTOCC_LVT3_PLD_NFM_CPU1_SKTOCC_LVT3_PLD_NPWRGD_P3V3_AUX_PDB1/16W0402LF1%33.2CHIP1/16W33.2FM_PVCCFA_EHV_FIVRA_CPU1_R_EN1%1/16WRST_SGPIO_RESET_NIRQ_SGPIO_INTR_NSGPIO_DEBUG_PLD_DOUTSGPIO_DEBUG_PLD_CLK1/16WSGPIO_BMC_LD_NRST_SGPIO_RESET_N_RIRQ_SGPIO_INTR_N_RSGPIO_DO_1SGPIO_CLK_11/16WSGPIO_DEBUG_PLD_LD_NSGPIO_BMC_CLKSGPIO_BMC_DOUTSGPIO_LD_01%CHIPSGPIO_BMC_DIN_RSGPIO_DEBUG_PLD_DIN
R1844
R1843
R1757
R1756
R1755
R1758
R1754
R1753
R1752
R1751
R1423
R986
R987
R988
R985
R984
R983
R982
R981
21R4267
21
21
21
21R1812
21R1811
21
21
21
21
21
21
21
21
21R1447
21R1448
21R1444
21R1443
21R1442
21
21
21
21
21
21
21
21
21
R1919
SHEETDATE
DEPARTMENT
SIZE
PROJECT DOCUMENT NUMBER REV
REVIEWER
DESIGNER
123
7 3 2 1 6 5 4
E
A
B
C
E
D
C
B
A
7 6 5 4
D
OUT
OUT
OUT
OUT
IN
INOUT
IN OUT
OUTIN
IN OUTOUT
IN
IN
OUT
OUT
IN
OUTIN
INOUT
IN OUT
OUTIN
OUT
IN
IN
IN
IN
OUT
OUT
OUT
OUT
IN
IN
OUT
IN OUT
IN
IN
OUT
OUT
OUT
OUT
OUT IN
OUTIN
IN
IN
IN
IN
C



20210902 MODIFY FOR GTTO BMC20211130 CHANGE TP 0 OHM20211126 CHANGE TO P3V3
Fri Aug 25 14:03:44 2023N/AN/AN/AN/AV05223 OF 312
P3V3
MAIN FPGA / PFR - SI (2/2)214219164214219149208 206211223203240 216215219208223206211215240244131182228182220216215215219252214219202158183255206215219 208215182252 214
183198215
240182252 215
RST_PERST_SWB_NCHIP33.20402LFRST_OCP_V3_2_N33.21%RST_PCIE_CPU1_DEV_PERST_NRST_PERST_SWB_R_N0402LF 1/16WCHIPFM_PLD_CLKS_DEV_ENFM_PLD_CLKS_OE_R_NFM_THERMTRIP_DLY_LVC1_NCHIP1/16W5%0402LFCHIPCHIP1/16W0FM_BMC_PWRBTN_OUT_N FM_THERMTRIP_DLY_LVC1_R_N
1%
RST_PLTRST_PLD_B_NFM_PLD_CLKS_DEV_ENFM_PLD_CLKS_DEV_R_ENCHIP1/16W10KRST_MB_STBY_NRST_RSMRST_PCH_NRST_RSMRST_NM_HDR_N1/16W1/16W1/16W0402LFCHIPFM_BMC_PWRBTN_N1%0402LFICRST_MB_STBY_R_NRST_RSMRST_PLD_R_N0402LFRST_PCIE_CPU0_DEV_PERST_NRST_PLTRST_B_MUX_NRST_OCP_V3_1_NBSS138KRST_PLTRST_N0402LFCHIP1/16W05%1/16W0402LF1%100K CHIP33.21%0402LF33.21%FM_DB2000_OE_N0402LF 1/16W33.21%CHIPFM_PLD_CLK_25M_R_EN FM_PLD_CLK_25M_EN0402LFCHIP1/16W33.21%RST_PLTRST_PLD_N33.21%0402LF 1/16WCHIP1/16WCHIP0402LF33.21%CHIP0402LF 1/16W33.21%FM_PCH_SLP_S4_N FM_SLPS4_PLD_N
1%0402LF1/16WFM_ADR_MODE1FM_ADR_MODE1_R
CHIP0402LF1%33.21/16W1%33.2 0402LFRST_PLTRST_B_N0402LFCHIP1/16W33.21%FM_PCH_SLP_S3_N FM_SLPS3_PLD_N1/16WCHIP33.21%CHIP1%0402LF33.2
33.2CHIP 1/16W
R2738
R1520
R1514
R1318
R3050
R1744
R1541
R269
R1996
R1995 R1470
R1469R109
R113
R110
R1207
R1206
R1205
G
S D
U70
21
21
21
21
21
21
21
21
21
21 21
2121
21
2
1
21
21
21
21
SHEETDATE
DEPARTMENT
SIZE
PROJECT DOCUMENT NUMBER REV
REVIEWER
DESIGNER
123
7 3 2 1 6 5 4
E
A
B
C
E
D
C
B
A
7 6 5 4
D
OUT IN
IN
IN
OUT
OUT
IN
IN
OUT
IN
OUT
IN OUT
IN
OUT OUT IN
IN OUT
OUT
IN
OUT
OUTIN
OUT
IN
IN
OUT
OUT
OUT
OUT
IN
R111
C



20220801 ADD ISOLATER20220215 ADD ISOLATER
Fri Aug 25 14:03:45 2023N/AN/AN/AN/AV05224 OF 312P3V3_AUX P3V3_AUXP3V3_AUXP3V3_AUXP3V3_AUXP3V3_AUXP3V3_AUX
MAIN FPGA / PFR - ISOLATOR240245214252214215
191214260
FM_AC_PWR_BTN_R_N FM_AC_PWR_BTN_PLD_NPWRGD_PS_PWROK_PLDPWRGD_PS_PWROK_PLD_ISO_R0402LFFM_AC_PWR_BTN_PLD_ISO_N33.2EMPTY1%1/16W10K1%0402LFCHIPFM_AC_PWR_BTN_PLD_ISO_R_N74LVC2G07DW-7EMPTYEMPTYEMPTYSMLF10%1%1/16WEMPTY0402ICPWRGD_PS_PWROK_PLD_N4.7K5%1/16W0402LFPWRGD_PS_PWROK_PLD_ISOPJT138KICSMLFNC_UXX_2YEMPTYC040225V1UF10%8.45K0402LF05%
5%1/16WFM_PS_EN_PLD_BUF1NC_U150_B1
25V0.1UFPJT138KCHIPFM_PS_EN_PLD_RNC_U150_A1SMLF4.7K1/16W5%0402LFSMLF74LVC2G17GWICCHIP1/16WCHIP1%33.210%X7R25V0.1UF0402EMPTY4.7K0402LFPLACE U150 NEAR FRONT SIDE OF MB
G1
G2
D1S1S2 D2
R4716
C2370
R4718
R4605
R4604
52
43
61
2
5
4
6
3
1
1 64 352
U332
Q144
Q144
U150
VCCGND
2Y
1Y
2A
1A
B0
A1
A0
B1
GND VCC
2
1
21
2
1
2
1
21
2
1
21R1446
2
1
2
1
2
12
1
CAD NOTE:
R2355
SHEETDATE
DEPARTMENT
SIZE
PROJECT DOCUMENT NUMBER REV
REVIEWER
DESIGNER
123
7 3 2 1 6 5 4
E
A
B
C
E
D
C
B
A
7 6 5 4
D
IN OUT
OUT
IN
OUTIN
C2369
R4717
R4719
C1619
C



20210902 MODIFY FOR GT20211206 CHANGE R4036,R403920211206 CHANGE R4037,R404020211206 CHANGE R4038,R4041Fri Aug 25 14:03:46 2023N/AN/AN/AN/AV05225 OF 312P3V3P3V3
P3V3_AUXP3V3_AUXP3V3_AUX
PVNN_TERM_CPU0PVNN_TERM_CPU0PVNN_TERM_CPU0
P3V3_AUX
GTL2014(1/2)
128128128128128128128
204182216216204182216204182454514451414 216216216216216216216216128
SMLFGTL2014PWH_CPU_ERR1_LVC1_N1/16WSMLFGTL2014PWP0V62_CPU1_RST_DDR_VREFPD_GTL2014_BMC_JTAG_DIR_1RST_CPU1_DRAM_GH_PLD_LVT3_R_NRST_CPU1_DRAM_EF_PLD_LVT3_R_NRST_CPU1_DRAM_CD_PLD_LVT3_R_NRST_CPU1_DRAM_AB_PLD_LVT3_R_NRST_CPU1_DRAM_AB_PLD_NRST_CPU1_DRAM_CD_PLD_NRST_CPU1_DRAM_EF_PLD_NRST_CPU1_DRAM_GH_PLD_NIC10%25VX6SC04021/16W150CHIP0402LF1/16W1%1KX7R10%25VICP0V62_CPU0_ERRS_U306_VREF33.233.2CHIP33.20402LFRST_CPU0_DRAM_AB_PLD_NRST_CPU0_DRAM_CD_PLD_N
4.32K1%1/16W1K0402LFCHIP1/16W1%1/16WCHIP0402LF4.32K1%1K0.1UFRST_CPU0_DRAM_GH_PLD_LVT3_R_NRST_CPU0_DRAM_EF_PLD_LVT3_R_NRST_CPU0_DRAM_CD_PLD_LVT3_R_NRST_CPU0_DRAM_AB_PLD_LVT3_R_NP0V62_CPU0_RST_DDR_VREF
NC_U306_A0H_CPU_ERR2_LVC2_R_NH_CPU_ERR1_LVC2_R_NH_CPU_ERR0_LVC2_R_NPD_CPU1_ERRS_U306_DIRPD_GTL2014_ERROR_B0
RST_CPU0_DRAM_EF_PLD_N
0402H_CPU_ERR0_PCH_R_NH_CPU_ERR0_LVC2_NH_CPU_ERR1_LVC2_NH_CPU_ERR1_PCH_R_NH_CPU_ERR2_LVC2_NH_CPU_ERR2_PCH_R_N0402LF1%
PD_GTL2014_BMC_JTAG_DIR_0X6SC0402CHIP0402LFCHIP0402LF0.1UF1/16W0402LF1501%1/16WCHIP
0.1UF0402H_CPU_ERR0_LVC1_NH_CPU_ERR2_LVC1_R_N0402LFH_CPU_ERR2_LVC1_NH_CPU1_ERR2_LVC1_R_NH_CPU1_ERR0_LVC1_R_NH_CPU0_ERR0_LVC1_R_NH_CPU1_ERR1_LVC1_R_NH_CPU0_ERR1_LVC1_R_NH_CPU0_ERR2_LVC1_R_NH_CPU_ERR0_LVC1_R_NH_CPU_ERR1_LVC1_R_N1%CHIP150CHIP1/16W1%0402LF1500402LF1/16WCHIP1%5%0402LF0CHIP 1/16W5%05%05%005%05%05%05%05% CHIPCHIPCHIP33.2CHIP1UF33.2CHIP33.233.2 CHIPCHIPRST_CPU1_DRAM_GH_PLD_LVT3_N1K25VCHIPCHIPC040233.233.210%1UF25VRST_CPU0_DRAM_EF_PLD_LVT3_NRST_CPU0_DRAM_AB_PLD_LVT3_NRST_CPU0_DRAM_CD_PLD_LVT3_NRST_CPU0_DRAM_GH_PLD_LVT3_N1K0402X7R1UFCHIPGTL2014PW25VX6S10%SMLF25V10%CHIPCHIPCHIP0402LF1/16W33.233.233.2CHIP33.2RST_CPU1_DRAM_EF_PLD_LVT3_NRST_CPU1_DRAM_CD_PLD_LVT3_NRST_CPU1_DRAM_AB_PLD_LVT3_NRST_CPU0_DRAM_GH_PLD_NX7R33.21%10%1%ICCHIP0402LFCHIP1/16W1%1K1/16W1%4.32KCHIP
R4053
R4048
R4049
R4047
R4046
R4042
R4043
R4044
R4045
GTL2014
GTL2014
GTL2014
R4391 R4394
R4393
R4052
R4050
R4392
R4038
R4041
R4389
R4388
R338
R342
R346
R4390
R340
R341
R337
R336
R345
R344
R4040
R4037
C2253
C2252
R4051
R4054
C2247
4
14
11
8
7
1
6
5
3
2
9
10
12
13
U306
4
14
11
8
7
1
6
5
3
2
9
10
12
13
U305
4
14
11
8
7
1
6
5
3
2
9
10
12
13
U304
VCC
VREF
DIR
A0
A1
A2
A3
GND_0
GND_1
GND_2
B3
B2
B1
B0
VCC
VREF
DIR
A0
A1
A2
A3
GND_0
GND_1
GND_2
B3
B2
B1
B0
VCC
VREF
DIR
A0
A1
A2
A3
GND_0
GND_1
GND_2
B3
B2
B1
B0
2
1
21
21
21
21
21
2
1
2
1
2
1
2
1
21
21
21
2
1
21 21
21 21
21 21
2
1
2
1
2
1
R4039
2
1
R4036
2
1
2
1
2
1
21
21
2
1
21
21
2
1
21 21
21 21
21 21 21 21
2
1
SHEETDATE
DEPARTMENT
SIZE
PROJECT DOCUMENT NUMBER REV
REVIEWER
DESIGNER
123
7 3 2 1 6 5 4
E
A
B
C
E
D
C
B
A
7 6 5 4
D
ININININ
INININ
IN
OUT
OUT
OUT
OUT
OUT
ININ
ININ
ININ
OUT
OUTOUTOUTOUT
OUTOUTOUTOUT
C2254
R4055
C2248
C2246
C



20210902 MODIFY FOR GT20211206 CHANGE R4016,R4019202120302 ADD R4621
Fri Aug 25 14:03:48 2023N/AN/AN/AN/AV05226 OF 312
P3V3P3V3
GTL2014(2/2)
222118118216 255216216240PWRGD_CPUPWRGD_LVC1H_CPU_RMCA_LVC1_R_NH_CPU_CATERR_LVC1_R_NH_CPU_CATERR_LVC2_BMC_R_NH_CPU_CATERR_LVC2_R1_NSMLFGTL2014PWP0V62_CPU0_ERRS_VREFPD_CPU0_ERRS_DIR33.21KX6SCHIPCHIP1%CHIP1/16W4.32KICCHIP1%CHIP33.21K0402LF33.2 CHIP33.2CHIPPWRGD_CPUPWRGD_LVC2_R1H_CPU_RMCA_LVC2_R2_NH_CPU_CATERR_LVC2_R2_NC040210%25V1UF0402X7R25V0.1UF1/16W0402LF10%H_CPU_CATERR_LVC2_BMC_NH_CPU_RMCA_LVC2_R1_NPWRGD_CPUPWRGD_LVC2_R
GTL2014
R4621
R4019
R4016
C2243
R4023
R4022
R4021
R4029
4
14
11
8
7
1
6
5
3
2
9
10
12
13
U301
VCC
VREF
DIR
A0
A1
A2
A3
GND_0
GND_1
GND_2
B3
B2
B1
B0 21
2
1
2
1
2
1
2
1
21 21 21
21
C2249
SHEETDATE
DEPARTMENT
SIZE
PROJECT DOCUMENT NUMBER REV
REVIEWER
DESIGNER
123
7 3 2 1 6 5 4
E
A
B
C
E
D
C
B
A
7 6 5 4
D
INININ
OUTOUTOUT
OUT
C



PCA9555 ADDR: 0XE8
20220215 DESIGN CHANGE
20211130 POP R3499,R3516,R3517,R3518202120802 ADD R4728,R4729,R4734,R4735,R4736,R4741,R4742202120812 ADD R4802Fri Aug 25 14:03:49 2023N/AN/AN/AN/AV05227 OF 312EMPTYP3V3_AUXP3V3_AUXP3V3_AUXP3V3_AUX
BMC - PCA9539144227
227227227152196227 227227227227227215154161191231233236245227227227227227227227227231231142144142144142144142144146215144146215227227227227227227227227227144147213144215 227227
227227227227151227146215PRSNT_CABLE_GPU_A3_ISO_N05%CHIPPRSNT_CABLE_GPU_A3_ISO_R_N
5%PRSNT_CABLE_GPU_A2_ISO_R1_NPRSNT_CABLE_SWB_B1_ISO_R_NTCA9539_0_ADD1CHIP25V10%PU_RST_SMB_U181_NRST_USB_HUB_NRST_SWB_BIC_NICGPU_PEX_STRAP0_RGPU_PEX_STRAP1_RGPU_BASE_ID1_RGPU_BASE_ID0_RPCA9539RPWPU_U181_INTTCA9539_0_ADD00402LFEMPTYSMLFRST_SMB_SWITCH_NX7R0EMPTY0402LFEMPTY4.7K1/16W5%1K1/16W1%0402LF1K1%1K1/16W0402LFCHIP1%1/16W1K0402LFCHIPTCA9539_0_ADD11/16W1%0402LF1%04021/16W10KTP_TCA9539_0_P0_2CHIP05%05%CHIP05%05%05%CHIP5%005%CHIP05%05%CHIP5%CHIP05%CHIP05%0GPU_PRSNT_N_ISO_R1CHIP
TP_TCA9539_0_P0_3PRSNT_SWB_ISO_R1_NGPU_PRSNT_N_ISO_R1PRSNT_CABLE_GPU_B3_ISO_R1_NPRSNT_CABLE_SWB_B2_ISO_R_NTCA9539_0_ADD0RST_SWB_BIC_NSMB_IOEXP_3V3AUX_SCLSMB_IOEXP_3V3AUX_SDAGPU_BASE_ID1GPU_BASE_ID0GPU_PEX_STRAP1GPU_PEX_STRAP0PRSNT_CABLE_GPU_B3_ISO_NPRSNT_CABLE_SWB_B2_ISO_NPRSNT_CABLE_GPU_A2_ISO_NSMB_IOEXP_3V3AUX_SCL_R1SMB_IOEXP_3V3AUX_SDA_R1GPU_BASE_ID1_RGPU_BASE_ID0_RGPU_PEX_STRAP1_RGPU_PEX_STRAP0_RCHIP5%0CHIP5%0PRSNT_CABLE_SWB_B2_ISO_R_NPRSNT_CABLE_GPU_A2_ISO_R1_NPRSNT_CABLE_SWB_B1_ISO_R_NPRSNT_CABLE_SWB_B1_ISO_NGPU_PRSNT_N_ISOPRSNT_SWB_ISO_NCHIPPRSNT_SWB_ISO_R1_NPRSNT_CABLE_GPU_A1_ISO_R1_N
PRSNT_CABLE_GPU_A1_ISO_R1_NSMB_IOEXP_3V3AUX_SCL_R1PRSNT_CABLE_GPU_A3_ISO_R_NSMB_IOEXP_3V3AUX_SDA_R10.1UFRST_SWB_BIC_R_NCHIPCHIPCHIPPRSNT_CABLE_GPU_B3_ISO_R1_NPRSNT_CABLE_GPU_A1_ISO_N
R3499
R2983
R2982
R2848
R4802
R4742
R3518
R3517
R3516
R2922
R2694
R2693
R2696
R2695
12 24
23
22
3
20
19
18
17
16
15
14
13
11
10
9
8
7
6
5
4
1
2
21
U181
VDD
SDA
SCL
A0
IO1_7
IO1_6
IO1_5
IO1_4
IO1_3
IO1_2
IO1_1
IO1_0
VSS
IO0_7
IO0_6
IO0_5
IO0_4
IO0_3
IO0_2
IO0_1
IO0_0
RESET
A1
INT
21
21
21R4741
21R4736
21R4735
21
21
21
21
21
21
21
21
21
21
2
1 2
1
2
1C1713
2
1
2
1
2
1
2
1
21
R4734
R4729
R4728
SHEETDATE
DEPARTMENT
SIZE
PROJECT DOCUMENT NUMBER REV
REVIEWER
DESIGNER
123
7 3 2 1 6 5 4
E
A
B
C
E
D
C
B
A
7 6 5 4
D
IN
IN OUT
IN
BI
IN
IN
OUT
OUT
IN
IN OUT
IN
OUTIN
IN
OUTIN
IN
OUTIN
IN
IN OUT
IN
IN OUT
IN
IN OUT
IN
IN
IN OUT
IN OUT
OUT
OUT
IN
IN
IN
IN
IN
IN
IN
OUT
OUT
OUT
OUTIN
OUT
R2921
R2923
C



20210705 MODIFY FOR GT
Fri Aug 25 14:03:51 2023N/AN/AN/AN/AV05228 OF 312NM DEBUG HEADER -(ME CONNECTOR)
197214 240228241241228241223228228228301305183215183213241228205228228241241PWRGD_PS_PWROK_ME_CONNPECI_BMC_MEPWRGD_PS_PWROKCHIPIRQ_SML0_ALERT_R1_NSMB_HOST_3V3AUX_SCL_R5SMB_HOST_3V3AUX_SDA_R5IRQ_SML1_PMBUS_ALERT_R_N5%CHIP5%0SCONN20_51386-0200C-V01SMB_PMBUS_SML1_ME_SDARST_RSMRST_NM_HDR_NSMB_HOST_ME_SCL33.21%0402LF1%CHIPCHIP1%33.233.21/16WCHIP0SMB_HOST_ME_SDASMB_HOST_ME_SCLIRQ_SML1_PMBUS_ALERT_NIRQ_SML0_ALERT_R_NSMB_SML0_ME_SDASMB_HOST_ME_SDAFM_BIOS_POST_CMPLT_HDR_NIRQ_SML1_PMBUS_ALERT_R_NIRQ_SML0_ALERT_R1_NIOSMLFSMB_PMBUS_SML1_ME_SCLSMB_SML0_ME_SCL
R3103
R3051
R30542019
1817
1615
1413
1211
109
87
65
43
21
J100
2019
1817
1615
1413
1211
109
87
65
43
21
21
21
21R3052
21R3053
21
SHEETDATE
DEPARTMENT
SIZE
PROJECT DOCUMENT NUMBER REV
REVIEWER
DESIGNER
123
7 3 2 1 6 5 4
E
A
B
C
E
D
C
B
A
7 6 5 4
D
BIIN
BIIN OUT
IN
OUT
IN
OUT
OUT
BIIN
IN
IN
BIIN
BI
OUTIN
BI
C



20221201 POP R182120221221 CHANGE R692,R694 TO 33.2 OHM229 OF 312V05N/AN/AN/AN/AFri Aug 25 14:03:52 2023241P3V3_AUXPVNN_TERM_CPU0
P3V3_AUXSMBUS - I3C CPU0 SPDI3C_SPD_DDRABCD_CPU0_BMC_SDAFM_SPD_REMOTE_EN_R1%1/16WCHIP0402LF2001KPD_I3C_SPD_DDR_CPU0_OE_NICI3C_SPD_DDRABCD_CPU0_R_SCLQS3VH257QG8I3C_SPD_DDREFGH_CPU0_R_SCLI3C_SPD_DDRABCD_CPU0_R_SDAFM_SPD_REMOTE_ENI3C_SPD_DDRABCD_CPU0_R_SCLI3C_SPD_DDREFGH_CPU0_R_SDAI3C_SPD_DDREFGH_CPU0_BMC_SDAI3C_SPD_DDREFGH_CPU0_BMC_SCLI3C_SPD_DDREFGH_CPU0_SCLI3C_SPD_DDREFGH_CPU0_SDAI3C_SPD_DDRABCD_CPU0_BMC_SCLI3C_SPD_DDRABCD_CPU0_SCLI3C_SPD_DDRABCD_CPU0_SDAI3C_SPD_DDREFGH_CPU0_LVC1_R_SDAI3C_SPD_DDREFGH_CPU0_LVC1_R_SCLI3C_SPD_DDRABCD_CPU0_LVC1_R_SDAI3C_SPD_DDRABCD_CPU0_LVC1_R_SCLI3C_SPD_DDREFGH_CPU0_R_SCLI3C_SPD_DDRABCD_CPU0_R_SDAI3C_SPD_DDREFGH_CPU0_R_SDA
FM_SPD_REMOTE_ENI3C_SPD_DDREFGH_CPU0_LVC1_SDAI3C_SPD_DDREFGH_CPU0_LVC1_SCLI3C_SPD_DDRABCD_CPU0_LVC1_SDAI3C_SPD_DDRABCD_CPU0_LVC1_SCL230 2292152412292292412292412291%1/16WCHIP0402LF
1313
1/16W05%0402LFEMPTY1/16W05%EMPTY0402LF1/16W0402LF5%0EMPTYSMLFEMPTY1/16W0402LF5%0X7R0.1UF10%040225V00402LF1/16WCHIP5%0402LF1%33.213130402LFCHIP1%4991/16W4990402LFCHIP1%1/16W1%4990402LF1/16WCHIP1/16W1%CHIP4990402LF00402LF1/16WCHIP5%1%33.2 0402LF
2292301%33.25%00402LF01/16WCHIP5%33.21%1/16W0402LFCHIP1%10K0402LF1KEMPTY1/16W1%2292299796959493929190979695949392919089888786858483828988878685848382229229
R1821
R692
R691
R693
R694
R682
R683
R684
R685
12
9
7
4
16
1
13
10
6
3
14
11
5
2
815
U15
I1D
I0D YD
YC
I1C
I0C
YB
I1B
I0B
I1A
I0A
Vcc
GND
YA
E*
S
21
2
1
2
1
21
21
21
21
21R688
21R687
2
1
2
1
2
1
21R690
21
2
1
21
21
21
21
2
1
2
1
R689
SHEETDATE
DEPARTMENT
SIZE
PROJECT DOCUMENT NUMBER REV
REVIEWER
DESIGNER
123
7 3 2 1 6 5 4
E
A
B
C
E
D
C
B
A
7 6 5 4
D
BI
ININ
BI
OUTBI
OUT
BI
BI
OUT
BI
OUTBI
BI
OUT
INBI
IN
BIIN
ININ
IN
R686R681R680
C538
R678
R679
R87
R318
C



20221221 CHANGE R675,R677 TO 33.2 OHMFri Aug 25 14:03:53 2023N/AN/AN/AN/AV05230 OF 312
PVNN_TERM_CPU1P3V3_AUX
SMBUS - I3C CPU1 SPDI3C_SPD_DDREFGH_CPU1_BMC_SCLI3C_SPD_DDRABCD_CPU1_R_SDAI3C_SPD_DDRABCD_CPU1_R_SCLFM_SPD_REMOTE_ENI3C_SPD_DDRABCD_CPU1_BMC_SCLI3C_SPD_DDREFGH_CPU1_R_SCLI3C_SPD_DDREFGH_CPU1_R_SDAI3C_SPD_DDREFGH_CPU1_BMC_SDAPD_I3C_SPD_DDR_CPU1_OE_NI3C_SPD_DDRABCD_CPU1_BMC_SDAI3C_SPD_DDRABCD_CPU1_SDAI3C_SPD_DDRABCD_CPU1_SCLI3C_SPD_DDREFGH_CPU1_SCLI3C_SPD_DDREFGH_CPU1_SDAI3C_SPD_DDREFGH_CPU1_LVC1_R_SDAI3C_SPD_DDREFGH_CPU1_LVC1_R_SCLI3C_SPD_DDRABCD_CPU1_LVC1_R_SDAI3C_SPD_DDRABCD_CPU1_LVC1_R_SCLI3C_SPD_DDREFGH_CPU1_R_SDAI3C_SPD_DDREFGH_CPU1_R_SCLI3C_SPD_DDRABCD_CPU1_R_SDAI3C_SPD_DDRABCD_CPU1_R_SCLI3C_SPD_DDREFGH_CPU1_LVC1_SDAI3C_SPD_DDREFGH_CPU1_LVC1_SCLI3C_SPD_DDRABCD_CPU1_LVC1_SDAI3C_SPD_DDRABCD_CPU1_LVC1_SCL2292301%1K0402LFCHIP1/16W241230241230241230241ICQS3VH257QG8SMLF444444444991%CHIP1/16W0402LF4990402LF1/16WCHIP1%
EMPTY05%0402LF 1/16W5%01/16W0402LFEMPTYEMPTY1/16W0402LF5%0EMPTY5%01/16W0402LF25V0402X7R10%0.1UF4990402LF1/16WCHIP1%0402LF4991%CHIP1/16W01/16WCHIP5%0402LF1%0402LF33.25%CHIP1/16W0402LF01%0402LF33.21%33.205%1%33.25%01/16W0402LFCHIP11311211111010910810710611311211111010910810710610510410310210110099981051041031021011009998230230230230
R674
R675
R676
R677
R665
R667
R668
R666
12
9
7
4
16
1
13
10
6
3
14
11
5
2
815
U14
I1D
I0D YD
YC
I1C
I0C
YB
I1B
I0B
I1A
I0A
Vcc
GND
YA
E*
S
21
21
21
21
2
1
2
1
21
21
21
2
1
2
1
21R671
21R670
21R673
21
2
1
21
2
1
R672
SHEETDATE
DEPARTMENT
SIZE
PROJECT DOCUMENT NUMBER REV
REVIEWER
DESIGNER
123
7 3 2 1 6 5 4
E
A
B
C
E
D
C
B
A
7 6 5 4
D
BIBI
ININ
BI
BIOUT
OUTBI
OUT
BI
OUT
BIBI
BIIN
INBI
ININ
IN
R669
C537
R662
R661
R664R663
C



20221222 CHANGE R2984,R2985 TO 10K OHM
20210604 MODIFY FOR GT
PCA9546 ADDR: 0XE0Fri Aug 25 14:03:54 2023N/AN/AN/AN/AV05231 OF 31210KP3V3_AUXP3V3_AUXP3V3_AUXP3V3_AUX
SMBUS - PCIE0 SMBUS
RST_SMB_SWITCH_NSMB_IOEXP_3V3AUX_SCLSMB_IOEXP_3V3AUX_SDASMB_SENSOR_E1S_3V3AUX_SCLSMB_SENSOR_E1S_3V3AUX_SDASMB_SENSOR_M2_P0_3V3AUX_SCLSMB_SENSOR_M2_P0_3V3AUX_SDAPCA9548_PCIE3_ADDR0PCA9548_PCIE3_ADDR1PCA9548_PCIE3_ADDR2SMB_BMC_SWB_SDASMB_BMC_SWB_SCLSMB_FRU_3V3AUX_SCLSMB_FRU_3V3AUX_SDASMB_SENSOR_M2_P0_3V3AUX_SDASMB_SENSOR_M2_P0_3V3AUX_SCL
SMB_PCIE0_3V3AUX_SCL_R5SMB_PCIE0_3V3AUX_SDA_R5SMB_PCIE0_3V3AUX_SCL_R3SMB_PCIE0_3V3AUX_SDA_R3SMB_IOEXP_3V3AUX_SCL_RSMB_IOEXP_3V3AUX_SDA_RPU_RST_SMB_PCIE0_NPCA9548_PCIE3_ADDR2PCA9548_PCIE3_ADDR1PCA9548_PCIE3_ADDR0SMB_PCIE0_3V3AUX_SCL_RSMB_INA230_3V3AUX_SCL_RSMB_PCIE0_3V3AUX_SDA_RSMB_BMC_SWB_SDA_R4SMB_BMC_SWB_SCL_R4SMB_FRU_3V3AUX_SCL_RSMB_FRU_3V3AUX_SDA_RSMB_INA230_3V3AUX_SDA_RSMB_INA230_3V3AUX_SDASMB_IOEXP_3V3AUX_SCLSMB_IOEXP_3V3AUX_SDASMB_BMC_SWB_SDASMB_PCIE0_3V3AUX_SCLSMB_PCIE0_3V3AUX_SDASMB_INA230_3V3AUX_SCLSMB_BMC_SWB_SCLSMB_FRU_3V3AUX_SDASMB_FRU_3V3AUX_SCLSMB_INA230_3V3AUX_SDASMB_INA230_3V3AUX_SCLSMB_PCIE0_3V3AUX_SDASMB_PCIE0_3V3AUX_SCLSMB_SENSOR_E1S_3V3AUX_SDASMB_SENSOR_E1S_3V3AUX_SCL1K0402LFCHIP1/16W1%EMPTY1%0402LF10K1/16W0402LF1KCHIP1/16W1%1/16WCHIP1K0402LF1%0402LFEMPTY1%1/16W10KEMPTY1/16W0402LF1%245 236 233 227191161154215194 231194 231231 194227231231 194227231CHIP1/16W1%0402LF10K
5%2.2K CHIP0402LFCHIP5%2.2K1/16WCHIP1/16W5%2.2K0402LFCHIP2.2K5%1%CHIP10K1%10KCHIP0402LF 1/16W23119419423124323124323123423123423123123123105%CHIPCHIP5%0CHIP05%0CHIP5%5%0CHIPCHIP5%0CHIP05%231231231TCA9548APWRICSMLF0.1UF10%X7R25V0402
1/16W2.2K0402LF5%CHIP2.2K5%CHIPCHIP2.2K5%0402LFCHIP1/16W2.2K5%CHIP2.2K5%1/16W5%CHIP0402LF2.2KEMPTY2.2K5%EMPTY2.2K5%0402LF 1/16W05%CHIP5%0CHIP5%CHIP05%CHIP05%CHIP0CHIP5%0CHIP1%0402LF1/16W33.233.2CHIP1%231194194231227231227231232231232231231240240231232231232231243231243231234231234231240231240231
R2704
R2703
R2566
R2565
R3581
R3580
R2204
R2205
R3395
R3396
R3582
R3583
R3536
R3535
R3394
R2968
R3393
R3527
R2967
R3526
R2984
R2985
R652
R651
R1089
R1090
R589
R588
R2268
24
23
19
17
15
13
10
8
6
4
22
20
18
16
14
11
9
7
5
3
12
21
2
1
U36
SD4
SC4
SD5
SC5
SD6
SC6
SD7
SC7
A2 SCL
SDA
VCC
GND
SC3
SD3
SC2
SD2
SC1
SD1
SC0
SD0
RESET#
A1
A0 2 12 1
21 21
2
1
21
2 1
21 21
21 21
21 21
2
1
2
1
2
1
2
1
2
1
2
1
2
1
SHEETDATE
DEPARTMENT
SIZE
PROJECT DOCUMENT NUMBER REV
REVIEWER
DESIGNER
123
7 3 2 1 6 5 4
E
A
B
C
E
D
C
B
A
7 6 5 4
D
INBI
OUTBI
OUTBI
BIOUT
OUTOUT
OUTOUT
OUTOUT
OUTOUT
INININ
OUT
OUT
OUT
OUTOUT
OUTOUT
OUTOUT
OUT
OUTBI
OUTBI
BI
IN
R1822
C174
R587
R536 R540R538
R539R537
C



20210622 MODIFY FOR GT
Fri Aug 25 14:03:55 2023N/A V05N/AN/AN/A232 OF 312SMBUS - PCIE1 SMBUS
2312311711711711711721721721721721720402LF 1/16W33.233.21%CHIPCHIP1%SMB_INA230_3V3AUX_SCLSMB_INA230_3V3AUX_SDASMB_INA230_1_3V3AUX_SCL_RSMB_INA230_1_3V3AUX_SDA_RSMB_INA230_2_3V3AUX_SDA_RSMB_INA230_2_3V3AUX_SCL_RSMB_INA230_3_3V3AUX_SCL_RSMB_INA230_3_3V3AUX_SDA_RSMB_INA230_4_3V3AUX_SCL_RSMB_INA230_5_3V3AUX_SCL_RSMB_INA230_5_3V3AUX_SDA_R1%33.2 CHIP0402LF 1/16WCHIP33.21%1/16W0402LF1/16W33.233.20402LF33.2SMB_INA230_4_3V3AUX_SDA_R33.21%CHIP1%CHIP0402LF33.21%CHIPCHIP1%1/16WCHIP1%1%CHIP33.2
21R3595
21R3594
21 21
21 21
21R3588 21R3589
21 21
R3592R3593
R3591R3590
R3586R3587
SHEETDATE
DEPARTMENT
SIZE
PROJECT DOCUMENT NUMBER REV
REVIEWER
DESIGNER
123
7 3 2 1 6 5 4
E
A
B
C
E
D
C
B
A
7 6 5 4
D
OUTBI
BIOUT
BIOUT
BI
OUTBI
OUTBI
IN
C



PCA9546 ADDR: 0XE0
20210929 MODIFY FOR GT
20211201 ADD R4269,R4270Fri Aug 25 14:03:57 2023233 OF 312V05N/AN/AN/AN/A
P3V3_AUXP3V3_AUXP3V3_AUXP3V3_AUX
SMBUS - PCIE2 SMBUS240 233233 240233241233170233233170233 240233 240215154161191227231236245233
233170170233233170170233233170170233233251305170170233251305233241233241233233233233241233251305170170233251305233170170233233170170233233
5%5%2.2K2.2KEMPTYSMB_VR_SENSOR_3V3AUX_SDASMB_VR_SENSOR_3V3AUX_SCL2.2KEMPTY5%1/16WSMB_LM75_0_3V3AUX_SDA_RSMB_LM75_0_3V3AUX_SCL_R1/16W0SMB_VR_3V3AUX_SDAPU_RST_SMB_PCIE2_NCHIP5%5%000SMB_LM75_2_3V3AUX_SCL_RSMB_LM75_2_3V3AUX_SDA_RSMB_LM75_1_3V3AUX_SCL_RSMB_LM75_1_3V3AUX_SDA_RSMB_VR_3V3AUX_SCL_R6SMB_VR_3V3AUX_SDA_R60402PCA9548_PCIE0_ADDR0SMB_LM75_3_3V3AUX_SCLSMB_LM75_3_3V3AUX_SDASMB_VR_SENSOR_3V3AUX_SDASMB_VR_SENSOR_3V3AUX_SCLRST_SMB_SWITCH_NPCA9548_PCIE0_ADDR11/16W10K0402LFEMPTY1%X7R10%0.1UF25V05%CHIP05%CHIPTCA9548APWRIC
SMB_LM75_3_3V3AUX_SDACHIP1/16W5%CHIPCHIP2.2K0402LF0402LF2.2K1/16W2.2K2.2K1/16W5%5%CHIPCHIPSMB_LM75_3_3V3AUX_SCL0402LF5%CHIP0402LFCHIP5%SMB_LM75_2_3V3AUX_SDASMB_LM75_2_3V3AUX_SCLSMB_LM75_1_3V3AUX_SDASMB_LM75_1_3V3AUX_SCLSMB_LM75_0_3V3AUX_SDASMB_LM75_0_3V3AUX_SCL5%0402LF2.2K0402LF2.2K1/16WCHIP1/16W2.2K2.2K1/16WSMB_VR_3V3AUX_SCLSMB_VR_3V3AUX_SDACHIPCHIP5%5%5%2.2K10K1%EMPTY0402LF10K1/16W1%EMPTY0402LF1%1KCHIP1/16W1%1/16WCHIP1K0402LF1/16W10K0402LF1%EMPTY1%1/16WCHIP0402LF1KPCA9548_PCIE0_ADDR0PCA9548_PCIE0_ADDR10402LFPCA9548_PCIE0_ADDR2SMLF0402LF1/16WCHIP5%CHIPSMB_VR_3V3AUX_SCLCHIP5%SMB_LM75_0_3V3AUX_SDA0CHIP5%SMB_LM75_0_3V3AUX_SCL5%0CHIPSMB_LM75_1_3V3AUX_SDA0CHIP5%SMB_LM75_1_3V3AUX_SCL0CHIP5%SMB_LM75_2_3V3AUX_SDA5%0CHIPSMB_LM75_2_3V3AUX_SCLPCA9548_PCIE0_ADDR2SMB_LM75_3_3V3AUX_SCL_RSMB_LM75_3_3V3AUX_SDA_RCHIP1%CHIP1%33.2SMB_VR_SENSOR_3V3AUX_SDA_RSMB_VR_SENSOR_3V3AUX_SCL_R0402LF33.2
R3720
R3719
R3718
R3717
R3716
R3715
R3714
R3713 R3721
R3722
R3711
R3712
R4269
R4270
R3724
R3723
R3725
R3726
R3727
R3728
R3730
R3729
R3710
R3731
R3732
24
23
19
17
15
13
10
8
6
4
22
20
18
16
14
11
9
7
5
3
12
21
2
1
U39
SD4
SC4
SD5
SC5
SD6
SC6
SD7
SC7
A2 SCL
SDA
VCC
GND
SC3
SD3
SC2
SD2
SC1
SD1
SC0
SD0
RESET#
A1
A0
2
1
21
2 12 1
2 12 1
2
1
21
21 21
21
2
1
2
1
2
1
2
1
2
1
2
1
SHEETDATE
DEPARTMENT
SIZE
PROJECT DOCUMENT NUMBER REV
REVIEWER
DESIGNER
123
7 3 2 1 6 5 4
E
A
B
C
E
D
C
B
A
7 6 5 4
D
OUTOUT
OUTOUT
OUTOUT
OUTOUT
OUT
OUT
OUT
OUT
OUT
IN
BIOUT
BIOUT
BIOUT
BIOUT BIOUT
INBIINININ
OUTOUT
R3705
C2056
R3708R3706
R3709R3707
R3703
R3704
C



20221222 CHANGE R2674 TO 27.4 OHM
20210607 MODIFY FOR GT20221222 CHANGE R2667,R2669 TO 10K OHM
20221221 CHANGE R3111 TO 0 OHMI3C FROM BMC202120215 ADD R4603
Fri Aug 25 14:03:58 2023N/AN/AN/AV05234 OF 312N/A
P3V3_AUXP3V3_AUXP3V3_AUX
P3V3_AUX P3V3_AUXP3V3_AUXP3V3_AUXP3V3_AUX
SMBUS - PCIE3 SMBUSSMB_2_BMC_GPU_BUF_R_SCL5%I3C_BMC_SWB_R_SCLI3C_BMC_SWB_R_SDA I3C_BMC_SWB_BUF_R_SDAI3C_BMC_SWB_BUF_R_SCLEMPTY10%25V0.1UF0402I3C_BMC_SWB_BUF_SCLSMB_2_BMC_GPU_BUF_R_SDAICSMLFSMB_2_BMC_GPU_BUF_SDASMB_2_BMC_GPU_BUF_SCLSMB_BMC_GPU_ENSMB_2_BMC_GPU_SCLSMB_2_BMC_GPU_SDASMB_BMC_GPU_EN_R3SMB_2_BMC_GPU_R_SCLSMB_2_BMC_GPU_R_SDAI3C_BMC_SWB_SDAI3C_BMC_SWB_SCLSMB_BMC_SWB_ENSMB_BMC_SWB_EN_R2
SMB_BMC_SWB_SCLSMB_BMC_SWB_ENSMB_BMC_SWB_SDASMB_BMC_SWB_EN_RSMB_BMC_SWB_R_SDASMB_BMC_SWB_R_SCLSMB_1_BMC_GPU_SDASMB_1_BMC_GPU_SCLSMB_BMC_GPU_ENSMB_BMC_SWB_BUF_R_SCLSMB_BMC_SWB_BUF_R_SDASMB_1_BMC_GPU_R_SCLSMB_1_BMC_GPU_R_SDASMB_BMC_GPU_EN_R1SMB_BMC_SWB_BUF_SCLSMB_1_BMC_GPU_BUF_R_SDASMB_BMC_SWB_BUF_SDASMB_1_BMC_GPU_BUF_R_SCLI3C_BMC_SWB_BUF_SDASMB_1_BMC_GPU_BUF_SCLSMB_1_BMC_GPU_BUF_SDA2402412402412132342402412402412132341/16W05%CHIP0402LF05%CHIP5%0CHIPLTC4307CMS800402LF 1/16WEMPTY0EMPTY1/16W10KCHIP0402LF1%CHIP05%1%CHIP33.25%00402LF 1/16WCHIP10%0402X7R25V0.1UFCHIP1/16W1%54.9K0402LFCHIP1/16W1%54.9K0402LFCHIP33.21%0402LF 1/16WCHIP1%33.25%1/16W00402LFCHIPCHIP0EMPTYSMLFLTC4307CMS81/16W5%EMPTY0402LF01431430EMPTY2312312132341/16W05%CHIP0402LF05%CHIPCHIP05%240241240241213234CHIP1%10K0402LF1/16WSMLFLTC4307CMS8IC5%0CHIP1/16WCHIP5%0402LF00CHIP5%5%0402LF 1/16W0EMPTYEMPTY00402X7R10%25V0.1UF10K1%0402LFCHIP1/16W10K1%0402LF1/16WCHIPSMLFICLTC4307CMS8CHIP33.21%1/16W33.20402LFCHIP1%040210%25VX7R0.1UF140140
27.41%CHIP0402LF 1/16W33.21%CHIP1371374.7K5%0402LFEMPTY1/16W0402LFEMPTY1/16W4.7K5%1/16W0402LF1%33.2 CHIP33.2 CHIP1%CHIP1/16W1%54.9K0402LF 0402LF54.9K1%1/16WCHIP143143
R2669R2667
R3523
R3110
R3109
R3105
R3106
R3107
R3108
R2898
R2897
R2670R2668
R2674
R2672
R2899
R2707
R2894
R2706
R2725
R2991
R2990
R2676
R3112
R3111
R2986
R2992
R2675
R2671
R2705
R2724
R2893
R2987
8
76
23
54
1
8
76
23
54
1
8
76
23
54
1
8
76
23
54
1
U194
U175
U176
U200
READY
SDA_OUT
SCL_OUT
VCC
GND
SDA_IN
SCL_IN
ENABLE
READY
SDA_OUT
SCL_OUT
VCC
GND
SDA_IN
SCL_IN
ENABLE
READY
SDA_OUT
SCL_OUT
VCC
GND
SDA_IN
SCL_IN
ENABLE
READY
SDA_OUT
SCL_OUT
VCC
GND
SDA_IN
SCL_IN
ENABLE
2
1
2
1
21
21
2
1
2
1
21
21
2
1
2
1
2
1
21
21
21
2
1
21
21
21
21
21
21
21
21
2
1
2
1
2
1
21
21
21
21
21
21
21
21
2
1
21
21
21
21
2
1
2
1
21
SHEETDATE
DEPARTMENT
SIZE
PROJECT DOCUMENT NUMBER REV
REVIEWER
DESIGNER
123
7 3 2 1 6 5 4
E
A
B
C
E
D
C
B
A
7 6 5 4
D
BI
OUT
OUT
BI
OUT
BI
IN
IN
IN
BI
IN
IN
BI
BI
IN
BI
OUT
IN
BI
IN
R3524
C1707
R4603
R3522R3521C1796
C1766
C1708
R2666
C



20211215 R960,R909 CHANGE TO 33 OHM20211215 R961,R962 CHANGE TO 33 OHM20211129 R960,R909 CHANGE TO 10 OHM2-3 CPU1 PCIE ALERT1-2 CPU0 PCIE ALERT20211129 R961,R962 CHANGE TO 10 OHM
Fri Aug 25 14:03:59 2023N/AN/AN/AN/AV05235 OF 312PVNN_TERM_CPU0P3V3P3V3PVNN_TERM_CPU1
PVNN_TERM_CPU1 PVNN_TERM_CPU1 P3V3_AUXP3V3_AUXP3V3_AUX
P3V3P3V3
PVNN_TERM_CPU0 PVNN_TERM_CPU0 P3V3_AUX
SMBUS - CPU0 &1 PEHP SMBUS4514158235
14144545 158158164164
1642351582351642350402LFSMLFPJT138KCHIPFM_SMB_CPU1_ALERT_R1 FM_PEHPCPU1_ALERT_NPJT138KICSMLFICFM_SMB_CPU0_ALERT_R1PJT138KSMLFIC0402LF0402LFFM_PEHPCPU0_ALERT_N0402LF4.7K5%1/16WCHIP5%PJT138KICSMLFFM_SMB_PEHPCPU0_PCIE_ALERT_R_NFM_SMB_PEHPCPU0_PCIE_ALERT_N1/16W4.7K1/16WCHIP1/16WFM_SMB_PEHPCPU1_PCIE_ALERT_R_N0402LF
1%1/16W0402LF0402LFSMB_PEHPCPU0_GTL_SCLCHIP1%33.2SMB_PEHPCPU0_GTL_SDA33.21%CHIPCHIP1%33.21/16W0402LF0402LFSMB_PEHPCPU1_GTL_R_SCLSMB_PEHPCPU1_GTL_R_SDASMB_PEHPCPU1_GTL_SDASMB_PEHPCPU1_GTL_SCL33.21%CHIPPCA9617ADPJP7: CPU PCIE ALERT0.1UF25VCHIP1/16W1%CHIP1%SMB_PEHPCPU0_LVC3_SDASMB_PEHPCPU0_LVC3_SDA_R033.21%CHIPSMB_PEHPCPU0_LVC3_SCLSMB_PEHPCPU0_LVC3_SCL_R01/16W0402LF1%CHIP33.2SMB_PEHPCPU1_LVC3_SDASMB_PEHPCPU1_LVC3_SDA_R0CHIP1%33.2SMB_PEHPCPU1_LVC3_SCLSMB_PEHPCPU1_LVC3_SCL_R033.2 CHIP1%0402LF1/16W4.7K5%CHIP0402LF5%1/16WCHIP4.7K5%5%1/16WCHIP4.7K 4.7K1/16W240 2401%CHIPCHIP1/16W240 2401K1%1/16WCHIP0402LF1%1KCHIP0402LF1/16W0402LF1/16WCHIP1K1% 1%1/16W0402LFCHIP1K
FM_SMB_PEHPCPU1_PCIE_ALERT_N0402LFCHIP 1/16W05%5%00402LFCHIPFM_SMB_PEHPCPU0_PCIE_ALERT_NFM_SMB_PEHPCPU1_PCIE_ALERT_N
SMB_PEHPCPU0_GTL_R_SDATP_SMB_PEHPCPU1_ENTP_SMB_PEHPCPU0_ENSMB_PEHPCPU0_GTL_R_SCL
IOCONN3_210-HP1-030BR1THLFICSMLF25VX7R040210%0.1UFPCA9617ADPICSMLF0402X7R10%040225V0.1UF10%X7R10%X7R040225V0.1UF
G2
G2
G1
G1
S2 D2 S2 D2D1S1 D1S1
R909
R960
R962
R961
R999
R998
5
5
2
2
4 3 4 31 6 1 6
Q16
Q15
Q16
Q15
JP7
U29
U28
1
2
3
GND
SCLB
SDABSDAA
SCLA
VCCBVCCA
EN
GND
SCLB
SDABSDAA
SCLA
VCCBVCCA
EN
21
21
21
21
2
1
2
1
21R2478
21R2477
2
1
2
1
21R2480
21R2479
21
2
1
R1001
21
2
1
R1000
2
1
2
1 2
1
2
1
R1003
2
1
R1002
2
1
2
1
2
1 2
1
2
1
2
1
R1007
2
1
R1006DESIGN NOTE:
321
81
63
72
4 5
81
63
72
4 5
SHEETDATE
DEPARTMENT
SIZE
PROJECT DOCUMENT NUMBER REV
REVIEWER
DESIGNER
123
7 3 2 1 6 5 4
E
A
B
C
E
D
C
B
A
7 6 5 4
D
OUT
BI
OUT
BI
IN
IN
BI
BI
OUT
IN
IN
OUT
OUT
OUT
R967R965
R966 R968
R963 R964
C560 C562
R910 R911
C559 C561
C



20210818 MODIFY FOR GT
20211129 R994 CHANGE TO 10 OHM20211215 R994 CHANGE TO 33 OHM20211129 R996 CHANGE TO 10 OHM20211129 R996 CHANGE TO 33 OHM
PCA9545 ADDR: 0X70
Fri Aug 25 14:04:00 2023N/AN/AN/AN/AV05236 OF 312P3V3_AUXPVNN_TERM_CPU0PVNN_TERM_CPU1 P3V3_AUX
P3V3_AUXP3V3_AUXP3V3_AUXP3V3_AUXP3V3_AUXPVNN_TERM_CPU0PVNN_TERM_CPU1P3V3_AUXP3V3_AUX
SMBUS - CPU0 &1 S3M SMBUS236
21515416119122723123324545236236451423645236236451423623614236236236236
23615 23623623624024124024123623614461546
236236
TP_SMB_S3M_CPU1_ENPCA9517ADSMLFSMB_S3M_CPU1_3V3AUX_SCL1/16W0402LF1%0402LF0402LF10K1%1/16WRST_SMB_SWITCH_NSMB_S3M_CPU0_PIROM_3V3AUX_SCL_RSMB_S3M_CPU1_PIROM_3V3AUX_SDASMB_S3M_CPU1_PIROM_3V3AUX_SCLSMB_S3M_CPU0_PIROM_3V3AUX_SDASMB_S3M_CPU1_PIROM_3V3AUX_SDASMB_S3M_CPU1_PIROM_3V3AUX_SCLSMB_S3M_CPU0_PIROM_3V3AUX_SDASMB_S3M_CPU0_PIROM_3V3AUX_SCL
0402LF1/16WSMB_S3M_CPU0_PIROM_3V3AUX_SDA_RSMB_S3M_CPU1_3V3AUX_SDASMB_S3M_CPU1_3V3AUX_SCL2K5%1/16WEMPTYX7R04021/16W1%CHIP CHIP0402LF560
SMLFPCA9545APWCHIPSMB_S3M_CPU0_3V3AUX_SCLCHIP5%05%SMB_S3M_CPU0_3V3AUX_SDA1%CHIP1/16W1%SMB_S3M_CPU1_3V3AUX_SDASMB_S3M_CPU1_R_SDASMB_S3M_CPU0_SCLSMB_S3M_CPU0_3V3AUX_SCLSMB_S3M_CPU0_3V3AUX_SDATP_SMB_S3M_CPU0_ENIC0402LF240CHIP X7R10%ICSMLFPCA9517AD2401%1/16WCHIP1%24010%25VX7R040204020.1UF10%25V0402LF1%10%25VX7R0.1UF04020402LFCHIP1/16W5605601%1/16W00402LF1/16W0EMPTY5%5601%CHIP0402LF2K1%CHIP2KCHIPCHIP1%2KCHIPCHIPCHIP1/16W005%0402ICPCA9543_S3M_ADDR1RST_SMB_S3M_NPCA9545_S3M_INT_NSMB_S3M_CPU_3V3AUX_SDASMB_S3M_CPU_3V3AUX_SCLPCA9543_S3M_ADDR010K1%1%CHIP1K0402LFCHIP5%00.1UFX7R10%25VCHIP0402LF1/16WCHIP1%10K1%1/16WCHIP0402LF 0402LF10K1%10K1%10K1/16WCHIP0402LF05%CHIPCHIP005%5%5%0CHIPCHIP5%0SMB_S3M_CPU1_3V3AUX_SDA_RPCA9543_S3M_INT1_N1/16W0402LFSMB_S3M_CPU0_PIROM_3V3AUX_SCLSMB_S3M_CPU0_R_SDA0.1UFSMB_S3M_CPU0_R_SCLCHIP0402LF1/16W0402LFSMB_S3M_CPU1_SCL33.21%240CHIP0402LFSMB_S3M_CPU1_R_SCL25V0.1UF1%1/16WCHIPSMB_S3M_CPU0_SDACHIP1%33.2SMB_S3M_CPU1_SDA1%CHIP33.233.21%CHIP
PCA9543_S3M_INT2_N1/16W1/16WEMPTY0402LF1%1K1/16W0402LF1%1/16W10KPCA9543_S3M_ADDR1PCA9543_S3M_ADDR0EMPTYCHIPSMB_S3M_CPU1_PIROM_3V3AUX_SCL_RSMB_S3M_CPU1_PIROM_3V3AUX_SDA_RPCA9543_S3M_INT3_NSMB_S3M_CPU0_3V3AUX_SCL_RSMB_S3M_CPU0_3V3AUX_SDA_RPCA9543_S3M_INT0_NSMB_S3M_CPU1_3V3AUX_SCL_R
R3126
R3125
R3123
R3124
R2211
R2210
R2209
R2208
R996
R994
R3223
R3222
R3224
R3225
R2313
R995
R993
R448 R1648
10
20
19
15
12
8
5
18
16
13
9
6
3
14
11
7
417
2
1
81
63
72
4 5
81
63
72
4 5
U143
U31
U30
GND
SCLB
SDABSDAA
SCLA
VCCBVCCA
ENABLE
GND
SCLB
SDABSDAA
SCLA
VCCBVCCA
ENABLE
INT3#
SC3
SD3
INT2#
SC2
SD2
INT1#
SC1
SD1
INT0#
SC0
SD0
VDD
VSS
SDA
SCL
INT#
RESET#
A1
A0
21
21
21 21
21 21
21 21
21 21
2
1
2
1
2
1
2
1
2
1
21
2
1
2
1
2
1
2
1
2
1
21 21
21 21
21
2
1
2
1
21
2
1
2
1
2
1
2
1
2
1
2
1
2
1
R978
2
1
R980
2
1
2
1
R977
2
1
R979
2
1
R970 R972
R969 R971
C568 C570
C567 C569
SHEETDATE
DEPARTMENT
SIZE
PROJECT DOCUMENT NUMBER REV
REVIEWER
DESIGNER
123
7 3 2 1 6 5 4
E
A
B
C
E
D
C
B
A
7 6 5 4
D
IN
OUTOUT
IN
OUT
BI
BI
OUT
BI
OUT
BI
BI
OUT
IN
BI
OUT
OUTOUT
OUT
BIOUT
OUTBI
INBI
IN
IN
R3131R3130R3127R2315R2312
R2311R2309
R2308 R2310
C1613
C



20210904 MODIFY FOR GT
Fri Aug 25 14:04:01 2023N/AN/AN/AN/AV05237 OF 312
P3V3P3V3_AUXP3V3
SMBUS - ISOLATED
2372372062062412412372372112111/16W0402LF10%PCA9617ADPX7R0.1UFSMB_HOST_CLK_BUF_ISO_3V3AUX_SCL_R0402LF33.2 CHIPSMB_HOST_CLK_BUF_ISO_3V3AUX_SDASMB_HOST_CLK_BUF_ISO_3V3AUX_SDA_R33.21%CHIPCHIPEMPTY25VSMB_HOST_CLK_BUF_ISO_3V3AUX_SCLCHIP1%0402LF10K1/16W0402LF 1/16WCHIP33.21%CHIP33.21%SMB_HOST_DB2000_3V3AUX_SCLSMB_HOST_DB2000_3V3AUX_SDASMB_HOST_CLK_BUF_3V3AUX_SDASMB_HOST_CLK_BUF_3V3AUX_SCL0402X7RPU_CLK_BUF_ISO_EN4.7K5%IC1/16W5%10%25V0.1UF0402LF4.7KSMB_HOST_CLK_BUF_ISO_3V3AUX_SCLSMB_HOST_CLK_BUF_ISO_3V3AUX_SDA1%33.21/16WCHIP1%33.2SMB_HOST_9ZXL045_3V3AUX_SDA0402LFCHIPSMB_HOST_9ZXL045_3V3AUX_SCLSMLF1%1/16W0402
R4541
R4540
R4500 R4499R4498
81
63
72
4 5
U315
GND
SCLB
SDABSDAA
SCLA
VCCBVCCA
EN
21
21
2
1
21 21
21 21
2
1
2
1
2
1
2
1
R4496R4497
R4481R4480
SHEETDATE
DEPARTMENT
SIZE
PROJECT DOCUMENT NUMBER REV
REVIEWER
DESIGNER
123
7 3 2 1 6 5 4
E
A
B
C
E
D
C
B
A
7 6 5 4
D
BI
OUT
INBI OUTBI
OUTBI
IN
BI
C2338C2337
C



20210818 MODIFY FOR GT
Fri Aug 25 14:04:04 2023N/AN/AN/AN/AV05238 OF 312
P3V3_OCP_V3_2P3V3_OCP_V3_2P3V3_OCP_SFFP3V3_OCP_SFFP3V3_AUXP3V3_AUX
SMBUS - ISOLATED
240241159159240241 153153158 156 157240241164 162 163240241SMB_OCP_SFF_3V3AUX_SCLSMB_OCP_V3_2_3V3AUX_BUF_SCLSMB_OCP_V3_2_3V3AUX_BUF_SDAHP_LVC3_OCP_V3_2_R_ENSMB_OCP_SFF_3V3AUX_SDAX7R10%PCA9617ADP0.1UF0.1UF10%SMLFCHIP1/16W4.7K1/16WCHIP0402LF4.7K5%1/16WCHIP0402LF1/16W5%4.7K4.7K5%0402LFCHIP5%0402LFSMB_OCP_SFF_3V3AUX_BUF_SDA0.1UF25VSMB_OCP_SFF_3V3AUX_BUF_SCLHP_LVC3_OCP_V3_1_ENCHIPHP_LVC3_OCP_V3_1_R_ENSMB_OCP_V3_2_3V3AUX_SDA0HP_LVC3_OCP_V3_2_EN0402LF5%1/16WCHIP0PCA9617ADP25VX7R040210%0402ICSMLF0.1UF10%X7R25V04025%1/16W0402X7RIC0402LF25VSMB_OCP_V3_2_3V3AUX_SCL
R3500 R3501
R3263
R3264
81
63
72
4 5
81
63
72
4 5
U236
U235
GND
SCLB
SDABSDAA
SCLA
VCCBVCCA
EN
GND
SCLB
SDABSDAA
SCLA
VCCBVCCA
EN
2
1
2
1
2
1
2
1
2
1
21
2
1
2
1
2
1
21
SHEETDATE
DEPARTMENT
SIZE
PROJECT DOCUMENT NUMBER REV
REVIEWER
DESIGNER
123
7 3 2 1 6 5 4
E
A
B
C
E
D
C
B
A
7 6 5 4
D
OUT
BI
IN
IN
OUT
BI
IN
IN
BI
BI
R3519 R3520
C1862C1860
C1861C1859
C



NO TO COM,COM TO NOOFFONCOM TO NCNC TO COM,ONOFFHINLFUNCTION TABLE20210607 MODIFY FOR GTFri Aug 25 14:04:06 2023239 OF 312V05N/AN/AN/AN/AP3V3_AUXP3V3_AUXP3V3_AUXP3V3_AUXP1V05_PCH_AUXP3V3_AUXP3V3_AUXP3V3_AUX
P3V3_AUX
P3V3_AUX
SCM REMOTE JTAG LOGIC221239221239248248248248 221221134239131132132131131132131203131132131132214239215239239215
214 240240NX3L2267GMSMLFICJTAG_BMC_PLD_TDIJTAG_BMC_DBP_TDOJTAG_BMC_PLD_TDOJTAG_BMC_DBP_TDIJTAG_BMC_SW_TDIJTAG_BMC_SW_TCKJTAG_BMC_SW_TMSJTAG_BMC_SW_TDO0.1UFX7R25V10%04020402LF0402LFJTAG_BMC_PLD_TCKJTAG_BMC_PLD_TMSJTAG_BMC_DBP_TCKJTAG_BMC_DBP_TMSJTAG_DBP_PRDY_NJTAG_DBP_TDOJTAG_DBP_PRDY_R_NJTAG_DBP_FB_TDOJTAG_DBP_PREQ_NFM_CPU_FBRK_DEBUG_NJTAG_DBP_TDIJTAG_DBP_TMSJTAG_DBP_PREQ_R_NJTAG_DBP_FB_TDIJTAG_DBP_FB_TMSP0V7_JTAG_VREF_2PD_GTL2014_BMC_JTAG_DIR_2TP_JTAG_BMC_A0JTAG_DBP_BMC_PRDY_R1_NTP_JTAG_BMC_A2JTAG_BMC_DBP_TDO_RPD_JTAG_DBP_B2PD_JTAG_DBP_B0PD_GTL2014_BMC_JTAG_VREF_1PU_GTL2014_BMC_JTAG_DIR_1JTAG_DBP_BMC_PREQ_R1_NFM_BMC_CPU_FBRK_OUT_NJTAG_BMC_DBP_TDI_RJTAG_BMC_DBP_TMS_RJTAG_BMC_DBP_TDOJTAG_DBP_BMC_PRDY_R_NJTAG_BMC_DBP_TDIJTAG_BMC_DBP_TMSJTAG_DBP_BMC_PREQ_R_N
FM_JTAG_BMC_MUX_SELJTAG_DBP_BMC_PRDY_NJTAG_BMC_DBP_PREQ_N
0402LF1%1/16WEMPTY1KEMPTY1/16W1%10K0402LF1001%CHIP0402LF 1/16W1%100CHIP1/16W1K1%CHIP1/16WCHIP0402LF1K1%05%CHIP5%0CHIP1/16W05%0402LFCHIPGTL2014PWICSMLFC040210%25V1UFX6SSMLFICGTL2014PWC040210%X6S25V1UF1/16WCHIP33.21%0CHIP5%0402LFCHIP1/16W49.91%0CHIP5%0402LF1001%CHIP1/16WX7R 0402 25V0.1UF10%0EMPTY1/16W0402LF5%0402LFCHIP1K1%1/16W0402LFCHIP1/16W1%1KCHIP1%33.21/16W0402LF05%CHIP5%CHIP01%1K1/16W0402LFCHIP1%1KEMPTY0402LFCHIP1%1K1/16W00402LF 1/16W5%EMPTY1K0402LF1%1/16WCHIP1/16W1%0402LFCHIP1K
0.1UF25VX7R10%0402
1/16W1%1KCHIP0402LFCHIP0402LF1/16W1%1K
ICNX3L2267GMSMLFFM_JTAG_BMC_MUX_SEL == HIGH , BMC TO CPU/PCHFM_JTAG_BMC_MUX_SEL == LOW (DEFAULT) , BMC TO CPLD
GTL2014
GTL2014
C1664
R2513
R2514
R2507R2506
R1831
R1832
R1813
R1367
R1366
R3056
R1346
R3057
R480
R481
R482
R483
R1184
R1345
R1347
10
5
6 4
37
9 2
18
4
14
11
8
7
1
6
5
3
2
9
10
12
13
10
5
6 4
37
9 2
18
4
14
11
8
7
1
6
5
3
2
9
10
12
13
U83
U84
U96
U97
2Y0
1S
1Z
2Y1
2S
1Y1
GND
1Y0
2Z
VCC
VCC
VREF
DIR
A0
A1
A2
A3
GND_0
GND_1
GND_2
B3
B2
B1
B0
2Y0
1S
1Z
2Y1
2S
1Y1
GND
1Y0
2Z
VCC
VCC
VREF
DIR
A0
A1
A2
A3
GND_0
GND_1
GND_2
B3
B2
B1
B0
212
1
21
21
21
21
2
1
2
1
R1814
21
21
21 21
21
2
1C1321
2
1
2
1
2
1
21
21
21
2
1
2
1
2
1
2
1
21 21
21
2
1
21
2
1
2
1
DESIGN NOTE:
SHEETDATE
DEPARTMENT
SIZE
PROJECT DOCUMENT NUMBER REV
REVIEWER
DESIGNER
123
7 3 2 1 6 5 4
E
A
B
C
E
D
C
B
A
7 6 5 4
D
OUTOUT
OUT
OUT
OUT
IN
IN
OUT
IN
IN
IN
OUTOUTOUTOUT
OUT
IN
IN
IN
IN
IN
ININ
OUT
OUT
OUT
IN
R2512
R1368 R1369
R1380
C1322
R1382
R3055
R1381 R1383
C1290
C1291
C



20221222 CHANGE R2415,R2416 TO 0 OHMSPI FROM MB TO SCM_BIOS FLASH20210705 MODIFY FOR GT
20221222 CHANGE R2413,R2414 TO 0 OHMSPI FROM SCM TO MB FPGA20230323 ADD R4809 CONNECT TO GND.Fri Aug 25 14:04:07 2023N/AN/A V05N/A240 OF 312N/A
PVNN_TERM_CPU0P12V_SCM P12V_SCM
SCM CONNFM_JTAG_BMC_MUX_SEL_FROM_BMC_R2
0402LF0245TP_HPM_STBY_ENFM_UARTSW_MSB_RRST_PLTRST_B_NJTAG_DBP_BMC_PRDY_NJTAG_BMC_DBP_PREQ_NPWRGD_SYS_PWROKFM_BMC_PWRBTN_OUT_R_N
PVCCIO_PECI_BMC33.2CHIPFM_UARTSW_LSB_RP2E_MB_BMC_RX_BUF_DN<0>FM_BMC_INTRUDER_NIRQ_SMI_ACTIVE_BMC_NFM_UARTSW_LSB_NROT_P1_RST_IND_N_RFM_UARTSW_MSB_NFM_BMC_PWRBTN_OUT_NPWRGD_PS_PWROKSMB_S3M_CPU_3V3AUX_SCLSMB_1_BMC_GPU_SDASMB_1_BMC_GPU_SCLFM_JTAG_BMC_MUX_SEL_FROM_BMC_RSMB_S3M_CPU_3V3AUX_SDAFM_BMC_INTRUDER_NIRQ0_A57ROT_P1_RST_IND_NRST_MB_STBY_NPWRGD_PS_PWROK_RSMB_S3M_CPU_3V3AUX_SDA_R0CLK_100M_BMC_RC_DNUSB3_PCH_RX_DP<4>FM_SCM_PRSNT1_NUSB3_PCH_RX_DN<4>TP_PCIE_HPM_RXN[1]CLK_100M_BMC_RC_DPSMB_PCIE3_3V3AUX_SDA_RSMB_PCIE3_3V3AUX_SCL_RSMB_S3M_CPU_3V3AUX_SCL_R0P2E_MB_BMC_RX_BUF_DP<0>TP_PCIE_HPM_RXP[1]IRQ_SGPIO_INTR_NP3V_BAT_R1FM_AC_PWR_BTN_NTP_SPI_2_PLD_CLKTP_SPI_2_PLD_CS_NTP_SPI_2_PLD_IO0TP_SPI_2_PLD_IO1TP_SPI_2_PLD_IO2RST_SGPIO_RESET_NTP_SPI_2_PLD_IO3USB2_8_DNUSB2_HOST_BMC_B_DNUSB2_8_DPUSB2_HOST_BMC_B_DPUSB3_PCH_TX_BUF_C_DN<4>USB3_PCH_TX_BUF_C_DP<4>USB2_HUB_2_BUF_EXT_DNUSB2_HUB_2_BUF_EXT_DPTP_PCIE_HPM_TXN[1]TP_PCIE_HPM_TXP[1]P2E_MB_BMC_TX_C_DP<0>TP_PCIE_HPM_TXP[3]P2E_MB_BMC_TX_C_DN<0>TP_PCIE_HPM_TXN[3]P3V_BAT_RFM_AC_PWR_BTN_R_NLED_HDD_ACTIVITY_B_NFM_PCH_SPKRSGPIO_LD_1JTAG_BMC_TDOSMB_2_BMC_GPU_SCLSMB_OCP_SFF_3V3AUX_SCLSMB_SML1_PMBUS_3V3AUX_PCH_SDASMB_SML0_3V3AUX_SDASMB_2_BMC_GPU_SDASMB_OCP_SFF_3V3AUX_SDASMB_HOST_3V3AUX_SCLSMB_HOST_3V3AUX_SDASMB_OCP_V3_2_3V3AUX_SCLSMB_SML1_PMBUS_3V3AUX_PCH_SCLSMB_1_PLD_3V3AUX_SDASMB_1_PLD_3V3AUX_SCLCLK_100M_BMC_P3E_DNCLK_100M_BMC_P3E_DPSMB_OCP_V3_2_3V3AUX_SDASMB_SML0_3V3AUX_SCLSMB_VR_SENSOR_3V3AUX_SCLSMB_VR_SENSOR_3V3AUX_SDASMB_PCIE2_3V3AUX_SDA_R0SMB_PCIE2_3V3AUX_SCL_R0JTAG_BMC_TMSSMB_FAN_3V3AUX_SDASMB_FAN_3V3AUX_SCLSMB_OCP_SFF_3V3AUX_SCL_R0VIRTUAL_RESEATSMB_1_PLD_3V3AUX_SDA_R3JTAG_BMC_TDISMB_1_PLD_3V3AUX_SCL_R3SMB_SML0_3V3AUX_SCL_R1SMB_PCIE0_3V3AUX_SDASMB_OCP_V3_2_3V3AUX_SDA_R0CLK_100M_BMC_P3E_DN_RP3E_PCH_BMC_TX_C_DNP3E_PCH_BMC_TX_C_DPJTAG_BMC_TCKSMB_SML0_3V3AUX_SDA_R1SMB_PCIE0_3V3AUX_SCLP3E_PCH_BMC_RX_DNP3E_PCH_BMC_RX_DPCLK_100M_BMC_P3E_DP_RSMB_OCP_V3_2_3V3AUX_SCL_R0I3C_BMC_SWB_SDAI3C_BMC_SWB_SCLSMB_SML1_PMBUS_3V3AUX_PCH_SDA_R0SMB_SML1_PMBUS_3V3AUX_PCH_SCL_R0SMB_VR_3V3AUX_SDA_R0SMB_VR_3V3AUX_SCL_R0SMB_HOST_3V3AUX_SDA_R0I3C_SPD_DDRABCD_CPU1_BMC_R_SCLI3C_SPD_DDREFGH_CPU0_BMC_R_SDAI3C_SPD_DDRABCD_CPU1_BMC_R_SDAI3C_SPD_DDREFGH_CPU1_BMC_R_SDAI3C_SPD_DDRABCD_CPU0_BMC_R_SCLI3C_SPD_DDRABCD_CPU0_BMC_R_SDAI3C_SPD_DDREFGH_CPU0_BMC_R_SCLI3C_SPD_DDREFGH_CPU1_BMC_R_SCLRMII_OCP_BMC_RXD_0SGPIO_LD_0SGPIO_DO_1SGPIO_CLK_1SGPIO_DI_1PRSNT0_NFM_SOL_UART_CH_SEL_RUSB2_7_R_DNIRQ_ESPI_LPC_SERIRQ_ALERT_R_NESPI_LPC_LAD0_IO1FM_LPC_ESPI_SELSPI_SYS_HOLD_IO3RMII_OCP_BMC_CRSDVRST_SRST_PLD_BMC_NESPI_BMC_LPC_RST_NESPI_LPC_LAD0_IO0ESPI_LPC_LAD0_IO2ESPI_LPC_LAD0_IO3SPI_SYS_CLKSPI_SYS_CS0_NSPI_SYS_MOSISPI_SYS_MISOSPI_SYS_WP_IO2USB2_7_R_DPUART_BMC_BIC_BUF_RXUART_BMC_BIC_TXESPI_HOST_LPC_BMC_CLKSPI_TPM_CS_NH_CPU_CATERR_LVC2_BMC_NESPI_HOST_LPC_BMC_LFRAME_NSGPIO_CLK_0SGPIO_DI_0SGPIO_DO_0RMII_BMC_OCP_TXD_0RMII_BMC_OCP_TXD_1RMII_BMC_OCP_RX_ERRMII_OCP_BMC_RXD_1PVCCIO_PECI_BMCPECI_BMCRMII_BMC_OCP_TX_ENCLK_50M_RMII_BMC_OCPUSB2_7_DPUSB2_7_DNFM_SOL_UART_CH_SELSMB_OCP_SFF_3V3AUX_SDA_R0SMB_HOST_3V3AUX_SCL_R0
05%CHIP1/16W0402LF205214240220 215240214219182222223223241234234241236241241236214228214CHIP05%CHIP5%0CHIP5%00CHIP5%1%CHIP33.233.21%CHIP5%0CHIP5%0CHIP5%CHIP05%0CHIP1%33.2 CHIP2122121671671691692422232392392481671671691691961960EMPTYEMPTY0402LF05%1/16W1801801521522222222221/16W0CHIP1/16W0402LF05%CHIP214198185214190245224185234241241234241241241241179179241238238241241 183183 24123323324124124123823824122UFX6SC04024V20%CHIP5%1/16WCHIP5%0CHIP05%33.21%CHIP1%33.2 CHIP1%33.2 CHIP33.21%CHIP10CHIP10 1%1%33.2 CHIP33.21%CHIPCHIP1%1%CHIP33.2CHIP1%33.2CHIP1%33.21%CHIP33.2CHIP1%0402LF33.21/16WCHIP1%33.2CHIP1%33.2248248248241245241231231181181181181241234234241215240241241241241241241241241222222222222222222222197240154 160154 160154 160154154 1601601541601541551851851851851851852572022022022022022022022020CHIPUART_1 MB TO BMC (BMC SLAVE)UART_2 BMC TO MB (BMC HOST)185226213EMPTY5%01511371/16WEMPTY5%00402LF2141801805%00402LF1/16WCHIPSCONN168_ME1016810202011SMLFIO
R4087
R1801
R2256
R3778
R3239
R3238
R2419
R2994
R4720
R3254
R3302
R1816
R1815
R2415
R2257
R2420
R2423
R2424
R2422
R3858
R2425
R4536
R4535
R2413
R2414
R2416
R2418
R2417
R3776 21R1798
R3777
R2421
OA3
A69
A68
A9
A8
A7
OA6
OB7
B69
B68
OA12 OB12
A15 B15
OA11 OB11
A14 B14
OA8
OA9
OA7
OB8
OB9
OB14OA14
OA5
OA4
A70 B70
A12
A42 B42
A10
B66
B63
B60
B57
B54
B51
B48
B45
B40
B37
B34
B31
B27
B24
B21
B18
B65
B62
B59
B56
B53
B50
B47
B44
B39
B36
B33
B30
B26
B23
B20
B17
OA2
OA1
A11
B10
A66
A63
A60
A57
A54
A51
A48
A45
A40
A37
A34
A31
A27
A24
A21
A18
A65
A62
A59
A56
A53
A50
A47
A44
A39
A36
A33
A30
A26
A23
A20
A17
OB1
OB2
OB3
OB13
OB10
OA13
OA10
B67
B64
B61
B58
B55
B52
B49
B46
B43
B41
B38
B35
B32
B29
B28
B25
B22
B19
B16
B13
A67
A64
A61
A58
A55
A52
A49
A46
A43
A41
A38
A35
A32
A29
A28
A25
A22
A19
A16
A13
A6
A5
A4
A3
A2
A1
G5
G4
G3
G2
G1
OB5
OB4
OB6
B9
B8
B7
B12
B6
B5
B4
B3
B2
B1
B11
R506
J41
KEY
KEY
KEY
G5
G4
G3
G2
G1
PRSNTB3#
RFU1_NC_B69
RFU1_NC_B68
GND_B67
PETp15
PETn15
GND_B64
PETp14
PETn14
GND_B61
PETp13
PETn13
GND_B58
PETp12
PWRBRK0#
USB_DATp
USB_DATn
GND_A67
PERp15
PERn15
GND_A64
PERp14
PERn14
GND_A61
PERp13
PERn13
GND_A58
PERp12
PERn12
GND_A55
PERp11
PERn11
GND_A52
PERp10
PERn10
GND_A49
PERp9
PERn9
GND_A46
PERp8
PERn8
GND_A43
PRSNTB1#
GND_A41
PERp7
PERn7
GND_A38
PERp6
PERn6
GND_A35
PERp5
PERn5
GND_A32
PERp4
PERn4
GND_A29
GND_A28
PERp3
PERn3
GND_A25
PERp2
PERn2
GND_A22
PERp1
PERn1
GND_A19
PERp0
PERn0
GND_A16
REFCLKp1
REFCLKn1
GND_A13
PRSNTB2#
PERST1#
PRSNTA#
SMRST#
SMDAT
SMCLK
GND_A6
GND_A5
GND_A4
GND_A3
GND_A2
GND_A1
RBT_CLK_IN
GND_OA13
REFCLKp3
REFCLKn3
GND_OA10
RBT_TXD0
RBT_TXD1
RBT_TX_EN
SLOT_ID1
RBT_ARB_OUT
RBT_ARB_IN
WAKE#
PERST3#
PERST2#
PETn12
GND_B55
PETp11
PETn11
GND_B52
PETp10
PETn10
GND_B49
PETp9
PETn9
GND_B46
PETp8
PETn8
GND_B43
PRSNTB0#
GND_B41
PETp7
PETn7
GND_B38
PETp6
PETn6
GND_B35
PETp5
PETn5
GND_B32
PETp4
PETn4
GND_B29
GND_B28
PETp3
PETn3
GND_B25
PETp2
PETn2
GND_B22
PETp1
PETn1
GND_B19
PETp0
PETn0
GND_B16
REFCLKp0
REFCLKn0
GND_B13
AUX_PWR_EN
+3.3V_EDGE
PERST0#
BIF2#
BIF1#
BIF0#
+12V_EDGE_B6
+12V_EDGE_B5
+12V_EDGE_B4
+12V_EDGE_B3
+12V_EDGE_B2
+12V_EDGE_B1
RBT_CRS_DV
GND_OB13
REFCLKp2
REFCLKn2
GND_OB10
RBT_RXD0
RBT_RXD1
SLOT_ID0
CLK
DATA_OUT
DATA_IN
LD#
MAIN_PWR_EN
NIC_PWR_GOOD 2
1
21
21
21 21
21
21 21
21 21
21 21
21
21
2
1
21
21
21 21
21
21 21
21 21
21R4506 21R4507
21R4509
21R4508
21 21
21R142
2
1
21
21 21
21
21
21
DESIGN NOTE:
SHEETDATE
DEPARTMENT
SIZE
PROJECT DOCUMENT NUMBER REV
REVIEWER
DESIGNER
123
7 3 2 1 6 5 4
E
A
B
C
E
D
C
B
A
7 6 5 4
D
IN
BI
IN
BIBIBIBIBIBIBI
BIBI
IN
IN
IN
BIBI
BIBI
BIBI
INOUT
IN
OUT
IN
OUT
OUTIN
BIBI
BIBI
OUT
BIBI
ININ
ININ
IN
IN
OUTININ
OUT
OUTOUT
ININ
IN
IN
IN
BI
OUT
BI
OUT
OUTIN
IN
ININ
IN
OUTIN
BIINBIBIBIBIIN
BI
ININ
IN
ININ
IN
ININOUTOUT
BI
OUTOUT
ININ
OUTBI
OUTOUTINOUT
BI
OUTOUTIN
BIBI
BIBI
BIBI
BI
BIBI
OUT
OUT
BIBI
ININ
OUTOUT
OUT
BIBI
BIBI
OUT
OUTOUT
OUT
R4809
C1302
C



HSC20220113 CHANGE NET NAMEI3CVRME NODEME NODEPCHPCHVR_PU1420220105 CHANGE NET NAMEVR_PU5Fri Aug 25 14:04:08 2023V05241 OF 312N/AN/AN/AN/A
P3V3_AUX
SCM SMBUS BUSSMB_PMBUS_SML1_ME_SDA214266 284241131241213240241240241131213241240241240241241241208241241208 212212240236236240234240240234240234240238238240238240240245240241240241240245240241183240241240241240183241234240240234240238240240240240240240240240230230230230229229229229240240241292296241292296233233213213274 278240241183183240241228241 301305301305228183183228228241131213241131213241241183234240241250250214266 284274 278228241292 296241292 296183240241240241183240241240241241228183237237208241208241
SMB_2_PLD_3V3AUX_SCL_R11/16WSMB_VR_3V3AUX_SDA_R3CHIP1/16W0402LF0402LF0402LFSMB_SML1_PMBUS_HSC_SCL_R30CHIP5%CHIPCHIPCHIPCHIP33.233.21/16W1/16W1/16W0402LF0402LF1/16W33.233.20402LF0402LFSMB_HOST_3V3AUX_SCL_R4SMB_HOST_3V3AUX_SDASMB_HOST_3V3AUX_SCLSMB_HOST_3V3AUX_SDA_R4SMB_HOST_3V3AUX_SDASMB_HOST_3V3AUX_SCLSMB_HOST_3V3AUX_SCL_RSMB_HOST_3V3AUX_SDA_RPLACE SMBUS SERIES RESISTOR CLOSE TO THE PCHSMB_HOST_CLK_3V3AUX_SDASMB_HOST_CLK_3V3AUX_SCL SMB_HOST_CLK_GEN2_3V3AUX_SCLSMB_HOST_CLK_GEN2_3V3AUX_SDA0402LFCHIPCHIP5%SMB_S3M_CPU_3V3AUX_SCLSMB_S3M_CPU_3V3AUX_SDASMB_2_BMC_GPU_SCLSMB_2_BMC_GPU_SDASMB_1_BMC_GPU_SDASMB_OCP_SFF_3V3AUX_SCL0402LF1/16W2.2K2.2KEMPTYEMPTY5%2.2K2.2K2.2K1/16W1/16WEMPTYEMPTYEMPTYEMPTYEMPTY0402LF5%5%0402LF 1/16W5%5%1/16WSMB_OCP_V3_2_3V3AUX_SDASMB_OCP_SFF_3V3AUX_SDASMB_FAN_3V3AUX_SDAEMPTY2.2KSMB_HOST_3V3AUX_SDASMB_HOST_3V3AUX_SCL1%2K1/16W1%2KSMB_FAN_3V3AUX_SCLSMB_SML0_3V3AUX_SDA1%1/16W2K1%0402LF0402LF2KSMB_SML1_PMBUS_3V3AUX_PCH_SDASMB_SML0_3V3AUX_SCLSMB_SML1_PMBUS_3V3AUX_PCH_SCL2K1/16W1%0402LF0402LF 1/16W5%2.2K2.2KEMPTYEMPTY5%5%5%EMPTY1/16W0402LF
EMPTYEMPTYEMPTYEMPTYEMPTYEMPTY2.2K5%2.2K5%0402LF2.2K0402LF5%EMPTY2.2KI3C_BMC_SWB_SDAI3C_BMC_SWB_SCL2.2K5%EMPTYSMB_OCP_V3_2_3V3AUX_SCLCHIP05%CHIP05%0CHIP5%5%0CHIP5%0CHIP5%0CHIPCHIP05%CHIP05%I3C_SPD_DDREFGH_CPU1_BMC_R_SCLI3C_SPD_DDREFGH_CPU1_BMC_R_SDAI3C_SPD_DDRABCD_CPU1_BMC_R_SDAI3C_SPD_DDRABCD_CPU1_BMC_R_SCLI3C_SPD_DDREFGH_CPU0_BMC_R_SDAI3C_SPD_DDREFGH_CPU0_BMC_R_SCLI3C_SPD_DDRABCD_CPU0_BMC_R_SDAI3C_SPD_DDRABCD_CPU0_BMC_R_SCLI3C_SPD_DDREFGH_CPU1_BMC_SDAI3C_SPD_DDREFGH_CPU1_BMC_SCLI3C_SPD_DDRABCD_CPU1_BMC_SDAI3C_SPD_DDRABCD_CPU1_BMC_SCLI3C_SPD_DDREFGH_CPU0_BMC_SDAI3C_SPD_DDREFGH_CPU0_BMC_SCLI3C_SPD_DDRABCD_CPU0_BMC_SDAI3C_SPD_DDRABCD_CPU0_BMC_SCL1%CHIP33.20402LFCHIP33.21%CHIP33.2CHIP1%33.21%33.233.20402LF33.2 CHIP1%33.2 CHIP1%33.2 CHIP1%1/16W1%33.2 CHIPCHIP33.21%SMB_1_PLD_3V3AUX_SDASMB_1_PLD_3V3AUX_SCLSMB_VR_3V3AUX_SDA_RSMB_VR_3V3AUX_SCL_RSMB_VR_3V3AUX_SCLSMB_VR_3V3AUX_SDASMB_1_PLD_3V3AUX_SCL_R1SMB_1_PLD_3V3AUX_SDA_R1SMB_VR_3V3AUX_SDA_R21/16W1%33.2SMB_SML1_PMBUS_3V3AUX_PCH_SCLSMB_SML1_PMBUS_3V3AUX_PCH_SDA1/16W0402LF0402LF 1/16W33.21%SMB_SML1_PMBUS_HSC_SDA_R3 SMB_SML1_PMBUS_HSC_SDASMB_SML1_PMBUS_HSC_SCLCHIP33.21%1%33.20402LF0402LF 1/16W1%33.233.21%SMB_SML0_ME_SDA1%CHIP33.20402LFCHIP1%0CHIP5%33.21%CHIP1%CHIP33.20402LF33.21%33.21%1%033.21%CHIP1%1/16W33.2SMB_HOST_BMC_3V3AUX_SDASMB_HOST_BMC_3V3AUX_SCLCHIP1/16WCHIPSMB_HOST_3V3AUX_SDA_R5SMB_HOST_3V3AUX_SCL_R5SMB_HOST_3V3AUX_SDA_RCHIP1/16W1%33.25%CHIP0SMB_HOST_3V3AUX_SCL_R4SMB_HOST_3V3AUX_SDA_R4SMB_HOST_3V3AUX_SCL_RCHIP0402LF1/16WSMB_SML0_3V3AUX_PCH_SDASMB_1_BMC_GPU_SCLCHIP33.21%SMB_SML1_PMBUS_HSC_SDA_R30402LF2.2K5%EMPTY1%2K
SMB_VR_3V3AUX_SDA_R1SMB_VR_3V3AUX_SCL_R11%33.2 CHIP0402LFCHIP1%1/16WCHIP1%1/16W33.2SMB_2_PLD_3V3AUX_SDA_R1SMB_VR_3V3AUX_SCL_R3SMB_VR_3V3AUX_SCL_R21%SMB_PMBUS_SML1_ME_SCLSMB_VR_3V3AUX_SCL_RSMB_VR_3V3AUX_SDA_RCHIP1/16WSMB_SML1_PMBUS_3V3AUX_PCH_SDASMB_SML1_PMBUS_3V3AUX_PCH_SCLSMB_SML0_3V3AUX_SDASMB_SML0_3V3AUX_SCL1%CHIPSMB_SML1_PMBUS_HSC_SCL_R3SMB_SML0_ME_SCLSMB_SML0_3V3AUX_PCH_SCLSMB_HOST_CLK_BUF_3V3AUX_SDASMB_HOST_CLK_BUF_3V3AUX_SCLSMB_HOST_CLK_3V3AUX_SDASMB_HOST_CLK_3V3AUX_SCLCHIP1%1/16W
R4513
R4512
R4151
R4152
R4149
R4150
R3340
R3341
R1336
R1460
R1387
R1386
R1385
R1384
R3062
R1319
R592
R601
21R600
21R599
21R597 21R598
21R595 21R596
21R594
21R593
21 21
21R578
21R577
21R4531
21
21R4510 21R4511
21 21
21 21
21 21
21 21
21 21
21R3226 21R3227
21 21
21R3060 21R3061
21R2999 21R3004
21 21
21 21
21 21
21 21
21R2213
21R2212
21 21
21 21
21R1662
21R1661
21R582
21R581
21 21
21 21
21R580
21R579
21 21
21 21
21 21
CAD NOTE:
R4530
R3243R3242
R3240R3241
R3059R3058
R2996R2995
R2453R2454
R2455R2456
R2450R2449
R107R108
R1526R1525
SHEETDATE
DEPARTMENT
SIZE
PROJECT DOCUMENT NUMBER REV
REVIEWER
DESIGNER
123
7 3 2 1 6 5 4
E
A
B
C
E
D
C
B
A
7 6 5 4
D
BIOUT
OUTOUT
BIIN
BIIN
BIIN
BIIN
BIIN
BIIN
BIIN
BIOUT
BIOUT
BI
BI
OUTBIIN
BIOUTBI
OUT
IN
BIIN BIOUT
BI
BIOUTBIIN
OUT
BIOUT
OUTBIINBI
OUTBIINBI
BIBI
BIBI
OUTOUT
OUTBI
BIIN BIOUT
OUTOUT
BI
OUTBI
OUT
BIIN OUT BI
BI
BIOUT
BIOUT
OUT
OUT
OUT
BI
OUTOUT
OUT
OUTOUT
BIOUT
OUTOUT
OUT
INBI
OUT
C



PC2239 DE-POPSTART UP TIME:8.21MSVIMON(MAX)= 1.563V @ IOUT=5.34ATFAULT: 1.27MSVIMON(MAX)= 1.610V @ IOUT=5.35ASTART UP TIME:8.62MSDE-POPMP5025A/MP5022APOPDE-POPMP5022CPU299 OPTIONAL BOMMP5025C/PR4006DE-POPPOPDE-POPPOPPOPPOPPR4009PR4014PR4010OVP: 14.91VUVP: 10.17V20211116 MODIFY FOR GTDESIGN SPECIFICATIONOCP=MAX*1.3=5.2AP12V_SCM_RIMAX=4A
VTH>1.391V(HIGH)ENABLE:TDELAY: 6.29MSFri Aug 25 14:04:10 2023N/AN/AN/AN/AV05242 OF 312
P12V_SCM_RP3V3_AUXP12V_SCM_RP12V_AUX
P12V_AUXP12V_AUXP3V3_AUXP3V3_AUXP3V3_AUXP12V_AUXP3V3_AUXP12V_SCM242 216242242242 255
213240 24221624225510K1%1/16WHP_LVC3_SCM_HSC_PWRGDSCM_P12V_BOM2 SCM_P12V_BOM249.90402LFP12V_SCM_OV_FBP12V_SCM_AVIN_PD1/16W1%100
C0805X6S22UF16VC080516V10UFX6SX7R25V0.1UFICB340A-13-F1%1%100K0402LFEMPTY1/16W0402LF5%0SCM_P12V_BOM1EMPTYEMPTY1%SCM_P12V_BOM110M1/16W50V3900PF5%SCM_P12V_BOM101/16WC0402EMPTY0.01UF50V1%EMPTYSCM_P12V_BOM1EMPTY1%101/16W0402LFSCM_P12V_BOM1MAX15090BEWI+TEMPTYSMLFSCM_P12V_BOM1EMPTY1UFC040225VEMPTY1/16W160KSCM_P12V_BOM10402LF1%SCM_P12V_BOM11UF25VC04021/16W1%6.8KSCM_P12V_BOM10402LFEMPTYSCM_P12V_BOM117.8K1%EMPTY1/16W0402LF0402LF15KEMPTY1/16W1%SCM_P12V_BOM1040210%0.1UF25VCHIP1/10W1%0603LFC0603X7R20%2.2UF16V1%0402LF120KCHIP1/16W1%EMPTY0402LF0402LF1/16WCHIP1%10KSCM_P12V_BOM20402LF10K1%1/16WCHIP0402LF1/16W5%0SCM_P12V_BOM2CHIP100NFX7RC040250VSCM_P12V_BOM20402LFEMPTYX6SC04021UF25VSCM_P12V_BOM20402LFCHIP1/16W1%30.1KSCM_P12V_BOM2C04020.047UF25VX7R
C04021UF25VX6SSMF14AIC0402LF0EMPTYSCM_P12V_BOM15%1/16WEMPTYSCM_P12V_BOM1PJT138KSMLFSCM_P12V_BOM10402LF10KEMPTY1/16W1%PJT138KSMLFSCM_P12V_BOM1EMPTYSCM_P12V_BOM105%1/16WEMPTY0402LF1/16W1%0402LFCHIP10K0402LF1/16W05%CHIPCHIP 1/16W0SCM_P12V_BOM20402LF5%1%CHIP0402LF20K1/16W1/16W1%24.3K0402LFCHIPSCM_P12V_BOM2ICSMLF16V0.22UF0402X7RSCM_P12V_BOM2X7RC0402560PFSCM_P12V_BOM2100CHIP10K0402LF1/16W1% P12V_SCM_FAULT_NP12V_SCM_PWRGDP12V_SCM_GATEP12V_SCM_SENSEP12V_SCM_UVP12V_SCM_OVP12V_SCM_CBP12V_SCM_REGP12V_SCM_VCC
P12V_SCM_AVIN_PDP12V_SCM_FAULT_R_N
P12V_SCM_UV_RP12V_SCM_EN_GP12V_SCM_EN_RP12V_SCM_ENVIRTUAL_RESEAT_FPGA_NP12V_SCM_ISET_RFM_SCM_PRSNT1_N2N7002KSCM_P12V_BOM2SCM_P12V_BOM20402LF CHIP 1/16WFM_SCM_PRSNT1_R_N1%50VSCM_P12V_BOM2SCM_P12V_BOM11/16W0402LFC04020402LFX7R71.5KSCM_P12V_BOM2SCM_P12V_BOM2P12V_SCM_SSP12V_SCM_ISETP12V_SCM_TIMERP12V_SCM_EN_R2P12V_SCM_FLTB_NSCM_P12V_BOM2ICRS31312RP12V_SCM_IMONCHIPSCM_P12V_BOM2HP_LVC3_SCM_HSC_PWRGD_R0402LF1/16W1.33KSCM_P12V_BOM1EMPTYSCM_P12V_BOM10402SCM_P12V_BOM1100K1/16WEMPTY0402LFHP_LVC3_SCM_HSC_PWRGDP12V_SCM_FAULT_R_NCHIPSCM_P12V_BOM200402LF
G
G2
G1
S DCAS2 D2D1S1
PC2242PC2240
PD116
PC2237A2
D2
D1 D7
D3
D6
D4
C6
C4
B6
B4
A4
A1
D5
C5
C3
B5
B3
A5
A3
C2
C1
B2
A6
C7
B7
A7B1
PU300
2
1 PR4001
2
1 PR4002
2
1 PC2241
2
1 PR4014
2
1 PR4006
5 Q125
2
1
R4071
2
1 PC2238
2
1 PR4526
2
1 PR4003
2
1 PC2340
2
1 PC2236
2
1
PC2233
PC2234
PC2239
PR4010
2
1 PR4009
PC2232
PC2230PD115
21
R3997
2
1 PR3999
PC2229 PR4011
PC2235
PC2231
2
1 PR4005
2 Q125
21
R3998
2
1 PR4540
2
1 PR4008
2
1 PR4000
2
1 PR4004
CA21
4 321CA6
R3836
R4770
R4708
R4709
R4015R4013
PR4012
R4062
R1856
PR4007
20
19
18
17
16
15
14
13
26
25
24
23
21_22
4
6
10
11
2
5
87
9
3
1
12
G
S D1
PU299
Q39
GND
SS
ISET
TIMER
ENTM
LOADEN
EN
VIN_26
VIN_25
VIN_24
VIN_23
IMON
FLTB
PG
OV
VOUT_13
AVIN
VOUT_14
VOUT_15
VOUT_16
VOUT_17
VOUT_18
VOUT_19
VIN_21_22
VOUT_20
S
G
D
PG
FAULT#
GND_C2
GND_C1
GND_B2
CDLY
GATE
OUT_D6
OUT_D4
OUT_C6
OUT_C4
OUT_B6
OUT_B4
OUT_A4
ISENSEOV
UV
REG
EN#
CB
IN_D5
IN_C5
IN_C3
IN_B5
IN_B3
IN_A5
IN_A3
VCC
CA
2
1
21
21
21
2
1
2
1
21
21
2
1
2
1
R1857
21
SHEETDATE
DEPARTMENT
SIZE
PROJECT DOCUMENT NUMBER REV
REVIEWER
DESIGNER
123
7 3 2 1 6 5 4
E
A
B
C
E
D
C
B
A
7 6 5 4
D
OUT
OUT
OUT
OUT
IN
OUT
IN
IN
R1854
R3996
C



FRU ADDR: 0XA220210603 MODIFY FOR GT
Fri Aug 25 14:04:11 2023N/AN/AN/AN/AV05243 OF 312
P3V3_AUXP3V3_AUXP3V3_AUX
MB FRU
2312310402LFMB_FRU_ADDR0MB_FRU_ADDR1MB_FRU_ADDR2SMB_FRU_3V3AUX_SDASMB_FRU_3V3AUX_SCLPD_MB_FRU_WP1/16WEMPTY0402LF1K1%CHIP0402LF1/16W10K1%1%10K1/16WEMPTY0402LFEMPTY1%10K0402LF1/16W0402LF1%1KCHIP1/16W1%1/16WCHIP0402LF1K04020.1UF25V10%X7R4.7K1/16WEMPTY5%0402LF4.7K0402LFEMPTY1/16W5%1%1/16W1KCHIPSMLFM24128-BWMN6TPIC
7
4
8
5
6 3
2
1
U64
E0
E1
E2
VSSSDA
SCL
WC#
VCC
2
1
R1331
2
1
R1332
2
1
2
1
2
1
2
1
2
1
2
1
2
1
2
1
SHEETDATE
DEPARTMENT
SIZE
PROJECT DOCUMENT NUMBER REV
REVIEWER
DESIGNER
123
7 3 2 1 6 5 4
E
A
B
C
E
D
C
B
A
7 6 5 4
D
INBI
R721
R722R710
C629
R714 R718
R713 R717
C



20221201 ADD R480820221201 ADD R4807V05Fri Aug 25 14:04:14 2023N/AN/AN/AN/A244 OF 312P3V3_AUXP3V3_AUX
P12V_AUX P3V3_AUXP3V3_AUX
P3V3_AUXP3V3_AUX
PWRGD_DSW_PWROKPWRGD_DSW_PWROK_R1PWRGD_DSW_PWROK_R2
FM_COMP_P3V3_AUX_VINFM_COMP_P3V3_AUX_ENINFM_PFR_DSW_PWROK_NFM_COMP_P3V3_AUX_VIN_RPWRGD_P3V3_AUX_R2PWRGD_P3V3_AUXPWRGD_DSW_PWROKRST_RSMRST_PCH_N
FM_COMP_P3V3_STBY_CEXTPWRGD_DSW_PWROK_R1
2440402LF1%100K1/16WCHIP0402LFEMPTY1/16W1%10K25VEMPTY10%C04021UF10%X7R25V0.1UF0402SMLF74LVC1G07SE-7IC05%EMPTY1/16W0402LFSMLF2N7002KIC6.19K1%0402LF1/16WCHIP1%1/16W0402LF100KCHIP0402LF5%0CHIP1/16W1/16WEMPTY5%00402LF0402LFCHIP1/16W1%10K 1UFC040210%X6S25V220214TPS3895ADRYRDELAY1_BOM2SMLFEMPTYDELAY1_BOM1ICADM1086AKSZ-REEL7SMLFCHANGE U117 TO AL003895003(PUSH-PULL)
1/16W1%100K0402LFEMPTY0402LF1%CHIP1/16W33.210K1%1/16WCHIP0402LF10%X6S25V1UFC04020402LF5%1/16WEMPTY0SMLF2N7002KIC1%10KCHIP1/16W0402LF258222259223131 182306 307182214C04020.047UF25V10%X7RU94 & U117 CO-LAYOUT, U117 IS 2ND SOLUTION244
G
G
S DS D
C1315R1690
R1745
R1950
R1688
R1689
R1692 R1695
R1693
R4807
C1317
C1318
C1316
C1319
R1694
R1691
G
6 4
3
21
5
G
4
5
13
2
S DS D
Q53
U94
U117
Q52
U95
S
G
D
GND
CEXT
ENOUT
ENIN
VIN
VCC
VCC
CT
SENSE_OUT
SENSE
GNDENABLE
S
G
D
NC1
Y
GND
A
VCC
2
1
2
1
21
2
1
2
1
2
1
21
21
2
1
2
1
21
2
1
2
1
2
1
2
1
2
1
2
1
2
1
CAD NOTE:
BOM NOTE:
36
2
4
1 5
SHEETDATE
DEPARTMENT
SIZE
PROJECT DOCUMENT NUMBER REV
REVIEWER
DESIGNER
123
7 3 2 1 6 5 4
E
A
B
C
E
D
C
B
A
7 6 5 4
D
OUT
OUT
OUT
IN
IN
IN
R2486
R4808
C



20211206 ADD FOR EMI20220726 ADD R470120210616 MODIFY FOR GT
PU IN VPDB20221215 DEPOP R2805,280720220315 DEPOP R2950,R2793,U19020220318 POP R2950,R2793,U19020220725 DEPOP U190,R2794,R279320220805 DEPOP R2950, ADD R4769N/AFri Aug 25 14:04:15 2023N/AN/AV05245 OF 312N/AP3V3_AUXP3V3_AUXP3V3_AUXP12V_PSUP3V3_AUX
POWER CONNECTOR/ISOLATEDFM_PDB_BUF_EN_RSMB_FAN_3V3AUX_SDASMB_FAN_3V3AUX_SCLSMB_FAN_3V3AUX_R_SDAFM_MB_PDB_SMB9_R_ENSMB_FAN_3V3AUX_R_SCLSMB_FAN_3V3AUX_BUF_SDASMB_FAN_3V3AUX_BUF_SCL
PWRGD_P3V3_AUX_PDB_BUFP3V3_PDB_AUX_ADCTP_J45_A1FM_AC_PWR_BTN_R_NRST_SMB_SWITCH_N RST_SMB_SWITCH_R_NFM_AC_PWR_BTN_PDB_NFM_GPU_HSC_EN_BUF_R1FM_FAN_PWR_EN_RHPDB_HSC_PWRGD_RPDB_PRSNT_NFM_GPU_HSC_EN_BUFHPDB_HSC_PWRGDSMB_FAN_3V3AUX_BUF_R_SDASMB_FAN_3V3AUX_BUF_R_SCLFM_FAN_PWR_EN
SMB_FAN_3V3AUX_BUF_R_SDASMB_FAN_3V3AUX_BUF_R_SCLHPDB_HSC_PWRGD_RFM_GPU_HSC_EN_BUF_R1FM_FAN_PWR_EN_RFM_AC_PWR_BTN_PDB_NPDB_PRSNT_NRST_SMB_SWITCH_R_N1512150402LF1%100KCHIP1/16W0402LF1/16WEMPTY5%4.7K241240241 24033.2 CHIP1%CHIP33.21%33.2 0402LF1%CHIP
CONN60_10106263-6003K02LFTHLFIO
5%EMPTY1/16W00402LFEMPTY0ICLTC4307CMS8SMLF0.1UFX7R25V10%04021%33.2 CHIP33.21%CHIP0402LFEMPTY4.7K5%1/16W4.7KEMPTY5%1/16W0402LF245245245245301245236 233 231 227191 161154 215246250224 24005%CHIPCHIP05%CHIP5%005%CHIP5%0CHIP2451/16WCHIP5%4.7K0402LF246301245246213245245
245245EMPTY0.1UFEMPTY0.1UFEMPTY0.1UFEMPTY0.1UF0.1UF EMPTYEMPTY0.1UF245245245245245
C2293
C2294
C2295
C2296
C2297
R2906
R4721
R2905
R2807R2805
R2811
R2812
C1751
R2800
R2801
R2796
R3113
R3114
R2802
R2803
8
76
23
54
1
P6_8
P6_7
P6_6
P6_5
P6_4
P6_3
P6_2
P6_1
P5_8
P5_7
P5_6
P5_5
P5_4
P5_3
P5_2
P5_1
P4_8
P4_7
P4_6
P4_5
P4_4
P4_3
P4_2
P4_1
P3_8
P3_7
P3_6
P3_5
P3_4
P3_3
P3_2
P3_1
P2_8
P2_7
P2_6
P2_5
P2_4
P2_3
P2_2
P2_1
P1_8
P1_7
P1_6
P1_5
P1_4
P1_3
P1_2
P1_1
D3
D2
D1
C3
C2
C1
B3
B2
B1
A3
A2
A1
U192
J45
READY
SDA_OUT
SCL_OUT
VCC
GND
SDA_IN
SCL_IN
ENABLE
POWER
SIGNAL
D3
C3
B3
A3
P6_8
P6_7
P6_6
P6_5
P6_4
P6_3
P6_2
P6_1
P3_8
P3_7
P3_6
P3_5
P3_4
P3_3
P3_2
P3_1
P5_8
P5_7
P5_6
P5_5
P5_4
P5_3
P5_2
P5_1
D1
C1
B1
A1
P4_8
P4_7
P4_6
P4_5
P4_4
P4_3
P4_2
P4_1
P2_8
P2_7
P2_6
P2_5
P2_4
P2_3
P2_2
P2_1
P1_8
P1_7
P1_6
P1_5
P1_4
P1_3
P1_2
P1_1
D2
C2
B2
A2
21
21
21
21
21
21C2371
2
1
21 21 21
21
21
2
1
2
1
21
21
2
1
21
21
21
21
21
2
1
2
1
SHEETDATE
DEPARTMENT
SIZE
PROJECT DOCUMENT NUMBER REV
REVIEWER
DESIGNER
123
7 3 2 1 6 5 4
E
A
B
C
E
D
C
B
A
7 6 5 4
D
IN
BI
IN
BI
INBI
ININOUT
OUT
OUT
INOUT
ININ
OUT
OUT
OUT
OUT
OUT
IN
R4701
R2950
R4769
C



OUT PUT IS PUSH PULL MODE20210616 MODIFY FOR GT
20211201 ADD BUF TO PDBFri Aug 25 14:04:16 2023N/AN/AN/AN/AV05246 OF 312P3V3_AUXP3V3_AUXP3V3_AUX
P3V3_AUXP3V3_AUXP3V3_AUXP3V3_AUXP3V3_AUX
POWER CONNECTOR/ISOLATED245222215245213147245
0402LF100K1%1/16WCHIPHPDB_HSC_PWRGD0402LFPWRGD_P3V3_AUX_PDB4.7K5%1/16WCHIP0402LFICPJT138KHPDB_HSC_PWRGD_NHPDB_HSC_PWRGD_ISO0402LF4.7K74LVC2G07DW-7SMLFPWRGD_P3V3_AUX_PDB_BUFPWRGD_P3V3_AUX_PDB_R PWRGD_P3V3_AUX_PDB_BUF_RSMLFPJT138KSMLF1/16W54.9K1/16WEMPTY5%CHIP1000PF1%
1/16WEMPTY0402LFFM_GPU_HSC_EN100KCHIP1/16W1%0402LF5%4.7KGPU_PRSNT GPU_PRSNT_RIC74LVC1G08W5-7SMLF0402LF0402LFEMPTY1/16W5%4.7K0402FM_GPU_HSC_EN_BUF_R33.2CHIP0 0402LF4.7K0402LF5%EMPTY1/16W0.1UFX7R25V10%CHIP1/16W0402LF5%4.7K33.20402LFCHIP0402LF1/16WEMPTY5%4.7KX7R10%25V04020.1UFIC5%CHIP1/16W5%CHIP1/16W0402LF0 FM_GPU_HSC_EN_BUF
EMPTY5%040250VIC
G2
G1
S2 D2D1S1
R4554
R4553
R4264
R3770
R2940
R2946
5
2
52
43
61
4
5
3
2
1
4 31 6
Q145
Q145
21R4266
U308
U278
21R2944
VCCGND
2Y
1Y
2A
1A
VCC
Y
GND
B
A
2
1
2
1
2
1
2
1
2
1
2
1
2
1
21
2
1C2283
21
2
1
2
1
2
1
2
12
1C1775
SHEETDATE
DEPARTMENT
SIZE
PROJECT DOCUMENT NUMBER REV
REVIEWER
DESIGNER
123
7 3 2 1 6 5 4
E
A
B
C
E
D
C
B
A
7 6 5 4
D
IN
OUT
IN
OUTIN
IN OUT
C2342R4551
R4552
R4265
R4268
R2948
R2941
C



20210616 MODIFY FOR GT
Fri Aug 25 14:04:17 2023N/AN/AN/AN/AV05247 OF 312
P12V_AUXP12V_AUX
PSU POWER CONNECTORS
301305214259MB0_P12V_STBY_PWRGD FM_P12V_HSC_EN_R5%CHIP1/16W0402LF00402LF1/16WCHIP0402LF5%4.7K100K1%CHIP1/16W5%01/16W0402LFSMLFP12V_AUX_BLEEDING2N7002KCHIPIC2N7002KSMLFFM_P12V_HSC_EN_R_NICFM_P12V_HSC_EN_N
G
G
S DS D
G
G
S DS D
Q54
U158
S
G
D S
G
D
2
1
2
1
21R2529
21R2531
SHEETDATE
DEPARTMENT
SIZE
PROJECT DOCUMENT NUMBER REV
REVIEWER
DESIGNER
123
7 3 2 1 6 5 4
E
A
B
C
E
D
C
B
A
7 6 5 4
D
IN
R2530
R2528
C



20221221 CHANGE JP16 JUMPER TO "2-3"2-3 DISABLE (DEFAULT)1-2 CONTROL BY CPLDJTAG SWITCH JUMPER20220304 MODIFY FOR GT
Fri Aug 25 14:04:18 2023V05N/AN/AN/AN/A248 OF 312
P3V3_AUXP3V3_AUXP3V3_AUX
SCM REMOTE JTAG LOGIC
JTAG_BMC_SW_OEJTAG_BMC_TMSJTAG_BMC_TCKJTAG_BMC_TDOJTAG_BMC_TDIPU_JTAG_SW_PUJTAG_BMC_SW_R_OEJTAG_BMC_TCK_RJTAG_BMC_TMS_RJTAG_BMC_TDI_RJTAG_BMC_TDO_R JTAG_BMC_SW_TDO_RJTAG_BMC_SW_TDI_RJTAG_BMC_SW_TMS_RJTAG_BMC_SW_TCK_RJTAG_BMC_SW_TMSJTAG_BMC_SW_TCKJTAG_BMC_SW_TDIJTAG_BMC_SW_TDO2131/16W1%10K0402LFCHIP1/16WEMPTY1K0402LF1%2402402402401%1/16WCHIP0402LF1KCONN3_210-HP1-030BR1IOTHLFCHIP0402LF5%01/16W0CHIPCHIP00CHIP0CHIPSMLF74CBTLV3126PWIC040210%X7R25V0.1UF0CHIPCHIP00CHIPCHIP0239239239239
14
7
13
1112
10
89
4
65
1
32
3
2
1
U327
JP16
VCC
4OE
4A 4B
3OE
3A
GND
1A
2B
1B
2OE
1OE
3B
2A
1
2
3
21
21
2
1C2348
21
21
21
21
2
1
2
1
2
1
21
21
21
SHEETDATE
DEPARTMENT
SIZE
PROJECT DOCUMENT NUMBER REV
REVIEWER
DESIGNER
74CBTLV3126
123
7 3 2 1 6 5 4
E
A
B
C
E
D
C
B
A
7 6 5 4
D
OUT
IN
IN
IN
IN
OUT
OUT
OUT
IN
R4632
R4633
R4626
R4627
R4629
R4624
R4623
R4634
R4635
R4630
R4631
R4628
C



THIS PAGE WAS INTENTIONALLY LEFT BLANK
Thu Aug 24 16:16:03 2023N/AV05249 OF 312N/AN/AN/ABLANK
SHEETDATE
DEPARTMENT
SIZE
PROJECT DOCUMENT NUMBER REV
REVIEWER
DESIGNER
123
7 3 2 1 6 5 4
E
A
B
C
E
D
C
B
A
7 6 5 4
D
C



NOTE:R4567 NEED CHANGE TO 5.11K OHM ON EVT STATES AND POP R4568
20220801 CHANGE NET NAME
IF USE AD128,POP R3668,R3670
20210615 MODIFY FOR GT
20220105 ADD R4567,R4568VI=1.581V
VIN 1.599V 1.599V 1.677V 1.581VV SOURCE P3V3_AUX P3V3 P5V P12V_AUXADDR: 0X6AADDR: 0X3AFri Aug 25 14:04:20 2023N/AN/AN/AN/AV05250 OF 312
P3V3_AUX
P3V3_AUXP3V3_AUX
P3V3_AUXP5VP12V_AUXP3V3
VOLTAGE SENSOR (1/2)
157250162250250250192250250250
250250250250250241250193250192250163193163241250250250
250162156250250250241250241250250250250250250250250250
250
250250157
250250
250
250250
156
250250245250250250 250
250
250P12V_OCP_SFF_ISENSE_MPS_TIC1/16W1KP3V3_ADC128_VCC04020402ADC1_BOM20CHIP10%SMLFBLM18PG300SN1DADC1_BOM2NIC1_P12V_MPS_TIC_BOM4P3V3_AUX_ADC_TICX7R10%CHIPP12V_OCP_V3_2_ISENSE_MAM_MAMCO-LAYOUTNIC1_P12V_MPS_TIC_BOM4NIC1_P12V_MAM_MAM_BOM1P12V_OCP_V3_2_ISENSE_MAMNIC1_P12V_MAM_TIC_BOM2P12V_OCP_V3_2_ISENSE_TICP12V_E1S_0_ISENSE_MAM100PFADC1_BOM1EMPTYE1S1_P12V_MPS_MAM_BOM3P12V_E1S_0_ISENSE_MAM_MAMEMPTYP12V_OCP_SFF_ISENSE_MAMP12V_AUX_ADC_MAMEMPTYCO-LAYOUTE1S1_P12V_MAM_TIC_BOM2CO-LAYOUT5%EMPTYP12V_OCP_SFF_ISENSE_TIC0402ADC1_BOM2ADC1_BOM15%01/16W0402LFADC1_BOM1U193 & U269 CO-LAYOUT, U193 IS 2ND SOLUTIONSMB_SEN_TIC_3V3AUX_SCLADC128_VREF1/16WEMPTYP12V_OCP_V3_2_ISENSE_TICP3V3_ADC_TICP3V3_AUX_ADC_TIC25V0.1UF50VADC1_BOM1P3V3_ADC_TICCHIP1/16W1%SMB_VR_3V3AUX_SDA_R10402LF1%P12V_E1S_0_ISENSE_MPS_TICP3V3_PDB_AUX_ADC_TICEMPTY0402EMPTY5%50V100PFADC1_BOM1P12V_E1S_0_ISENSE_MAM_TIC P12V_E1S_0_ISENSE_TICP12V_OCP_V3_2_ISENSE_MPS_TICP12V_E1S_0_ISENSE_MPS_MAMCO-LAYOUT5%P12V_OCP_V3_2_ISENSE_MPS_MAMNIC1_P12V_MPS_MAM_BOM30402ADC1_BOM2SMB_VR_3V3AUX_SCL_R1ADC128_A1P3V3_PDB_AUX_ADC_MAMADC1_BOM20.1UF25VCHIP1/16W5.11K0402LF1/16WCHIP0402LFP12V_AUX_ADCCHIP1/16W1%1.21K0402LF1/16W1%ADC1_BOM2CO-LAYOUTP3V3_ADC_MAM25V5.11KCHIP0402LFE1S1_P12V_MAM_MAM_BOM1ADC1_BOM2P12V_OCP_V3_2_ISENSE_MAM_TIC00.1UF10%X7R0402EMPTY5%E1S1_P12V_MPS_TIC_BOM40402X7R10%CHIP05%05%0EMPTYCHIP5%EMPTY0NIC1_P12V_MAM_TIC_BOM2CO-LAYOUTNIC1_P12V_MPS_MAM_BOM35%ADC1_BOM1EMPTYADC1_BOM2ADC1_BOM110%X7RCHIP5%0EMPTY05%P12V_OCP_SFF_ISENSE_MAM_TIC
ADC1_BOM2ADC1_BOM1CO-LAYOUTX7RP5V_ADC0402LF9.09K1%CHIPADC1_BOM2CHIPP5V_ADC_TICP5V_ADC_MAMADC1_BOM1CO-LAYOUT0402100PFCHIPADC1_BOM20.1UF5%P3V3_PDB_AUX_ADC_TICADC1_BOM10402LFSMB_VR_3V3AUX_SDA_R1SMB_VR_3V3AUX_SCL_R1ADC1_BOM2SMB_SEN_TIC_3V3AUX_SDA04020ADC1_BOM14.7K0402LF5%CHIPADC128_A0P12V_E1S_0_ISENSE_TICP3V3_AUX_ADC_MAMSMB_SEN_MAM_3V3AUX_SCLSMB_SEN_MAM_3V3AUX_SDAP12V_E1S_0_ISENSE_MAMSMB_SEN_MAM_3V3AUX_SCLEMPTYP12V_AUX_ADC_TICICP3V3_PDB_AUX_ADC_MAMSMB_SEN_MAM_3V3AUX_SDAP12V_OCP_SFF_ISENSE_MPS_MAM040210UF10%5%0C0805025V
P1V581_PDB_ADC1%5%
MAX11617_VREFADC1_BOM1EMPTYADC1_BOM2ADC128D818CIMTX/NOPBADC1_BOM2P12V_OCP_SFF_ISENSE_TICP5V_ADC_TICADC1_BOM2EMPTYADC1_BOM2ADC1_BOM210%5.11KP12V_OCP_SFF_ISENSE_MAMADC1_BOM1ADC1_BOM1ADC1_BOM1ADC1_BOM1BLM18PG300SN1DEMPTYADC1_BOM1EMPTY0402
01/16WADC1_BOM2ADC128_A1ADC1_BOM21K1%ADC128_A010%0.1UF5%100PF5%P12V_OCP_SFF_ISENSE_MAM_MAM50VNIC1_P12V_MAM_MAM_BOM15%
5%0100PF040210%X7R0.1UFP12V_AUX_ADC_TICP12V_AUX_ADC_MAMADC1_BOM2040205%EMPTY0.1UFX7R25V100PF0040210%25V0.1UF5%CHIPADC1_BOM1ADC1_BOM1ADC1_BOM1CO-LAYOUTADC1_BOM2EMPTY100PFSMLF1/16W 1/16WCHIPCHIP1%0402LFEMPTYX7R10%X7R00402
0402LFP3V3_PDB_AUX_ADCCHIP1%7.87K1%CHIP18K5%00402LFCHIP1%1/16W4.7K0402LFP3V3_ADC5%EMPTY01/16W1%0402LF1%1/16W4.7K5%01%1/16WP3V3_AUX_ADC05%
0402EMPTY0402LF 0402LF1KEMPTY50V5%5%50V5%50VEMPTY0402LFEMPTY1/16W1%0402LFEMPTY1/16W1%1KIND25V0.1UF0402050VEMPTY5%50V05%0EMPTYCO-LAYOUTEMPTY0.1UF25V100PFEMPTY25V10%04020.1UF
04021%4.7KX7R4.7K1/16WSMB_SEN_TIC_3V3AUX_SDAP12V_OCP_V3_2_ISENSE_MAMP5V_ADC_MAM05%P3V3_ADC_MAM
CHIP5%CHIP5%0TP_ADC128_INTSMB_SEN_TIC_3V3AUX_SCL
16VEMPTY0402LF2KEMPTYMAX11617_VREF_REMPTYSMLFMAX11617EEE+TADC1_BOM1P3V3_MAX11617 _VDDEMPTY10%25V0.1UF10%16V10UFC0805SMLF
ADC1_BOM1CO-LAYOUT5%EMPTYP3V3_AUX_ADC_MAM25V0402
1/16W25V
L15
R3942
R3941
R3940
C2195
R3939
R3862
R3861
R3860
R3859
R3866
R3865
R3864
R3863
C2175
C2176
C2045
C1344
R3684
R3683
C2043
R3686
R3685
C2044
C2042
R3682
R3681
R1799
R1791
R2908
R2907
R3672
R3671
C1767 C1768
R1792
R1793
R4567
R4568
R3688
R3687
C2050
R3669
R3670
R3667
R3668
R3680
R3679
C2046
C2048
C2049
C2047
R1800
R3005
R2843
R1785
R3689
R2900
C1347 C1757
21
1
5
2
3
6
9
10
11
12
13
14
15
16 4
8
7
21
16
14
13
15
1
2
3
4
12
11
10
98
7
6
5
L16
U269
U193 1 2
VDD
GND
SDA
SCL
AIN7
AIN6
AIN5
AIN4AIN3
AIN2
AIN1
AIN0
AIN8
AIN9
AIN10
AIN11||REF
1 2
INT#
GND
SCL
SDA
IN0
IN1
IN2
IN3
IN4
IN5
IN6
IN7
A1
A0
V+
VREF
2
1
2
1
21
21
21
2
1 C2194
2
1
21
21
21
21
21
21
21
21
21
2
1 C2177
2
1
2
1 C2178
2
1
21
21
2
1
2
1
2
1
2
1
2
1
2
1
21
21
2
1
2
1
21
21
2
1
2
1
21
21
2
1
2
1
2
1
2
1
21
21
2
1
2
1
2
1
2
1
2
1
2
1
2
1
2
1
2
1
2
1
2
1
2
1
21 21
21
2
1
2
1
2
1
2
1
21 21
CAD NOTE:
R3690
SHEETDATE
DEPARTMENT
SIZE
PROJECT DOCUMENT NUMBER REV
REVIEWER
DESIGNER
123
7 3 2 1 6 5 4
E
A
B
C
E
D
C
B
A
7 6 5 4
D
IN
IN
IN
IN
IN
OUT
IN OUT
IN
IN
IN
IN
IN
IN
IN
IN
OUT
OUT
OUT
OUT
IN
IN
IN
IN
IN
IN
ININININ
ININ
BI
OUT
OUT
IN
ININ
OUT
OUT
OUT
BI
IN
IN
IN
OUT
OUT
OUT
OUT
OUT
OUT
OUT
OUT
IN
IN
INBI
INBI OUTBI
C2052C2051
C



ADDRESS : 0X84
Fri Aug 25 14:04:21 2023251 OF 312V05N/AN/AN/AN/A
P3V3_AUXP3V3_AUX
P12V_S3_AUX_CPU0_NVDIMMP12V_AUXP12V_S3_AUX_CPU1_NVDIMMP12V_AUXVOLTAGE SENSOR (2/2)
HSC1_BOM2INA230AIRGTREMPTY0402NC_HSC_TYPE_VINPHSC1_BOM2SMB_HSC_TYPE_ADC_SDASMB_HSC_TYPE_ADC_SCLEMPTY
CHIPSMLF0.0011%3WCHIP1%3W0.001SMLFP12V_AUX_CPU0_DIMM_ISEN_PPVCCD_HV_CPU1_NVDIMM_ISENSEP12V_AUX_CPU1_DIMM_ISEN_NP12V_AUX_CPU0_DIMM_ISEN_NP12V_AUX_CPU1_DIMM_ISEN_NP12V_AUX_CPU1_DIMM_ISEN_P
25V0.1UF4.7K1/16W4.7K1%1/16W EMPTYEMPTY0402LF0402LF0402LF0EMPTY0402LF4.7K 1/16W1%EMPTY1/16W10%1%HSC1_BOM2HSC1_BOM2HSC1_BOM2HSC1_BOM20402
P12V_AUX_CPU0_DIMM_ISEN_PP12V_AUX_CPU0_DIMM_ISEN_NPVCCD_HV_CPU0_NVDIMM_ISENSEP12V_AUX_CPU1_DIMM_ISEN_PINA183A1IDBVRSMLFEMPTYSMLFINA183A1IDBVREMPTY278251296296251278251296251296251278251278251278296251
HSC_TYPE_ADC_A033.21%HSC1_BOM21/16W0402LFEMPTY170233305SMB_LM75_0_3V3AUX_SCL170305 233EMPTY33.21%SMB_LM75_0_3V3AUX_SDASMLFNC_HSC_TYPE_VINMHSC_TYPE_ADC_A1305HSC1_BOM20.1UF25VHSC_TYPE_ADC10%EMPTYTP_HSC_TYPE_ADC_ALERTNC_HSC_TYPE_NC4NC_HSC_TYPE_NC5NC_HSC_TYPE_NC0NC_HSC_TYPE_NC1NC_HSC_TYPE_NC2NC_HSC_TYPE_NC35%
TH
GND
NC5
NC4
NC3
NC2
NC1
NC0
ALERT
IN-
IN+
BUS
SDA
SCL
A0
A1
VS
21
21
4343
R4687
R4688
9
TH
4
5
16
15
14
8
7
6
12
13 10
11
3
1
2
3
4
5
2
1
21
R1838
21
R1837
3
4
5
2
1
4343
U331
U102
U103
IN+
IN-
OUT
GND1
GND0
IN+
IN-
OUT
GND1
GND0
21R4689 21R4690
2
1
2
1
21
21
2
1
2
1
SHEETDATE
DEPARTMENT
SIZE
PROJECT DOCUMENT NUMBER REV
REVIEWER
DESIGNER
123
7 3 2 1 6 5 4
E
A
B
C
E
D
C
B
A
7 6 5 4
D
IN
BI
OUT
OUT
OUT
IN
IN
OUT
IN
IN
OUT
IN
OUT
R4692
C2364
R4691
C2363
C



P3V3 1 = ONP5V_AUX 1 = ONPWRGD_PS_PWROK 1 = ONRST_RSMRST_PLD_R_N 1 = ONPWRGD_P1V05_PCH_AUX 1 = ON20210705 MODIFY FOR GTPWRGD_P1V8_PCH_AUX 1 = ON
FM_PCH_SLP_S4 1 = ON
FM_PCH_SLP_S3 1 = ON
P5V 1 = ONFri Aug 25 14:04:22 2023N/AN/AN/AN/AV05252 OF 312
P3V3_AUXP3V3_AUXP3V3_AUXP3V3_AUXP3V3_AUXP5VP5V_AUXP3V3_AUXP3V3POWER GOOD LED'S 1/5
262214215219223263194222182223214224182223LED_P5V_AUX0402LF1%4701/16WCHIPLED_P5V0402LF1%4701/16WCHIPLTST-C281TBKT-5APJT138KSMLFLED_PWRGD_PS_PWROK_PLD_DIC0402LFLED_BLUEICLTST-C281TBKT-5APJT138KLED_FM_PCH_SLP_S4_N_DICPJT138KSMLFLED_RST_RSMRST_PLD_R_N_DPJT138KSMLFLED_PWRGD_P1V05_PCH_AUX_DPJT138KPWRGD_P1V05_PCH_AUXLTST-C281TBKT-5ASMLFLED_BLUELED_PWRGD_P1V8_PCH_AUX_DRST_RSMRST_PLD_R_NSMLFLED_BLUEICSMLF0402LF1/16WCHIP1%130SMLFICIC0402LF1%130IC1/16WCHIP130CHIP130SMLFIC0402LF1/16W1%130ICICLED_BLUESMLFSMLF
LTST-C281TBKT-5AICLED_BLUE1%0402LF1/16WLTST-C281TBKT-5ASMLFPJT138KPWRGD_P1V8_PCH_AUX FM_PCH_SLP_S3_NLED_FM_PCH_SLP_S3_NPWRGD_PS_PWROK_PLDCHIPICSMLFLTST-C281TBKT-5AICSMLFLED_BLUEICSMLFLED_BLUELED_RST_RSMRST_PLD_R_NLED_PWRGD_P1V8_PCH_AUXCHIP 1/16WLED_PWRGD_PS_PWROK_PLDLED_BLUESMLF1%LTST-C281TBKT-5ALED_BLUELED_FM_PCH_SLP_S4_NFM_PCH_SLP_S4_NLTST-C281TBKT-5AICLED_FM_PCH_SLP_S3_N_DLED_PWRGD_P1V05_PCH_AUXLTST-C281TBKT-5A1301%CHIP 1/16W0402LF
0402LFCHIP1%LED_P3V31301/16W
G2
G1
G1
G2
G2
G1
S2 D2D1S1
D1S1
S2 D2
S2 D2
D1S1
R3102
D99
D98
D97
D92
D95
Q78
D96
5 Q78
D91
Q76
D93
D94
Q77
5 Q77
5 Q76
AC
AC
AC
AC
AC
AC
AC
AC
AC
4 3
4 3 4 3
21
21
21
21
21
21
21
21
21
C A
C A
C A
C A
C A
2
C A
C A
2
C A
C A
2
1 6
1 61 6
SHEETDATE
DEPARTMENT
SIZE
PROJECT DOCUMENT NUMBER REV
REVIEWER
DESIGNER
123
7 3 2 1 6 5 4
E
A
B
C
E
D
C
B
A
7 6 5 4
D
IN
IN
IN
IN
IN
IN
R3100
R3101
R3078
R3075
R3071
R3072
R3074
R3073
C



20210705 MODIFY FOR GTPWRGD_PVCCD_HV_CPU0 1 = ONPWRGD_PVPP_HBM_CPU0 1 = ONPWRGD_PVCCFA_EHV_CPU0 1 = ONPWRGD_PVCCFA_EHV_FIVRA_CPU0 1 = ON
PWRGD_PVCCINFAON_CPU0 1 = ONPWRGD_PVNN_MAIN_CPU0 1 = ONPWRGD_PVCCIN_CPU0 1 = ON
Fri Aug 25 14:04:23 2023N/AN/AN/AN/AV05253 OF 312
P3V3_AUXP3V3_AUXP3V3_AUX
P3V3_AUXP3V3_AUXP3V3_AUXP3V3_AUX
POWER GOOD LED'S 2/5
213282132266213266213274214281213278213274214PWRGD_PVNN_MAIN_CPU0LED_PWRGD_PVNN_MAIN_CPU0_DICLED_PWRGD_PVCCINFAON_CPU0_DLED_PWRGD_PVPP_HBM_CPU0LED_BLUEICLTST-C281TBKT-5AIC1301%0402LFSMLFPJT138KLED_PWRGD_PVCCFA_EHV_FIVRA_CPU0LED_BLUESMLFLED_PWRGD_PVCCFA_EHV_FIVRA_CPU0_DPWRGD_PVCCFA_EHV_FIVRA_CPU0SMLFPJT138KSMLFLED_PWRGD_PVCCFA_EHV_CPU0_DPJT138KLED_PWRGD_PVPP_HBM_CPU0_DSMLFICPJT138KSMLFLED_PWRGD_PVCCD_HV_CPU0CHIP 1/16W1%LED_PWRGD_PVCCFA_EHV_CPU0CHIP 1/16WPWRGD_PVCCIN_CPU0LED_PWRGD_PVCCIN_CPU0_DICLED_BLUESMLFLTST-C281TBKT-5APJT138KSMLFLED_BLUE1%130LTST-C281TBKT-5ALED_BLUESMLFSMLFLED_BLUELTST-C281TBKT-5ACHIPLTST-C281TBKT-5AIC1/16WPWRGD_PVCCFA_EHV_CPU0PWRGD_PVPP_HBM_CPU0PWRGD_PVCCD_HV_CPU0LED_PWRGD_PVCCD_HV_CPU0_DPWRGD_PVCCINFAON_CPU0LED_PWRGD_PVCCINFAON_CPU0LED_PWRGD_PVNN_MAIN_CPU0LED_PWRGD_PVCCIN_CPU0ICPJT138KIC1301%CHIP 1/16W0402LFICSMLF0402LFIC1300402LFPJT138KSMLFICICLED_BLUESMLFLTST-C281TBKT-5AICSMLFLTST-C281TBKT-5AIC1301%CHIP 1/16W0402LF1301%CHIP 1/16W0402LF1301%CHIP 1/16W0402LF
G1
G2
G1
G2
G1 G1
G2
D1S1S2 D2
D1S1S2 D2
D1S1
D1S1
S2 D2
D77
D78
Q81
5 Q81
D79
Q83
D73
D74
D75
D76
Q79
5 Q79
Q80
5 Q80
AC
AC
AC
AC
AC
AC
AC
4 3
4 34 3
21
21
21
21
21
21
21 C A
C A
2
C A
2
C A
C A
C A
C A
2
2
1 61 6
1 61 6
SHEETDATE
DEPARTMENT
SIZE
PROJECT DOCUMENT NUMBER REV
REVIEWER
DESIGNER
123
7 3 2 1 6 5 4
E
A
B
C
E
D
C
B
A
7 6 5 4
D
IN
IN
IN
IN
IN
IN
IN
R3092
R3090
R3091
R3088
R3089
R3087
R3086
C



20210705 MODIFY FOR GTPWRGD_PVCCD_HV_CPU1 1 = ON PWRGD_PVCCINFAON_CPU1 1 = ONPWRGD_PVCCIN_CPU1 1 = ONPWRGD_PVPP_HBM_CPU1 1 = ONPWRGD_PVCCFA_EHV_CPU1 1 = ONPWRGD_PVNN_MAIN_CPU1 1 = ONPWRGD_PVCCFA_EHV_FIVRA_CPU1 1 = ONFri Aug 25 14:04:25 2023N/AN/AN/AN/AV05254 OF 312
P3V3_AUXP3V3_AUXP3V3_AUXP3V3_AUXP3V3_AUXP3V3_AUX
P3V3_AUXPOWER GOOD LED'S 3/5
300213292214299213214284292214
284214
296214SMLFPJT138KSMLFLED_PWRGD_PVCCFA_EHV_CPU1_DPWRGD_PVNN_MAIN_CPU10402LFPWRGD_PVCCFA_EHV_CPU1LED_PWRGD_PVCCFA_EHV_FIVRA_CPU1_DPJT138KICPWRGD_PVPP_HBM_CPU1LED_PWRGD_PVPP_HBM_CPU1_D LED_PWRGD_PVPP_HBM_CPU11/16WPWRGD_PVCCIN_CPU1PJT138KICSMLFSMLFICPJT138KLED_PWRGD_PVCCIN_CPU1_DLED_PWRGD_PVNN_MAIN_CPU1_DPWRGD_PVCCINFAON_CPU1LTST-C281TBKT-5ALED_BLUELED_PWRGD_PVCCINFAON_CPU1SMLFLED_PWRGD_PVCCFA_EHV_FIVRA_CPU1ICLTST-C281TBKT-5ALED_BLUESMLFLTST-C281TBKT-5ALED_BLUELTST-C281TBKT-5AICLED_BLUESMLFLED_PWRGD_PVCCFA_EHV_CPU1LTST-C281TBKT-5APJT138KSMLF
LED_PWRGD_PVCCD_HV_CPU1_DSMLFICPWRGD_PVCCFA_EHV_FIVRA_CPU1SMLFLED_BLUECHIP 1/16WIC
0402LF1/16WCHIP1%1300402LF1/16WCHIP1%1300402LF1/16WCHIP1%130SMLFICLED_BLUELTST-C281TBKT-5AICSMLFICLTST-C281TBKT-5ASMLFLED_BLUEIC0402LF1/16WCHIP1%130ICPJT138K0402LF1/16WCHIP1%130CHIP1%130SMLFIC0402LF1%130ICPWRGD_PVCCD_HV_CPU1LED_PWRGD_PVCCD_HV_CPU1LED_PWRGD_PVCCIN_CPU1LED_PWRGD_PVNN_MAIN_CPU1LED_PWRGD_PVCCINFAON_CPU1_DPJT138K
G2
G1 G2
G1
G2
G2
G1
S2 D2D1S1
S2 D2 D1S1
S2 D2
S2 D2
D1S1
5
4 3
Q83
D84
Q86
D85
D86
5 Q86
D80
Q84
D81
D82
D83
5 Q84
Q85
5 Q85
AC
AC
AC
AC
AC
AC
AC
4 3
4 34 3
21
21
21
21
21
21
21
C A
2
C A
C A
C A
2
C A
C A
C A
2
1 6
1 61 6
SHEETDATE
DEPARTMENT
SIZE
PROJECT DOCUMENT NUMBER REV
REVIEWER
DESIGNER
123
7 3 2 1 6 5 4
E
A
B
C
E
D
C
B
A
7 6 5 4
D
IN
IN
IN
ININ
IN
IN
R3099
R3097
R3098
R3093
R3094
R3096
R3095
C



P12V_PSU 1 = ONP12V_SCM FAULT 0 = ON20220725 ADD LED FOR DEBUG PLAN
P12V_AUX 1 = ON20210705 MODIFY FOR GTPWRGD_SYS_PWROK 1 = ONPWRGD_CPUPWRGD_GTL 1 = ONRST_PLTRST_N 1 = ON
PWRGD_PCH_PWROK 1 = ON
Fri Aug 25 14:04:26 2023N/AN/AN/AN/AV05255 OF 312P3V3_AUXP3V3_AUXP3V3_AUXP12V_AUXP12V_PSUP3V3_AUXP3V3_AUXP3V3_AUXPOWER GOOD LED'S 4/5LED_BLUE226216214220222214220222183223242CHIPLTST-C190KSKT-PPJT138KCHIP1%
LED_PWRGD_PCH_PWROK_RCHIPLED_P12V_PSU_R20402LF5%4.7KCHIP0402LFSMLFLED_YELLOWIC0402LF1/16W2490402LF0402LF1%560LED_BLUESMLF1%1/16W0402LFLED_BLUEPWRGD_CPUPWRGD_LVC2_R10402LFSMLFCHIPLED_PWRGD_CPUPWRGD_GTLLTST-C281TBKT-5APJT138KICSMLFLED_RST_PLTRST_N130CHIPICPJT138KSMLFLED_PWRGD_CPUPWRGD_GTL_D1/16WCHIPLED_P12V_PSU_R35601%1%560LED_P12V_AUX_R1560IC1/16W1301%0402LF1301%SMLFICLED_BLUELTST-C281TBKT-5AICSMLFLED_BLUEICPJT138KSMLFICSMLF0402LF1/16WCHIP1%130LTST-C281TBKT-5ASMLFICLED_PWRGD_SYS_PWROK_R_DPWRGD_PCH_PWROK_RPWRGD_SYS_PWROK_RLED_RST_PLTRST_N_DRST_PLTRST_N
1/16WLED_PWRGD_PCH_PWROK_R_DCHIPLTST-C281TBKT-5ALED_PWRGD_SYS_PWROK_RLTST-C281TBKT-5AICSMLFCHIP1/16W5601/16W1%0402LFCHIP1/16W5601%0402LF1%CHIPICLED_P12V_SCM_FAULTICPJT138KPJT138K1/16WLED_P12V_SCM_FAULT_D1SMLFIC
LED_P12V_AUX_R31/16WLED_BLUELED_P12V_AUX_R20402LFLED_P12V_PSU_R1LTST-C281TBKT-5AP12V_SCM_FAULT_R_N1/16WLED_P12V_SCM_FAULT_D2SMLF
G1
G2
G1
G2
G1
G2
D1S1
S2 D2D1S1
S2 D2D1S1S2 D2
5
2
C A
C A
C A
5
4 31 6
4 3
Q150
Q150
D144
D142
D143
Q88
D90
D87
D88
Q87
5 Q87
D89
Q88 AC
AC
AC
AC
AC
AC
AC
4 3
2
1 21
21R470621R470421R4702
21R470721R470521R4703
21
21
21
21
C A
C A
C A
2
C A
2
1 61 6
SHEETDATE
DEPARTMENT
SIZE
PROJECT DOCUMENT NUMBER REV
REVIEWER
DESIGNER
123
7 3 2 1 6 5 4
E
A
B
C
E
D
C
B
A
7 6 5 4
D
IN
IN
IN
IN
IN
R4710
R4711
R3070
R1044
R3069
R3068
C



RST_CPU0_DRAM_EF 1 = ONRST_CPU0_DRAM_GH 1 = ONRST_CPU1_DRAM_GH 1 = ONRST_CPU1_DRAM_EF 1 = ONRST_CPU1_DRAM_CD 1 = ONRST_CPU0_DRAM_CD 1 = ONRST_CPU0_DRAM_AB 1 = ONRST_CPU1_DRAM_AB 1 = ON20210705 MODIFY FOR GT
Fri Aug 25 14:04:27 2023N/AN/AN/AN/AV05256 OF 312
P3V3_AUX
P3V3_AUXP3V3_AUXP3V3_AUXP3V3_AUXP3V3_AUX
P3V3_AUXP3V3_AUX
POWER GOOD LED'S 5/5216129216130
216130216130216129216130216129
216129NX6008NBKSLED_RST_PLD_CPU0_DRAM_EF_NRST_PLD_CPU0_DRAM_EF_NLED_RST_PLD_CPU0_DRAM_GH_N_DLED_RST_PLD_CPU0_DRAM_EF_N_DSMLFICLTST-C281TBKT-5ARST_PLD_CPU1_DRAM_GH_NLED_RST_PLD_CPU1_DRAM_GH_N_DICNX6008NBKSSMLFLED_RST_PLD_CPU1_DRAM_EF_N_D
LED_RST_PLD_CPU1_DRAM_AB_N_DRST_PLD_CPU1_DRAM_AB_NNX6008NBKSICSMLFNX6008NBKSICSMLFLED_RST_PLD_CPU1_DRAM_CD_N_DRST_PLD_CPU1_DRAM_CD_NLED_RST_PLD_CPU0_DRAM_CD_NSMLFRST_PLD_CPU0_DRAM_CD_NSMLFLED_BLUELED_RST_PLD_CPU1_DRAM_EF_NRST_PLD_CPU1_DRAM_EF_N1/16WSMLFLED_RST_PLD_CPU0_DRAM_GH_NCHIPNX6008NBKSLTST-C281TBKT-5A0402LFICSMLFLTST-C281TBKT-5ASMLFLED_BLUELED_RST_PLD_CPU1_DRAM_GH_NSMLFNX6008NBKSRST_PLD_CPU0_DRAM_GH_NICLTST-C281TBKT-5AICNX6008NBKSSMLF
NX6008NBKSICSMLFICLED_RST_PLD_CPU0_DRAM_CD_N_DLED_RST_PLD_CPU0_DRAM_AB_N_DRST_PLD_CPU0_DRAM_AB_NLTST-C281TBKT-5ALED_BLUELTST-C281TBKT-5ACHIP
LED_BLUELED_BLUE
0402LFLTST-C281TBKT-5ALED_BLUE1%130CHIP0402LFLTST-C281TBKT-5ALED_BLUESMLF0402LF1/16W
1/16W
IC1301/16WCHIPLED_RST_PLD_CPU0_DRAM_AB_N
ICSMLF1%0402LF1/16WCHIP1%130IC1301%1/16W0402LFCHIPIC
LED_RST_PLD_CPU1_DRAM_AB_NIC1%1301%0402LF1/16WCHIP1%1300402LF1/16WCHIP1%130SMLFIC130
LED_BLUESMLFLED_RST_PLD_CPU1_DRAM_CD_NIC
G1
G2
G1
G1
G1
G2
G2
G1
D1S1S2 D2D1S1D1S1
D1S1S2 D2S2 D2 D1S1
2
5
2
2
2
5
5
2
1 64 31 61 6
1 64 34 3 1 6
Q105
Q100
Q100
Q99
Q97
Q97
Q98
Q98
D72
D71
D69
D70
D65
D66
D67
D68
AC
AC
AC
AC
AC
AC
AC
AC
21
21
21
21
21
21
21
21R1371
C A
C A
C A
C A
C A
C A
C A
C A
SHEETDATE
DEPARTMENT
SIZE
PROJECT DOCUMENT NUMBER REV
REVIEWER
DESIGNER
123
7 3 2 1 6 5 4
E
A
B
C
E
D
C
B
A
7 6 5 4
D
IN
IN
IN
IN
IN
IN
IN
IN
R3085
R3083
R3082
R3084
R3081
R3079
R3080
C



ID (TA/25 DEG) : 0.3AID (TA/25 DEG) : 4A20211201 CONTROL WITH FPGAFri Aug 25 14:04:28 2023N/AN/AN/AN/AV05257 OF 312
I15P3V3_AUXPGPPA_AUXPGPPA_AUXP1V8_PCH_AUXP3V3_AUXPGPPA_AUX
240202FM_LPC_ESPI_SELEMPTYFM_ESPI_PLD_R_EN_BUFFM_ESPI_PLD_R_EN_BUF_RIC0402LF1%BSS138KBSS138KEMPTY R1763, IT ALREADY PU AT SCM BOARD5%01/16W1KEMPTYCHIP10K1/16WCHIP0402LF0: FOR ESPI(DEFAULT),PU 10KOHM AT SCM BOARD.1%0402LFLPC_ESPI_SEL1: FOR LPC10K1%1/16W= P3V3_AUX FOR LPC= P1V8_AUX FOR ESPIPGPPA_AUXLPC PRIMARYESPI IS BACKUPPDG PGPPA TDCP3V3 : 0.2AP1V8 : 0.2AEMPTY0805LF1/8W5%0C080522UF16V20%X6S01/8WCHIP5%0805LFX6S16V22UF20%C0805
R1765
R1747
R4177
R4176
R1764
R1763
G
S D
U307
21
2
1
2
1
2
1
2
1
2
1C513
2
1
2
1
DESIGN NOTE:
DESIGN NOTE:
DESIGN NOTE:
DESIGN NOTE:
DESIGN NOTE:
SHEETDATE
DEPARTMENT
SIZE
PROJECT DOCUMENT NUMBER REV
REVIEWER
DESIGNER
123
7 3 2 1 6 5 4
E
A
B
C
E
D
C
B
A
7 6 5 4
D
IN
OUT
C535
C



3RD 47PF2ND 270PFVOUT=0.6(1+RA/RB)=5.11V20220808 ADD CHANGE LISTPC1877 MAIN 47PF2ND 2.2UFIC TABLE1ST AL0533180022ND AL0005480063RD AL00863300720220804 CHANGE IC TABLE3RD 1UFPC1848 MAIN 1UFRBPCMB104E-4R7MSRAP5V_AUXOCP(IMAX*120%) = 4AOUTPUT VOLTAGE = 5.0VDESIGN SPECIFICATIONSLEW RATE = 1A/USCURRENT STEP = 1AIMAX = 2.1ATDC = 1.8AOUTPUT RIPPLE & NOISE = +/-1.0%DC TOLERANCE = +/-1.5%WORK FREQUENCY = 600KHZTRANSIENT TOLERANCE = +/-5.0%
20220808 ADD CHANGE LIST10.3*11.2*4.0ISAT=13ADCR=15MOHMPR92 NEED CHANGE TO CS38872FB04 FOR EF PARTFri Aug 25 14:04:29 2023N/AN/AN/AN/AV05258 OF 312
P12V_AUXP5V_AUX_VCCP5V_AUX_VCCP5V_AUX
MPQ8633A/P5V_AUX
SMLFRS53318LRSW_P5V_AUX_SW0402LF1%CHIP88.7K10%SW_P5V_AUX_BSTBLM18SN220TN1D/8000MA2592222442130402LF0.1%1/16W11.8KP5V_AUX_FBSW_P5V_AUX_FLTP5V_AUX_MODEPWRGD_P3V3_AUXP5V_AUX_CSP5V_AUX_REFPWRGD_P5V_AUX_R PWRGD_P5V_AUX100NFC040250V10%X7RINDSMLF22UFX6SC080520%16V25VX6S10%1UFC04021/16WCHIP05%22UF20%16VC0805X6S X6S20%16VC080522UF1UF16VC040210%X6S1%16.9KCHIP1/16W0402LFIC0402X7R0.1UF25V10%47PF50V5%NPO04020402LFCHIP25VC0402X7R0.22UF0402LF10K1/16W1%CHIP0402LF5%CHIP 1/16W0SMLF4.7UHINDALUMSMLF220UF20%6.3V22UFC080520%10VX6S X6SC080522UF10V20%0402X7R10%0.1UF25V
PR92
2
1 PC1852
2
1 PC1855
2
1 PC1845
21
PC18772
1
PC1853
PC1846
2
1 PC1850
2
1
PC1848
2
1 PC1849
21
PL64
PC1847
2
1 PC1898
2
1
PR89
21
PL65
2
1
R2356
2
1 PC1856
2
1
PR91
PR3337
R231621
10
19
20
6
5
9
11_18
4
7
8
3
1
2
PU181
1 2
1 2
VIN2
CS
MODE
REF
SW
RTN
VCC
AGND
FB
BST
EN
PGND
PGOODVIN1
21
2
1
2
1PC1648
2
1
21
21
SHEETDATE
DEPARTMENT
SIZE
PROJECT DOCUMENT NUMBER REV
REVIEWER
DESIGNER
123
7 3 2 1 6 5 4
E
A
B
C
E
D
C
B
A
7 6 5 4
D
OUT
IN
C



2ND1ST3RD2ND AL0038840003RD AL003284002PR830 CHANGE TO CS31242BB10R&C TABLEPR831 CHANGE TO CS35602BB01PR834 CHANGE TO CS31622FB02PR836 CHANGE TO CS21002FB06PC569 CHANGE TO CH0106F0B00PC8 CHANGE TO CH5103K19001ST AL003889000IC TABLETO IMPROVE INPUT RIPPLEBASE ON POCESR=9.5M OHM ESR=9.5M OHMP3V3_AUX
RBRA14.3*12.9*8.0ISAT=53A@100CEM-15AM17VG1-QSDCR=1.5M OHMVO=0.8(1+RA/RB)=3.3V
WORK FREQUENCY = 600KHZCURRENT STEP = 10.5AIMAX = 21ATDC = 19ADESIGN SPECIFICATIONSLEW RATE = 2.5A/USOCP = 32ATRANSIENT TOLERANCE = 330MVOUTPUT VOLTAGE = 3.3V+/-5%OUTPUT RIPPLE & NOISE < 50MV
TSS=4MS20220804 CHANGE IC TABLE20220901 ADD D145,CHANGE R1571 TO 100K,C2341 TO 0.22 UFFri Aug 25 14:04:30 2023N/AN/AN/AN/AV05259 OF 312P12V_AUXP12V_AUXP12V_AUXP3V3_AUXP3V3_AUXP3V3_AUX
NCP3284/P3V3_AUX301305214247222 244 258100KNC_PU9_221.5K0402LF1/16WCHIP0402LF1%86.6K1/16WEMPTY0402LF510K5%EMPTY1/16W1/16WNC_PU9_11/16WEMPTY10%X7R0402LF1%ICMB0_P12V_STBY_PWRGDSDMK0340L-7-FSMLF0.22UFC040225V0402LFP3V3_AUX_MODEP3V3_AUX_ILIMP3V3_AUX_SSP3V3_AUX_ENP3V3_AUX_VDRVNC_HICCUPNC_PU9_4NC_PU9_3P3V3_AUX_VCCSW_P3V3_AUX_FLTP3V3_AUX_VOSSW_P3V3_AUX_BOOTPWRGD_P3V3_AUXSW_P3V3_AUX_BOOTRP3V3_AUX_FBSW_P3V3_AUX_SWSW_P3V3_AUX_BOOT_R01/16W5%CHIPX6S10%16V4.7UFC06031.5K1%1%CHIP0402LF10%2.2UF16VX6SC06031/16W0402LFCHIP11%SMLFIR3889MTRPBFICC0402X7R10%100NF50VSMLF100NH/16AIND20%C0805X6S16V22UF20%C080522UFX6S16V20%16VOSCONTHLF270UFOSCON16VTHLF270UF20%X6S20%16VC080522UF22UF16VC080520%X6SX6S20%16V22UFC080520%X6S16V22UFC080520%16VX6S22UFC0805 C080520%16VX6S22UFX6S20%22UF16VC080522UF16VX6S20%C080520%22UF16VC0805X6S16VC080522UFX6S20%0402X7R10%25V0.1UF10%4.7UFX6SC060316V1%0402LF1K1/16W EMPTY0.22UF10% X7R25VCHIP05%0402LF1/16WCHIP1/16W0402LF15K0.1%50VX7R10%220PF04020.1%CHIP47K1/16W0402LFSMLF1.5UH/53AINDTHLF20%6.3VOSCON560UF 560UF20%6.3VOSCONTHLF22UFC080520%10VX6SC0805X6S20%10V22UF 22UFC0805X6S20%10V 25VX7R0.1UF040210%CHIP1/16W10K1%0402LF
PC1600PC1599
2
1
PR73
2
1 PC1869
2
1
2
1
2
1 PC1868
21
PL66
2
1
PR830
21PR835
21
PC568
21 PR836
PC8
2
1 PC577
2
1 PC71
2
1 PC576
PC2344PC2343
2
1 PC571
2
1 PC570
PC2342PC2263
PC567
PC2262
2
1
PC2261PC2260
21
PL45
21 PR389
2
1 PC591
2
1
PR834
2
1
PR833
2
1 PC581
2
1
PR832
C2541
PC566PC3
PC1867PC1866
PR831
R1571
31
3
5
4
36
11_18
29
20_24
25
2
7_10-19
35
34
33
28
1
37
6
30
27
26
32
21
PU9
D145
1 2
GATEL2
SS||Latch
GATEL1
VDRV
En
AGND
NC1
PGood
PVin
SW
NC2
PGND
NC4
VSENM
VCC||LDO
PHASE
ILIM
BOOT
FB
Vin
TON||MODE
NC3
1 2
1 2
2
1
2
1
21PC569
2
1
2
1
2
1
2
1
2
1
2
1
2
1
2
1
2
1
2
1PC1649
2
1
R3117
2
1
R3118
2
1
2
1
SHEETDATE
DEPARTMENT
SIZE
PROJECT DOCUMENT NUMBER REV
REVIEWER
DESIGNER
123
7 3 2 1 6 5 4
E
A
B
C
E
D
C
B
A
7 6 5 4
D
IN
OUT
C



20220225 ADD U324
PUSH PULL OUTPUTOD OUTPUT20220317 ADD ADD R4638,R4639,R4640,R4641
20220519 ADD U330,U99 FOR P3V3Fri Aug 25 14:04:32 2023N/AN/AN/AV05260 OF 312N/AP12V_AUXP3V3P5VP5VP3V3P12V_AUXP3V3_AUXP3V3P12V_AUXP5VP5V_AUXP12V_AUX
P3V3P5VP5V & P3V3 SWITCH
214224213214260260
0402LFCHIP5%0402LFFM_PS_EN_PLD_R5%PWRGD_P3V3_R1PJT138KCHIP1/16W1/16WCHIP0402LFCHIP1/16WPWRGD_P5V100K0402LFCHIP1/16WPJT138KPWRGD_P5V_ISOPWRGD_P3V3C0402RT9818C-44GVCHIP1%1%0402LF10%X6S10%X7R33.20402LFSMLFFM_P5V_ENCHIPIC1% PWRGD_P5V_ISO_RPSMNR58-30YLH100K0402LFCHIP1%100KSMLFPJT138KPWRGD_P5V_N100NFSMLF0402LFICC0805X7R10%50V100NFC040210UF16V10%C0805EMPTY10UF16VICSMLF10%50V100NFX7RC040210UF16V10%C0805ICVR_P5V_EN_D_R1SMLFVR_P5V_EN_N100K1%0402LFICPJT138KICCHIP1206LFCHIP1/4W2431/4W1%243CHIP1206LF1/4WSMLFICC0805VR_P5V_EN_D_RC0402SMLFC080516V10%X6SC08051%10K0402LFC0402X7R50V100NF10%1/16WPSMNR58-30YLH16V10UFX7R10%10UFEMPTY10%50V1/16WIC10UF16V1%2432N7002KX6S10%100NF1206LFCHIP1/4W2431%1%00EMPTY1206LFCHIPX6SCHIP 1/16W25V0.22UF1K1%1/16WCHIP0402LF1/16WVR_P5V_ENC0402VR_P5V_EN_DVR_P5V_EN_N10%X7RSMLFICC0402X7R10%25V0.22UF1K10K1%04020.1UF25VX7RSMLF10%100K0402LF1%1/16W10K0402LFIC50VEMPTY1/16W1%1/16W1%10K0402LFAPX809-29SAG-7BAT547FSMLFCHIP1/16W
G1 G2
G2
G1
G
D1S1S2 D2
S2 D2D1S1S D
C2359
C1226
R4678
R4641R4640R4639R4638
R1642
R1641
R1607
R1640
2 5
5
2
G
1 64 3
4 31 6S D
U330
Q236 Q236
Q37
Q37
U324
Q56
D7
Q57
U99
S
G
D
1
25
3
GND
RESET#
VDD
31
1
25
3
GND
RESET_L
VCC
D1G1S3 S2 S14
D1G1S3 S2 S14
2
1
2
1
2
1
2
1
2
1
2
1
2
1
21
2
1
2
1
2
1
2
1
2
1
2
1
2
1
2
1
2
1
2
1
2
1
2
1
2
1
2
1
2
1
2
1
21
2
1
2
1
2
1
21
21 2
1
2
1
3
2
1
5
3
2
1
31
5
3
2
1
3
1
2
4
4
SHEETDATE
DEPARTMENT
SIZE
PROJECT DOCUMENT NUMBER REV
REVIEWER
DESIGNER
123
7 3 2 1 6 5 4
E
A
B
C
E
D
C
B
A
7 6 5 4
D
OUT
IN
IN
IN
OUT
R4682
R4681
C2360
R4680
R4679
R4677
R1706
C1340C1339
C1338C1333C1332
C1331C1227
R1654
C1171C1170
R1643
C1042
R1655
C1172
C



THIS PAGE WAS INTENTIONALLY LEFT BLANK
Thu Aug 24 16:16:18 2023N/AN/AN/AN/AV05261 OF 312BLANK
SHEETDATE
DEPARTMENT
SIZE
PROJECT DOCUMENT NUMBER REV
REVIEWER
DESIGNER
123
7 3 2 1 6 5 4
E
A
B
C
E
D
C
B
A
7 6 5 4
D
C



IC TABLE2ND AL0005480071ST AL0533190023RD AL00863300520220804 CHANGE IC TABLE20220808 ADD CHANGE LIST3RD 1UF2ND 2.2UFPC113 MAIN 1UF
P1V05_PCH_AUXRB20220808 ADD CHANGE LISTPC1223 MAIN 680PF((7.32/10)+1)*0.6=1.0392VOUT=((RA/RB)+1)*0.62ND 1000PF3RD 680PFRAPLACE AT CHIPSET SIDEREMOTE SENSEDCR=0.17MOHM9.6*6.4*9.0PG1712.301AHLTISAT=29A@125CPDG REV 1.6VOUT=1.05VRIPPLE=+/-0.5%TDC=10.9A20220808 UPDATE PDG REV 1.6WORK FREQUENCY=600KHZP1V05_PCH_AUX SPECIFICATIONDC TOLERANCE=+/-1%TOTAL TOL=+3%~-5%MAX CURRENT=12AOCP(IMAX*130%)=15.6ACURRENT STEP=6.8ASLEW RATE=74A/US
Fri Aug 25 14:04:33 2023N/AN/AN/AN/AV05262 OF 312P3V3_AUXP12V_AUXP3V3_AUXP3V3_AUXP1V05_PCH_AUXP1V05_PCH_AUX
MPQ8633B/P1V05_PCH_AUX VR214214 252213P1V05_PCH_AUX_VCCP1V05_PCH_AUX_CSP1V05_PCH_AUX_REFSW_P12V_AUX_P1V05_PCH_AUX_FLTFM_P1V05_PCH_AUX_ENP1V05_PCH_AUX_MODEFM_P1V05_PCH_AUX_R_ENPWRGD_P1V05_PCH_AUX_RSW_P1V05_PCH_AUX_SWSW_P1V05_PCH_AUX_BSTP1V05_PCH_AUX_FBSH_P1V05_PCH_AUX_NSH_P1V05_PCH_AUX_PPWRGD_P1V05_PCH_AUXPWRGD_PVNN_PCH_AUXX6S25V10%1UFC04021/16W5%0402LFCHIP08.45K1%1/16WCHIP0402LF040250V1000PFEMPTY5%0402LF1%2K1/16WCHIP1/16WCHIP5%00402LFICRS53319LRSMLF0.022UF10%040216VX7R10%040225VX7R0.1UF100NF10%50VC0402X7RIND100NH/16ASMLF100UF16VSMLFOSCON20%22UF16VX6SC080520%10K0402LF1%EMPTY1/16W5%CHIP016V22UFC080520%X6SC080516V22UF20%X6S1UF16VX6S10%C040210%X7R0.22UF25VC04020402LF10K1%1/16WCHIP0.1%CHIP0402LF10K1/16WX7R680PF10%040250V1/16W0402LF7.32K 0.1%CHIP0.01UFX7R25V040210%10%04020.1UF25VX7R330UF35%SMLFSPCAP2VOSCON2.5V20%560UFTHLFEMPTYSMSMEMPTYX6S47UF4VC080520%X6S47UF4VC080520%SPCAP330UF2V35%SMLFOSCON2.5V20%560UFTHLF05%CHIP0402LFCHIP1/16W05%SMLF300NH/33AIND
PR338
21R4780
2
1 PC1230PC117
2
1 PC1224
2
1 PC1216
21
PL110
2
1 PC1221
2
1 PC113
2
1 PC1229
2
1 PC1217
2
1
PR1327
2
1
PR1326
2
1 PC1226
21R1389 21PL150
PJ63
2
1
R2357
2
1 PC1222
2
1 PC1218
21R1650
2
1 PC1225
21PR1647
2
1
21
PJ62
2
1 PC1227
PC2279
21PR1328
21PC1223
2
1
PR187
2
1 PC1219
2
1
PC2000
21
10
19
20
6
5
9
11_18
4
7
8
3
1
2
PR1649PC2286
1 2
SHORT
1 2
SHORT
1 2
1 2
VIN2
CS
MODE
REF
SW
RTN
VCC
AGND
FB
BST
EN
PGND
PGOODVIN1
2
1
21
2
1PC1650
2
1
2
1
21
SHEETDATE
DEPARTMENT
SIZE
PROJECT DOCUMENT NUMBER REV
REVIEWER
DESIGNER
123
7 3 2 1 6 5 4
E
A
B
C
E
D
C
B
A
7 6 5 4
D
OUT
OUT
IN
PU73
PC1215
C



P1V8_PCH_AUX SPECIFICATIONTOTAL TOL=+3.5%~-4%DC TOLERANCE=+/-1.7%2ND AL051372000WORK FREQUENCY=600KHZWORK FREQUENCY=750KHZCURRENT STEP=0.9ASLEW RATE=9A/USMAX CURRENT=2.0ARIPPLE=+/-0.5%PDG RV 1.6TDC=1.6AVOUT=1.8VOCP=4A20220808 UPDATE PDG REV 1.620220804 UPDATE 2ND FREQ.P1V8_PCH_AUX6.5*6.9*3.0DCR=9M OHMISAT=22A3RD AL0006950011ST AL0006820012ND AL051372000IC TABLER TABLE2ND TI USE 5V1ST MPS USE 3V33RD MPS USE 3V320220804 CHANGE IC TABLEPCMC063T-1R0MN
Fri Aug 25 14:04:34 2023N/AN/AN/AN/AV05263 OF 312P5V_AUXPVCC1_AUXP3V3_AUXP12V_AUX
PVCC1_AUXPVCC1_AUXP3V3_AUXP1V8_PCH_AUX
NB695/P1V8_PCH_AUX
2.2UHSMLFSW_P1V8_PCH_AUX_BST0.22UFIND100NF4V 4VPWRGD_P1V8_PCH_AUX214219194222 252P1V8_PCH_AUX_VCCFM_PCH_P1V8_AUX_EN FM_PCH_P1V8_AUX_EN_RSW_P1V8_PCH_AUX_FLTP1V8_PCH_AUX_MODESW_P1V8_PCH_AUX_SWPWRGD_P1V8_PCH_AUX_R1/16W05%0402LFEMPTY1UF10%X6S25VC0402CHIP1/16W0402LF5.15%5%1/16W 0402LF0CHIP1%1/16W1KEMPTY0402LFCAP & DAMPING RS CLOSE TO DRIVE-END10%50V100NFC0402X7RBLM18SN220TN1D/8000MASMLFIND05%CHIP16VX6S10%10UFC080510UF10%16VC0805X6S10%100NF50VC0402X7R0402LF1%1/16W150KCHIPICSMLFNB682GD-ZC0402X7R50V10%C080520%X6S22UFC040225V10%X7RCHIP0402LF1/16W1%10K05%CHIPCAP & DAMPING RS CLOSE TO DRIVE-END50V0.01UF10%X7RC0402C0805X6S20%22UF20%4VX6SC080522UF4VC080522UF20%X6S X6S20%C080522UF4V470CHIP0402LF1/16W1%
2
1 PC1241
21R2360
2
1
R2359
2
1 PC1233
2
1 PC1232
21PL16
21
2
1
PR1329
PR396
2
1 PC1239
2
1 PC1238
2
1 PC1237
2
1
21R2358
2
1 PC1642
2
1
PR1330
PR395
2
1 PC1240
2
1 PC1235
2
1 PC1236
PC1234
PR1653
C2287
PC1651
21
12
1
8
2
13
7
6
5
3
4
9
11
10
PL170
PR1850
PU74
1 2
3V3
SW
VOUT
MODE
C0
C1
LP#
AGND
BST
EN
PGND
PGVIN
1 2
2
1
2
1
2
1 CAD NOTE:
CAD NOTE:
SHEETDATE
DEPARTMENT
SIZE
PROJECT DOCUMENT NUMBER REV
REVIEWER
DESIGNER
123
7 3 2 1 6 5 4
E
A
B
C
E
D
C
B
A
7 6 5 4
D
OUT
IN
C



THIS PAGE WAS INTENTIONALLY LEFT BLANK
Thu Aug 24 16:16:22 2023N/AN/AN/AN/AV05264 OF 312BLANK
SHEETDATE
DEPARTMENT
SIZE
PROJECT DOCUMENT NUMBER REV
REVIEWER
DESIGNER
123
7 3 2 1 6 5 4
E
A
B
C
E
D
C
B
A
7 6 5 4
D
C



THIS PAGE WAS INTENTIONALLY LEFT BLANK
Thu Aug 24 16:16:23 2023N/AN/AN/AN/AV05265 OF 312BLANK
SHEETDATE
DEPARTMENT
SIZE
PROJECT DOCUMENT NUMBER REV
REVIEWER
DESIGNER
123
7 3 2 1 6 5 4
E
A
B
C
E
D
C
B
A
7 6 5 4
D
C



20220725 CONNECT TO CPLDTRACE SPACING = 5MILTRACE WIDTH = 10MILDIFFERENTIAL PAIRCS# SHOULD BE TIDE TO GNDIF SPS IS NOT USEDCONFIRM ADDRESS SETTING
20211013 MODIFY FOR GT
I2C(7BIT/8BIT)SVID00H60H/C0HPVCCIN_CPU0SVID / I2C ADDRESS
DIFFERENTIAL PAIRTRACE SPACING = 5MILTRACE WIDTH = 10MIL
RAIL
442A(UNDERSHOOT)OCP=500ATDC=220A1081A(UNDERSHOOT)TRANSIENT OCP=600AWORK FREQUENCY=700KHZPDG REV.1.6 FOR SPR+HBM20220808 UPDATE PDG REV 1.6LOAD-LINE=0.7 MOHMOCP=164APROTOCOL ID=0AH (VR14 10MV VID)SVID ADDRESS=00H BUS#0WORK FREQUENCY=700KHZSLEW RATE=960A/US(OVERSHOOT)RIPPLE=+/-9MVDC=+/-0.5% OF VIDTDC=102AMAX CURRENT=136ASETVID RATE=10MV/US (FAST)PROTOCOL ID=04H (VR13 10MV VID)SVID ADDRESS=03H BUS#0LOAD-LINE=0.5 MOHMCURRENT STEP=370A(OVERSHOOT)ICCIN_MAX.APP=430ATOTAL TOLERANCE BAND=+/-22MVDC=+/-0.5%RIPPLE=+/-10MVVID=1.6V~1.88V(TYP=1.8 OR1.83V)VBOOT=1.8VPVCCIN_CPU0 SPECIFICATIONVID=1.6V~1.88V(TYP=1.8V)VBOOT=1.8VPVCCFA_EHV_FIVRA_CPU0 SPECIFICATIONPDG REV 1.6 FOR 350W SPR+HBMSETVID RATE=25MV/US (FAST)
Fri Aug 25 14:04:36 2023N/AN/AN/AN/AV05266 OF 312P3V3_AUXP3V3_AUX
P3V3_AUX
PVNN_TERM_CPU0P3V3_AUXP3V3_AUXPVCCIN_CPU0PVCCFA_EHV_FIVRA_CPU0P12V_AUXP3V3_AUXVCCIN/VCCFA_EHV_FIVRA CPU0 VR(1/7)
26926926926826827226821416222142662741426627414266274271272270270270271272271269268
267 268 269 270213253
213253222161427426614274266142662742412842412841621516266267268269270271272270271271272272267267267267266 267 268 269 2702712721UFPVCCIN_CPU0_PWM53300PFPVCCIN_CPU0_PWM6PVCCIN_CPU0_IMON6PVCCIN_CPU0_PWM4PVCCIN_CPU0_IMON4PVCCFA_EHV_FIVRA_CPU0_IMON3PVCCIN_CPU0_IMON31/16W0402LF1%1%0402LF0402LFIRQ_PVCCIN_CPU0_VRHOT_R_N1KVSENSE_PVCCFA_EHV_FIVRA_CPU0_DN100CHIP1K1%0402LF1/16WFM_PVCCFA_EHV_FIVRA_CPU0_EN5%0402LF CHIP 1/16W5%0402LFIRQ_PVCCIN_CPU0_VRHOT_NCHIP5%PVCCIN_CPU0_VR_FAULT1%1K0402LF1/16W0402SH_PVCCFA_EHV_FIVRA_CPU0_R0
0402LF1%1/16WCHIP1
10%X7RC040250V100NFC0603EMPTY20%4V10UF0402LF 1/16WCHIP1%49.9100CHIP1%1/16W0402LF49.90402LF 1/16WEMPTY1%0402LF10K1%1/16WEMPTY10%50VX7R0402470PF
10UF04025%1000PF50VEMPTY5%50V1000PF0402X7R0402LF1/16W33.2CHIP1%X7R10%50V1%0402LF1/16WCHIP33.20402LFCHIP5%0 EMPTY5%01/16W0402LF1/16W0402LFEMPTY5%EMPTY10K1%0402LF1/16W470PFX7R040210%50V5%0X7R10%50V3300PF0
ICSMLF
0402X7R0.1UF25V10%EMPTY1K1%1/16W0402LF0402X7R5%50V1000PF04025%EMPTY50V1000PF01/16WCHIP05%1/16WCHIP0402LF1%0402LF1/16W1KCHIPEMPTY0.1UF25V040210%0402LF0CHIP1/16W5%
0402LFCHIP 1/16W1K 1%0402LF1/16WCHIP5%0CHIP0402LF5%1/16W0CHIP1501%0402LF1/16WCHIP 1/16W0402LF5%04.7K5%EMPTY0402LF 1/16W05%CHIP 1/16W0402LF4.7K5%EMPTYCHIP 1/16W100SMEMPTY0402LFCHIP1%1001/16W1%1000402LFCHIP 1/16WSMEMPTY1/16W1%CHIP0402LF0EMPTY5%1/16W0402LF05%CHIP1/16WCHIP5%00402LFEMPTY 1/16W0402LF1%28KSVID_CLK0_CPU0_RSVID_ALERT0_CPU0_R_NSVID_DIO0_CPU0_RPVCCFA_EHV_FIVRA_CPU0_BTSENPVCCIN_CPU0_IMON7PVCCIN_CPU0_IMON8PVCCIN_CPU0_PWM8PVCCFA_EHV_FIVRA_CPU0_IMON2PVCCFA_EHV_FIVRA_CPU0_IMON4PVCCFA_EHV_FIVRA_CPU0_IMON1PVCCIN_CPU0_IMON5PVCCIN_CPU0_PWM3PVCCIN_CPU0_EN_RPWRGD_PVCCIN_CPU0_RSVID_DIO_PVCCIN_CPU0_RSVID_CLK_PVCCIN_CPU0_RSH_PVCCIN_CPU0_RSMB_CLK_PVCCIN_CPU0SMB_DIO_PVCCIN_CPU0SVID_ALERT_PVCCIN_CPU0_R
PVCCIN_CPU0_ATSENPVCCIN_CPU0_PIN_ALERTPVCCFA_EHV_FIVRA_CPU0_EN_RPVCCIN_CPU0_CSPINPWRGD_PVCCFA_EHV_FIVRA_CPU0_RSH_PVCCFA_EHV_FIVRA_CPU0SH_PVCCIN_CPU0PWRGD_PVCCFA_EHV_FIVRA_CPU0PVCCIN_CPU0_ADDRPVCCIN_CPU0_VIN_CSNIN
PWRGD_PVCCIN_CPU0FM_PVCCIN_CPU0_ENVSENSE_PVCCIN_CPU0_DPSVID_ALERT0_CPU0_R_NSVID_DIO0_CPU0_RSVID_CLK0_CPU0_RSMB_VR_3V3AUX_SDA_R3SMB_VR_3V3AUX_SCL_R3VSENSE_PVCCFA_EHV_FIVRA_CPU0_DPIRQ_PSYS_CRIT_NVSENSE_PVCCIN_CPU0_DNPVCCIN_CPU0_VREF0402PVCCIN_CPU0_PWM7PVCCFA_EHV_FIVRA_CPU0_PWM1PVCCFA_EHV_FIVRA_CPU0_PWM20PVCCFA_EHV_FIVRA_CPU0_PWM3PVCCFA_EHV_FIVRA_CPU0_PWM46.3VPVCCIN_CPU0_IMON2PVCCIN_CPU0_PWM2PVCCIN_CPU0_IMON1PVCCIN_CPU0_PWM1C0402X6S10%X6S10%C04020.1UF25V10%EMPTY1UF16V16VC0402X6S20%PVCCIN_CPU0_VREF0402PVCCIN_CPU0_VCC0402EMPTY10%25V0.1UFRAA229126GNP#HA0
0402LF0402LF1/16WNC_PVCCIN_CPU0_SMB_ALERTCHIP
2
1
2
1
21R2381
R2590
2
1
2
1
2
1
PC1173
21
21
21
21
21
PR400
2
1
21
21
21
21
2
1
21
21PR527
21PR587
R2373
2
1
21R2382
2
1
2
1
2
1
2
1
21
21
21
21
21R2589
21R2376
21
21
21
21
2
1
R4593
40
25
45
46
48
47
TH
44
43
22
21
39
26
12
11
10
9
8
7
6
5
4
3
2
1
13
14
20
16
18
23
15
19
24
17
27
28
29
30
31
32
33
34
35
36
37
38
41
42
PU14
2
1
21
21
21PR531
21PR586
21
21
21R2375
C3271C3270
PC100
PC337PC334
C3266
C3267
R2371
R2372
PR170
PC336
PR345
C3269
R2379
R2377
PC329
R2369
R1712
PR171
PC335
PC331
PC330PR166
C3268
R2591
R2368
R2370
R1713
PR157
PR156
PR159
PR176
PC594
PR158
R2366
PJ47
R2365
PJ53
PR451
PR4218
R4216
PR4217
3
2
1
PJP1
CS10
PWM10
CS9
PWM9
CS8
PWM8
CS7
PWM7
CS0
PWM0
TEMP0
ADDR_CFG
TH_GND
CFP
CS2
PWM2
CS3
PWM3
PWM11
CS1
RGND1
VSEN1
nPINALERT||nPSYS_CRIT
TEMP1||ISYS
VINSEN||VSYS
VMON||IINSEN||VSYS||ISYS
VCCS
PWM6
PG0
PWM1
VSEN0
PWM5
PWM4
PMSDA
RGND0
EN0
nPMALERT
SVCLK
PG1
CS4
CS5
nVRHOT
nSVALERT
CS6
SVDATA
PMSCL
EN1
VCC
CS11
SHORT
1 2
1
2
3
SHORT
1 2
2
1PC2361
21
2
1
2
1
21
21
21 21
21
21
SHEETDATE
DEPARTMENT
SIZE
PROJECT DOCUMENT NUMBER REV
REVIEWER
DESIGNER
123
7 3 2 1 6 5 4
E
A
B
C
E
D
C
B
A
7 6 5 4
D
IN
OUT
IN
OUT
IN
OUT
IN
OUT
IN
OUT
IN
OUT
IN
OUT
IN
IN
BI
OUT
IN
BI
IN
IN
IN
OUT
OUT
OUT
IN
IN
IN
IN
IN
IN
OUT
IN
OUT
IN
OUT
IN
OUT
IN
OUT
IN
OUT
IN
OUT
IN
C



ISAT = 120A @ 100C10.0*8.3*8.0PGL6189.500HLTDCR = 0.04M OHMESR=9.5M OHMESR=9.5M OHMESR=9.5M OHMRESERVE BY ARCHER CITYESR=9.5M OHMDCR=1-4,0.105M OHMISAT=70A@100C11.0*7.5*12.5PGL6303.151HLTDCR=2-3,0.27M OHM
(499OHM) TO ABSORB LEAKAGE FROM SPS.RENESAS RECOMMEND BLEEDER RESISTORAPPLY TO ALL RAILS.DCR=2-3,0.27M OHMDCR=1-4,0.105M OHMISAT=70A@100C11.0*7.5*12.5PGL6303.151HLT
PVCCIN_CPU0_PHASE1PVCCIN_CPU0_PHASE2Fri Aug 25 14:04:37 2023N/AN/AN/AN/AV05267 OF 312PVCCIN_CPU0_PVCC
P5VP3V3
SW_P12V_PVCCIN_CPU0_FLTPVCCIN_CPU0PVCCIN_CPU0
SW_P12V_PVCCIN_CPU0_FLTP12V_AUXPVCCIN_CPU0PVCCIN_CPU0SW_P12V_PVCCIN_CPU0_FLT
VCCIN CPU0 VR PHASE 1&2 (2/7)266267268269270266266267268269270271272266267266267268269270271272267268269270266266266269268267560UFTHLFOSCON2.5V20% 20%560UFTHLFOSCON2.5VEMPTYSMLF330UF+10/-35%2.5VEMPTYSMLF330UF+10/-35%2.5V2.5V20%560UFOSCONTHLF330UF+10/-35%SMLFEMPTY2.5V
THLF270UFOSCON20%16V16VTHLF20%270UFOSCON270UFOSCON16V20%THLFTHLF16VOSCON270UF20%THLF2.5V20%OSCON560UFOSCON20%270UFTHLF16V2.5VOSCON20%560UFTHLFSMLF330UF+10/-35%EMPTY2.5VPVCCIN_CPU0_LSET2PVCCIN_CPU0_PWM2PVCCIN_CPU0_ATSENPVCCIN_CPU0_VREFPVCCIN_CPU0_IMON2PVCCIN_CPU0_VDD2SW_PVCCIN_CPU0_BOOT2SW_PVCCIN_CPU0_BOOTR2SW_PVCCIN_CPU0_SW2IND_P0_CPL2SW_PVCCIN_CPU0_BOOT2_RPVCCIN_CPU0_VDD1PVCCIN_CPU0_VREFPVCCIN_CPU0_LSET1PVCCIN_CPU0_ATSENPVCCIN_CPU0_PWM1PVCCIN_CPU0_IMON1PVCCIN_CPU0_PVCCSW_PVCCIN_CPU0_BOOT1SW_PVCCIN_CPU0_SW1SW_PVCCIN_CPU0_BOOTR1IND_P0_CPL1SW_PVCCIN_CPU0_BOOT1_R
PVCCIN_CPU0_VOS2PVCCIN_CPU0_VOS1IND_P0_CPL3IND_P0_CPL2
1/16WEMPTY1%8.87K0402LFSMLFICISL99390FRZ-TR5935X6S10%2.2UF10VC04020.1UF25V10%X7R04021/16WCHIP1%2.20402LFX6S10%2.2UF10VC04020402LFCHIP1/16W3.31%50V3300PF0402X7R10%C0402X7R10%100NF50VSMLFIND150NHX6S10%1UF16VC040216VX6S22UFC080520%C080522UF16VX6S20%
CHIP1/16W5%00402LF1/16WEMPTY1%8.87K0402LF0.1UF25V10%X7R0402X6S10%2.2UF10VC04021/16WCHIP1%0402LF2.2X6S10%2.2UF10VC0402SMLFICISL99390FRZ-TR59350402LF1/16WEMPTY5%0X7R10%50V3300PF0402150NHSMLFINDX6S10%1UF16VC0402C0402100NFX7R10%50V22UFX6S16VC080520%22UF16VX6SC080520%
5%CHIP00402LF 1/16WX6S22UF16VC080520%C0805X6S22UF4V20%4V22UFX6SC080520%0402LF4991%1/16WCHIP0CHIP5%1/16W0402LF16VX6S22UFC080520%50V10%X7R100NFC04021WEMPTY2512LF0.1%0.03INDSMLF50NH/148A100NFC0402X7R10%50VC040216V1UF10%X6S4V22UFX6SC080520%X6SC080520%22UF4V0402LFCHIP1%1/16W3.3
21PR1787
2
1
2
1
2
1
2
1
21PL15
2
1
PC2336
2
1
2
1
2
1
2
1
PR403
2
1
PR151
2
1
2
1PC300
21PR1786
2
1
2
1
2
1
1
30
25_29
3
36
10_19
39
34
4
32
40
7_9-20_24
5
37
38
41
6
35
31
33
2
PU12_P0_2
2
1
2
1
2
1
2
1
PC1920
PR4219
2
1
21PC1356
PR402
4
32
1
PL13
2
1
2
1
PR150
2
1
2
1
2
1
21PR155
2
1
2
1
2
1
21PR154
2
1
2
1PC301
2
1
2
1
2
1
2
1
PC16
2
1
4
32
1
PL114
1
30
25_29
3
36
10_19
39
34
4
32
40
7_9-20_24
5
37
38
41
6
35
31
33
2
PU13_P0_12
1
2
1
2
1
2
1
21PC1355
PC324PC321
PC312_P0_1PC308_P0_1
PC313_P0_2PC311_P0_2
PC299_P0_1PC297_P0_1
PC302_P0_2
PC294_P0_2PR152
PC292
PC307_P0_1
PC322
PC326
PC303_P0_1
PC296_P0_2
PC318PC315
PC314_P0_1
PC325
PC323
PC316
PC305_P0_1
PR153
PC310_P0_1
PC319
PC306_P0_2
PC295_P0_1
PC293
PC304_P0_2PC298_P0_2
PR2554
PC2345
1 2
PGND2
GL2
GL1
DNC
EN
PGND3
VOS
VIN2
PGND1
SW
LSET
IOUT
TOUT_FLT
PVCC
PHASE
VIN1
BOOT
AGND
VCC
REFIN
PWM
1 4
32
PGND2
GL2
GL1
DNC
EN
PGND3
VOS
VIN2
PGND1
SW
LSET
IOUT
TOUT_FLT
PVCC
PHASE
VIN1
BOOT
AGND
VCC
REFIN
PWM
1 4
32
2
1PC1652 21
2
1
2
1
SHEETDATE
DEPARTMENT
SIZE
PROJECT DOCUMENT NUMBER REV
REVIEWER
DESIGNER
123
7 3 2 1 6 5 4
E
A
B
C
E
D
C
B
A
7 6 5 4
D
OUT
BI
IN
BI
OUT
BI
IN
OUT
IN
OUT
IN
BI
C



ISAT=70A@100C11.0*7.5*12.5PGL6303.151HLTDCR=1-4,0.105M OHMDCR=2-3,0.27M OHMPGL6303.151HLT11.0*7.5*12.5ISAT=70A@100CDCR=1-4,0.105M OHMDCR=2-3,0.27M OHM
PVCCIN_CPU0_PHASE3PVCCIN_CPU0_PHASE4Fri Aug 25 14:04:38 2023N/AN/AN/AN/AV05268 OF 312PVCCIN_CPU0_PVCCPVCCIN_CPU0_PVCCSW_P12V_PVCCIN_CPU0_FLTSW_P12V_PVCCIN_CPU0_FLT
PVCCIN_CPU0PVCCIN_CPU0
VCCIN CPU0 VR PHASE 3&4 (3/7)266267268269270271272267268269270266266266266267268269270266266266267268269270271272268 269267 268PVCCIN_CPU0_LSET4PVCCIN_CPU0_VDD4PVCCIN_CPU0_VREFPVCCIN_CPU0_ATSENPVCCIN_CPU0_PWM4PVCCIN_CPU0_IMON4PVCCIN_CPU0_PWM3PVCCIN_CPU0_ATSENPVCCIN_CPU0_VDD3PVCCIN_CPU0_IMON3PVCCIN_CPU0_VREFSW_PVCCIN_CPU0_SW4SW_PVCCIN_CPU0_BOOTR4IND_P0_CPL4SW_PVCCIN_CPU0_BOOT4 SW_PVCCIN_CPU0_BOOT4_RPVCCIN_CPU0_VOS4PVCCIN_CPU0_VOS3IND_P0_CPL5
SW_PVCCIN_CPU0_BOOT3SW_PVCCIN_CPU0_SW3SW_PVCCIN_CPU0_BOOTR3SW_PVCCIN_CPU0_BOOT3_RIND_P0_CPL3 IND_P0_CPL4PVCCIN_CPU0_LSET38.87K1%EMPTY1/16W0402LF1/16W0402LF8.87K1%EMPTYC040210V2.2UF10%X6S25V0.1UFX7R 10%0402ISL99390FRZ-TR5935ICSMLF0402LF2.21%CHIP1/16W10%C040210V2.2UFX6SISL99390FRZ-TR5935ICSMLFC040210V2.2UF10%X6S0.1UF 040210%X7R25V0402LF2.21%CHIP1/16WC040210V2.2UF10%X6S
IND150NHSMLFC040250V100NF10%X7R040250V10%X7R3300PF0402LFCHIP1/16W1%3.3C040216V1UFX6S10%16V22UF20%X6SC080522UFC080516V20%X6S1/16W0402LF05%CHIP16VX6S20%22UFC08051/16W5%0402LF0CHIP040250V3300PF10%X7R1%3.31/16W0402LFCHIP150NHINDSMLFC0402X7R50V100NF10%C040216V1UF10%X6SC080516V22UF20%X6SC080516V22UF20%X6SC080516V22UF20%X6SX6S20%22UF4VC0805X6S20%22UF4VC0805X6S20%22UF4VC0805X6S20%22UF4VC0805
2
1
2
1
2
1
2
1
2
1
2
1
21PR149
2
1
21PR148
2
1PC278
4
32
1
PL11
2
1
1
30
25_29
3
36
10_19
39
34
4
32
40
7_9-20_24
5
37
38
41
6
35
31
33
2
PU11_P0_3
21PC1340
2
1
2
1
PR145
2
1
2
1
2
1PC279
4
32
1
PL112
21PR1769
2
1
2
1
2
1
2
1
21PR1768
2
1
2
1
2
1
21PC1341
2
1
2
1
PR146
1
30
25_29
3
36
10_19
39
34
4
32
40
7_9-20_24
5
37
38
41
6
35
31
33
2
PU10_P0_4
2
1
PR144
PC291_P0_3
PC290_P0_4PC288_P0_4
PC289_P0_3
PC283_P0_3PC277_P0_3
PC284_P0_4
PC271
PC270
PC285_P0_3PC281_P0_3PC275_P0_3
PC282_P0_4PC280_P0_4PC276_P0_4PC274_P0_4
PC273_P0_3PR147
PC272_P0_4
1 4
32
1 4
32
PGND2
GL2
GL1
DNC
EN
PGND3
VOS
VIN2
PGND1
SW
LSET
IOUT
TOUT_FLT
PVCC
PHASE
VIN1
BOOT
AGND
VCC
REFIN
PWM
PGND2
GL2
GL1
DNC
EN
PGND3
VOS
VIN2
PGND1
SW
LSET
IOUT
TOUT_FLT
PVCC
PHASE
VIN1
BOOT
AGND
VCC
REFIN
PWM
SHEETDATE
DEPARTMENT
SIZE
PROJECT DOCUMENT NUMBER REV
REVIEWER
DESIGNER
123
7 3 2 1 6 5 4
E
A
B
C
E
D
C
B
A
7 6 5 4
D
OUT
IN
OUT
IN
BIBI
BIBI
OUT
IN
OUT
IN
C



PGL6303.151HLTDCR=2-3,0.27M OHMDCR=1-4,0.105M OHMISAT=70A@100C11.0*7.5*12.5PGL6303.151HLT11.0*7.5*12.5ISAT=70A@100CDCR=1-4,0.105M OHMDCR=2-3,0.27M OHMPVCCIN_CPU0_PHASE6PVCCIN_CPU0_PHASE5
Fri Aug 25 14:04:39 2023N/AN/AN/AN/AV05269 OF 312PVCCIN_CPU0_PVCCPVCCIN_CPU0_PVCCSW_P12V_PVCCIN_CPU0_FLTSW_P12V_PVCCIN_CPU0_FLT
PVCCIN_CPU0PVCCIN_CPU0
VCCIN CPU0 VR PHASE 5&6 (4/7)266267268269270266266267268269270271272266267268269270266266266266267268269270271272270 267268 270PVCCIN_CPU0_LSET6PVCCIN_CPU0_VDD6PVCCIN_CPU0_PWM6PVCCIN_CPU0_ATSENPVCCIN_CPU0_VREFPVCCIN_CPU0_IMON6PVCCIN_CPU0_ATSENPVCCIN_CPU0_PWM5PVCCIN_CPU0_LSET5PVCCIN_CPU0_VDD5PVCCIN_CPU0_IMON5PVCCIN_CPU0_VREFSW_PVCCIN_CPU0_SW6SW_PVCCIN_CPU0_BOOTR6IND_P0_CPL6SW_PVCCIN_CPU0_BOOT6 SW_PVCCIN_CPU0_BOOT6_RPVCCIN_CPU0_VOS6PVCCIN_CPU0_VOS5IND_P0_CPL1
SW_PVCCIN_CPU0_BOOT5SW_PVCCIN_CPU0_BOOTR5SW_PVCCIN_CPU0_SW5SW_PVCCIN_CPU0_BOOT5_RIND_P0_CPL5 IND_P0_CPL8
0402LF8.87K1%EMPTY1/16W0402LF8.87K1%EMPTY1/16W0.1UF10%X7R25V0402ISL99390FRZ-TR5935ICSMLFC040210V2.2UF10%X6S0402LF2.21%CHIP1/16WC040210V2.2UF10%X6SC040210V2.2UF10%X6SX7R040210%0.1UF25V0402LF2.21%CHIP1/16WC040210V2.2UF10%X6S
SMLFIND150NHC040250V100NF10%X7R040250V3300PF10%X7R0402LF3.3CHIP1%1/16WC040216V1UF10%X6SC080516V22UF20%X6SC080516V22UF20%X6S0402LF05%CHIP1/16WX6S20%22UF4VC0805C080516V22UF20%X6S1/16W5%CHIP00402LF040250V3300PF10%X7R1/16WCHIP0402LF1%3.3SMLFIND150NH50V100NF10%X7RC0402C040216V1UF10%X6SC080516V22UF20%X6SC080516V22UF20%X6S X6S20%22UF16VC0805
X6S20%22UF4VC0805X6S20%22UF4VC0805X6S20%22UF4VC0805ISL99390FRZ-TR5935ICSMLF
PC250_P0_6
1
30
25_29
3
36
10_19
39
34
4
32
40
7_9-20_24
5
37
38
41
6
35
31
33
2
PU9_P0_5
2
1
2
1
2
1
2
1
2
1
2
1
2
1PC257
4
32
1
PL10
21PR1771
2
1
21PR143
2
1
21PR1770
2
1PC256
2
1
2
1
21PC1343
2
1
2
1
2
1
2
1
PR139
2
1
2
1
21PR142
2
1
2
1
2
1
2
1
4
32
1
PL9
2
1
1
30
25_29
3
36
10_19
39
34
4
32
40
7_9-20_24
5
37
38
41
6
35
31
33
2
PU8_P0_6
21PC1342
2
1
PR138
PC269_P0_5PC267_P0_5
PC263_P0_5PC261_P0_5PC259_P0_5PC255_P0_5PC253_P0_5
PC262_P0_6
PC251_P0_5PR141
PC249
PR140
PC248
PC268_P0_6PC266_P0_6
PC260_P0_6PC258_P0_6PC254_P0_6PC252_P0_6
PGND2
GL2
GL1
DNC
EN
PGND3
VOS
VIN2
PGND1
SW
LSET
IOUT
TOUT_FLT
PVCC
PHASE
VIN1
BOOT
AGND
VCC
REFIN
PWM
1 4
32
1 4
32
PGND2
GL2
GL1
DNC
EN
PGND3
VOS
VIN2
PGND1
SW
LSET
IOUT
TOUT_FLT
PVCC
PHASE
VIN1
BOOT
AGND
VCC
REFIN
PWM
SHEETDATE
DEPARTMENT
SIZE
PROJECT DOCUMENT NUMBER REV
REVIEWER
DESIGNER
123
7 3 2 1 6 5 4
E
A
B
C
E
D
C
B
A
7 6 5 4
D
IN
OUT
IN
OUT
BIBI
BIBI
IN
OUT
IN
OUT
C



DCR=1-4,0.105M OHMISAT=70A@100C11.0*7.5*12.5PGL6303.151HLTDCR=2-3,0.27M OHM11.0*7.5*12.5ISAT=70A@100CDCR=1-4,0.105M OHMDCR=2-3,0.27M OHMPGL6303.151HLT
PVCCIN_CPU0_PHASE7PVCCIN_CPU0_PHASE8PGL6312.121AHLT6.5*6.5*10.0ISAT=60A@100CDCR=0.17M OHM
Fri Aug 25 14:04:41 2023N/AN/AN/AN/AV05270 OF 312
PVCCIN_CPU0SW_P12V_PVCCIN_CPU0_FLT
PVCCIN_CPU0SW_P12V_PVCCIN_CPU0_FLTPVCCIN_CPU0_PVCCPVCCIN_CPU0_PVCC
VCCIN CPU0 VR PHASE 7&8 (5/7)266267268269270271272266267268269270266266266267268269270271272266269269266267268269270266PVCCIN_CPU0_VREFPVCCIN_CPU0_LSET80402X7R10%25V0.1UFPVCCIN_CPU0_IMON8PVCCIN_CPU0_VDD80402LF3.31/16WCHIP10%X7RC040250V100NFSW_PVCCIN_CPU0_BOOT8_RC080516V22UFC0402X7R10%SW_PVCCIN_CPU0_BOOT7_R1UF16V10%SW_PVCCIN_CPU0_BOOT71UF4V16V150NHSMLF50V100NFCHIP0402LF1%1/16W3.325VICC0402PVCCIN_CPU0_LSET7PVCCIN_CPU0_ATSENPVCCIN_CPU0_PWM7040210%X7R0.1UFPVCCIN_CPU0_VREFPVCCIN_CPU0_IMON7PVCCIN_CPU0_VDD7SW_PVCCIN_CPU0_BOOTR7SW_PVCCIN_CPU0_SW7C0805X6S20%22UF4VC0805X6S20%22UFC080516V22UF20%X6SC080516V22UF20%X6S10%C0402X6SIND05%CHIP0402LF 1/16WC0805X6S20%22UF4VC0805X6S20%22UF4VX6S1UF16V10%C040222UF16V20%X6SC080516V20%X6S22UFC08050402LF05%CHIP1/16WSMLF150NHIND
C080516V22UF20%X6SC0402X6S040250V3300PF10%X7RINDSMLF120NH/69AC040210V2.2UF10%X6S0402LF2.21%CHIP1/16WISL99390FRZ-TR5935SMLF10V2.2UF10%X6S0402LF8.87K1%EMPTY1/16W20%X6SC040216V1UF10%X6S1%040250V3300PF10%X7RC040210V2.2UF10%X6S2.21%CHIP1/16W0402LFC040210V2.2UF10%X6S0402LF8.87K1%EMPTY1/16WISL99390FRZ-TR5935ICSMLFIND_P0_CPL6SW_PVCCIN_CPU0_BOOTR8SW_PVCCIN_CPU0_SW8IND_P0_CPL8IND_P0_CPL7PVCCIN_CPU0_VOS7PVCCIN_CPU0_VOS8SW_PVCCIN_CPU0_BOOT8PVCCIN_CPU0_PWM8PVCCIN_CPU0_ATSEN
2
1
2
1
2
1
2
1
2
1
PC235
2
1
2
1
2
1
2
1
21PR136
2
1
PC234
4
32
1
PL7
2
1
2
1
2
1
1
30
25_29
3
36
10_19
39
34
4
32
40
7_9-20_24
5
37
38
41
6
35
31
33
2
PU7_P0_7
2
1
21PC1345
2
1
PR133
2
1
2
1
2
1
2
1
2
1
21PC1344
2
1
PR132
2
1
4
32
1
PL8
21PR137
2
1
21PR1773
2 1
PL105
2
1
2
1
2
1
21PR1772
1
30
25_29
3
36
10_19
39
34
4
32
40
7_9-20_24
5
37
38
41
6
35
31
33
2
PU6_P0_8
PC247_P0_7PC245_P0_7
PC239_P0_7
PC243_P0_7
PC246_P0_8PC244_P0_8
PC240_P0_8PC238_P0_8
PC237_P0_7PC233_P0_7PC231_P0_7
PC227
PC236_P0_8PC230_P0_8
PC228_P0_8PR134
PC226
PC241_P0_7
PC242_P0_8
PC229_P0_7PR135
PC232_P0_8
1 4
32
1 4
32
12
PGND2
GL2
GL1
DNC
EN
PGND3
VOS
VIN2
PGND1
SW
LSET
IOUT
TOUT_FLT
PVCC
PHASE
VIN1
BOOT
AGND
VCC
REFIN
PWM
PGND2
GL2
GL1
DNC
EN
PGND3
VOS
VIN2
PGND1
SW
LSET
IOUT
TOUT_FLT
PVCC
PHASE
VIN1
BOOT
AGND
VCC
REFIN
PWM
SHEETDATE
DEPARTMENT
SIZE
PROJECT DOCUMENT NUMBER REV
REVIEWER
DESIGNER
123
7 3 2 1 6 5 4
E
A
B
C
E
D
C
B
A
7 6 5 4
D
OUT
IN
BI
OUT
IN
OUT
IN
IN
OUT
BI
C



ESR=9.5M OHMDCR = 0.12M OHMISAT = 13A @ 100CHCBS4545-1014.5*4.5*4.5ISAT = 90A @ 100CDCR = 0.103M OHM10.0*7.5*12.0PG2323.131HLT
(499OHM) TO ABSORB LEAKAGE FROM SPS.RENESAS RECOMMEND BLEEDER RESISTORAPPLY TO ALL RAILS.10.0*7.5*12.0PG2323.131HLTDCR = 0.103M OHMISAT = 90A @ 100C
PVCCFA_EHV_FIVRA_CPU0_PHASE120211013 MODIFY FOR GT
PVCCFA_EHV_FIVRA_CPU0_PHASE2Fri Aug 25 14:04:42 2023N/AN/AN/AN/AV05271 OF 312
P5VP5VP3V3P3V3
SW_P12V_PVCCFA_EHV_FIVRA_CPU0_LPVCCFA_EHV_FIVRA_CPU0PVCCFA_EHV_FIVRA_CPU0SW_P12V_PVCCFA_EHV_FIVRA_CPU0_RP12V_AUXPVCCFA_EHV_FIVRA_CPU0SW_P12V_PVCCFA_EHV_FIVRA_CPU0_L
VCCFA_EHV_FIVRA CPU0 VR PHASE 1&2(6/7)266271272266266266267268269270271272266271272266266266267268269270271272 20%560UFTHLF2.5VOSCON16V270UFOSCON20%THLF2.5VOSCON20%560UFTHLF2.5VOSCON20%560UFTHLFPVCCFA_EHV_FIVRA_CPU0_LSET2PVCCFA_EHV_FIVRA_CPU0_LSET1
PVCCFA_EHV_FIVRA_CPU0_PWM2PVCCFA_EHV_FIVRA_CPU0_BTSENPVCCFA_EHV_FIVRA_CPU0_IMON2PVCCIN_CPU0_VREFPVCCFA_EHV_FIVRA_CPU0_PVCC2PVCCFA_EHV_FIVRA_CPU0_PWM1PVCCFA_EHV_FIVRA_CPU0_VDD2SW_PVCCFA_EHV_FIVRA_CPU0_BOOT2
PVCCFA_EHV_FIVRA_CPU0_PVCC1PVCCFA_EHV_FIVRA_CPU0_BTSENPVCCFA_EHV_FIVRA_CPU0_IMON1PVCCIN_CPU0_VREFSW_PVCCFA_EHV_FIVRA_CPU0_BOOT1SW_PVCCFA_EHV_FIVRA_CPU0_BOOTR1
PVCCFA_EHV_FIVRA_CPU0_VOS2
SW_PVCCFA_EHV_FIVRA_CPU0_SW1SW_PVCCFA_EHV_FIVRA_CPU0_BOOT1_RPVCCFA_EHV_FIVRA_CPU0_VOS1SW_PVCCFA_EHV_FIVRA_CPU0_BOOT2_RSW_PVCCFA_EHV_FIVRA_CPU0_BOOTR2SW_PVCCFA_EHV_FIVRA_CPU0_SW2
PVCCFA_EHV_FIVRA_CPU0_VDD1
1%8.87K1/16WEMPTY0402LF0402LF1/16WCHIP5%0EMPTY0402LF1/16W1%8.87K1/16WCHIP5%00402LF
0.1UF25V0402X7R10%SMLFISL99390FRZ-TR5935ICX6S10%2.2UF10VC04020402LFCHIP1%1/16W2.2C0402X6S10%10V2.2UFEMPTY5%0402LF1/16W0SMLFICISL99390FRZ-TR593510%3300PF50V0402X7R X6S1UF16VC040210%1%CHIP0402LF 1/16W3.3X6S16VC080522UF20%16VX6SC080522UF20%0402X7R10%25V0.1UFC0402X6S10%2.2UF10VCHIP1%2.20402LF1/16W1/16WEMPTY5%00402LF2.2UFX6SC040210%10V X7R10%3300PF50V0402X6S10%C04021UF16V1%3.3CHIP0402LF1/16WX6SC080522UF16V20%22UFX6SC080516V20%
IND130NH/106ASMLF1/16WCHIP5%00402LF1UFX6S10%C040216VC080522UF4VX6S20%X7R10%100NF50VC0402C080516V22UFX6S20%X6SC08054V22UF20%1/16W1%0402LF499CHIP+10/-35%330UFSMLFSPCAP2.5V330UF2.5VSMLF+10/-35%SPCAP5%00402LFCHIP 1/16WIND130NH/106ASMLF50V100NFX7R10%C0402X6S22UF16VC080520%100NFC0402X7R10%50V4V22UFX6SC080520%C0402X7R50V100NF10%100NH/16AINDSMLFX6S22UF4VC080520%22UFC0805X6S16V20%16VC0805X6S22UF20%C080516V22UFX6S20%22UF16VX6SC080520%
PC1672PC1671PC1669 PC1670
2
1
2
1
2
1
PC720_P0_1
2
1PC606
2
1
PC2645
2
1
PR4265
PC721_P0_2
2
1PC607
2
1 PC1211_P0_1
PR632
2
1
21PC1349
2
1
2
1
1
30
25_29
3
36
10_19
39
34
4
32
40
7_9-20_24
5
37
38
41
6
35
31
33
2
PU69_P0_1 21PL44
21
PL33
2
1
2
1
2
1
2
1
21PR1781
2
1 PC1212_P0_2
2
1
2
1
21PC1350
PR444
PR447
2
1
21PR1322
1
30
25_29
3
36
10_19
39
34
4
32
40
7_9-20_24
5
37
38
41
6
35
31
33
2
PU70_P0_2
2
1
2
1
2
1
PR633
2
1
2
1
2
1
2
1
2
1
21PR1323
21
PL34
2
1
21PR1780
2
1
2
1
PC622
PC617_P0_1PC612_P0_1
PC623
PC600
PC611_P0_2PC605_P0_2 PC620PC619
PC616_P0_2
PC609_P0_2
PR356
PC601
PC615_P0_1
PR354
PC613_P0_2
PC608_P0_1PC604_P0_1PC602_P0_1
PC603_P0_2 PC621
PC618_P0_2
PC610_P0_1
PR355
PR353
1 2
1 2
1 2
PGND2
GL2
GL1
DNC
EN
PGND3
VOS
VIN2
PGND1
SW
LSET
IOUT
TOUT_FLT
PVCC
PHASE
VIN1
BOOT
AGND
VCC
REFIN
PWM
PGND2
GL2
GL1
DNC
EN
PGND3
VOS
VIN2
PGND1
SW
LSET
IOUT
TOUT_FLT
PVCC
PHASE
VIN1
BOOT
AGND
VCC
REFIN
PWM
2
1
2
1PC16532
1
2
1
2
1
2
1
2
1
2
1
SHEETDATE
DEPARTMENT
SIZE
PROJECT DOCUMENT NUMBER REV
REVIEWER
DESIGNER
123
7 3 2 1 6 5 4
E
A
B
C
E
D
C
B
A
7 6 5 4
D
OUT
IN
OUT
IN
OUT
IN
OUT
IN
C



ESR=9.5M OHMDCR = 0.12M OHMISAT = 13A @ 100C4.5*4.5*4.5HCBS4545-101DCR = 0.103M OHMISAT = 90A @ 100C10.0*7.5*12.0PG2323.131HLTPG2323.131HLT10.0*7.5*12.0ISAT = 90A @ 100CDCR = 0.103M OHMPVCCFA_EHV_FIVRA_CPU0_PHASE4PVCCFA_EHV_FIVRA_CPU0_PHASE320211013 MODIFY FOR GT
Fri Aug 25 14:04:43 2023N/AN/AN/AN/AV05272 OF 312
PVCCFA_EHV_FIVRA_CPU0_PVCC2PVCCFA_EHV_FIVRA_CPU0_PVCC1SW_P12V_PVCCFA_EHV_FIVRA_CPU0_LSW_P12V_PVCCFA_EHV_FIVRA_CPU0_RP12V_AUX
PVCCFA_EHV_FIVRA_CPU0PVCCFA_EHV_FIVRA_CPU0PVCCFA_EHV_FIVRA_CPU0SW_P12V_PVCCFA_EHV_FIVRA_CPU0_R
VCCFA_EHV_FIVRA CPU0 VR PHASE 3&4(7/7)266271272266266267268269270271272266266266267268269270271272266271272266 16V270UFOSCON20%THLF2.5VOSCON20%560UFTHLF2.5VOSCON20%560UFTHLF2.5VOSCON20%560UFTHLFPVCCFA_EHV_FIVRA_CPU0_PWM4PVCCFA_EHV_FIVRA_CPU0_BTSENPVCCIN_CPU0_VREFPVCCFA_EHV_FIVRA_CPU0_IMON4PVCCFA_EHV_FIVRA_CPU0_LSET4PVCCFA_EHV_FIVRA_CPU0_PWM3PVCCFA_EHV_FIVRA_CPU0_VDD4PVCCFA_EHV_FIVRA_CPU0_VDD3PVCCIN_CPU0_VREFPVCCFA_EHV_FIVRA_CPU0_IMON3PVCCFA_EHV_FIVRA_CPU0_BTSENPVCCFA_EHV_FIVRA_CPU0_LSET3SW_PVCCFA_EHV_FIVRA_CPU0_BOOT4PVCCFA_EHV_FIVRA_CPU0_VOS4SW_PVCCFA_EHV_FIVRA_CPU0_BOOTR4SW_PVCCFA_EHV_FIVRA_CPU0_BOOT4_RSW_PVCCFA_EHV_FIVRA_CPU0_SW4
SW_PVCCFA_EHV_FIVRA_CPU0_BOOT3SW_PVCCFA_EHV_FIVRA_CPU0_BOOTR3SW_PVCCFA_EHV_FIVRA_CPU0_BOOT3_RPVCCFA_EHV_FIVRA_CPU0_VOS3SW_PVCCFA_EHV_FIVRA_CPU0_SW3
8.87K1%EMPTY0402LF1/16W0.1UF10%0402X7R25VISL99390FRZ-TR5935ICSMLF2.2CHIP0402LF1/16W1%2.2UF10V10%X6SC04020402LF8.87K1/16WEMPTY1%10VX6SC040210%2.2UF10%X6S2.2UF10VC040210%040225V0.1UFX7R1/16WCHIP2.21%0402LF10%X6S10VC04022.2UFX7R10%040250V3300PF1%1/16WCHIP0402LF3.310%X6SC040216V1UF16VX6S22UFC080520%C0805X6S22UF16V20%C0402100NFX7R50V10%0402LF5%1/16WCHIP0SMLF130NH/106AINDX7R100NF50V10%C040216V22UFC0805X6S20%50V3300PFX7R10%04021/16W3.31%CHIP0402LF16VX6S1UFC040210%22UFX6S16VC080520%22UF16VX6SC080520%100NF50V10%X7RC04020402LFCHIP 1/16W05%SMLFIND130NH/106AC0805X6S16V22UF20%10%16VX6SC04021UFX7R100NF50V10%C0402100NH/16AINDSMLF
X6SC080522UF4V20%C080522UF4VX6S20%SPCAPSMLF330UF+10/-35%2.5VSPCAPSMLF330UF+10/-35%2.5V4VC080522UFX6S20%22UFC08054VX6S20%X6S22UF16VC080520%C080522UF16VX6S20%22UFC080516VX6S20%16VC080522UFX6S20%ICISL99390FRZ-TR5935SMLF
PC1676PC1673 PC1674 PC1675
2
1
2
1
PC2170
2
1
PC1187
2
1
PC1185
2
1
PC1183
21PL101
PC722_P0_3
2
1PC1177
2
1
2
1
2
1
2
1 PC1213_P0_3
2
1
PR1299
2
1 PC1214_P0_4
2
1
1
30
25_29
3
36
10_19
39
34
4
32
40
7_9-20_24
5
37
38
41
6
35
31
33
2
PU72_P0_4
21PC1352
2
1
1
30
25_29
3
36
10_19
39
34
4
32
40
7_9-20_24
5
37
38
41
6
35
31
33
2
PU71_P0_3
2
1
2
1
21PR1324
2
1
2
1
21PR1325
2
1
21PC1351
2
1
2
1
21
PL2
PC723_P0_4
2
1PC1178
2
1
PC1186
2
1
2
1
2
1
21PR1782
2
1
2
1
PC1183_P0_4
21PL210
2
1
21PR1783
2
1
PC1187_P0_3
PC1179_P0_3
PC1180_P0_4PC1176_P0_4
PC1172
PR1297
PC1189
PC1186_P0_4
PC1181_P0_3
PC1185_P0_3
PC1174_P0_4
PR1298
PR1300
PC1188_P0_4
PC1183_P0_3
PC1175_P0_3PC1173_P0_3
PC1182_P0_4
PC1171
PGND2
GL2
GL1
DNC
EN
PGND3
VOS
VIN2
PGND1
SW
LSET
IOUT
TOUT_FLT
PVCC
PHASE
VIN1
BOOT
AGND
VCC
REFIN
PWM
1 2
1 2
1 2
PGND2
GL2
GL1
DNC
EN
PGND3
VOS
VIN2
PGND1
SW
LSET
IOUT
TOUT_FLT
PVCC
PHASE
VIN1
BOOT
AGND
VCC
REFIN
PWM
2
12
1
2
1
2
1PC1654
2
1
2
1
2
1
SHEETDATE
DEPARTMENT
SIZE
PROJECT DOCUMENT NUMBER REV
REVIEWER
DESIGNER
123
7 3 2 1 6 5 4
E
A
B
C
E
D
C
B
A
7 6 5 4
D
OUT
IN
OUT
IN
OUT
IN
OUT
IN
C



Thu Aug 24 16:16:33 2023N/AN/AN/AN/AV05273 OF 312BLANK
SHEETDATE
DEPARTMENT
SIZE
PROJECT DOCUMENT NUMBER REV
REVIEWER
DESIGNER
123
7 3 2 1 6 5 4
E
A
B
C
E
D
C
B
A
7 6 5 4
D
C



20220725 CONNECT TO CPLDCURRENT STEP=4.75A(1.5A-6.25A)WORK FREQUENCY=600KHZSVID ADDRESS=02H BUS#0PROTOCOL ID=04H (VR13 10MV VID)SETVID RATE=10MV/US (FAST)PDG REV.1.6 FOR SPR+HBM20220808 UPDATE PDG REV 1.6PDG REV.1.6 FOR SPR+HBMTOTAL TOLERANCE=1.841VMAX/1.749VMINVID=1.6V~1.87V(TYP=1.8V)PVCCFA_EHV_CPU0 SPECIFICATIONSLEW RATE=5.3ATDC=5AOCP=15ALOAD-LINE=N/ASVID ADDRESS=01H BUS#0PROTOCOL ID=09H (VR14 5MV VID)RIPPLE=+/-9MVMAX CURRENT=6.25ADC=+/-0.5% OF VID
61H/C2HI2C(7BIT/8BIT)01HSVIDRAILPVCCINFAON_CPU061H/C2HPVCCFA_EHV_CPU002HSVID / I2C ADDRESSTRACE SPACING = 5MILSET FW CODE FUNCTION TO BVR_ENCONFIRM ADDRESS SETTINGTRACE WIDTH = 10MILTRACE SPACING = 5MILTRACE WIDTH = 10MILDIFFERENTIAL PAIRDIFFERENTIAL PAIRVBOOT=1.8VSETVID RATE=2.5MV/US (FAST)WORK FREQUENCY=700KHZPVCCINFAON_CPU0 SPECIFICATIONVBOOT=1.0VVID=0.7V~1.05V(TYP=1.0V)RIPPLE=+/-8MVDC=+/-0.5%@1VTOTAL TOLERANCE=1.05VMAX/0.909VMIN(EMR 1.05VAMX/0.93VMIN)TDC=48A(EMR 42A)MAX CURRENT=53A(EMR 46A)OCP=69A(130%)CURRENT STEP=15A(38A-53A)(EMR 31A-46A)SLEW RATE=18A/US(EMR 20.2A/US)LOAD-LINE=2.2 MOHM
Fri Aug 25 14:04:45 2023N/AN/AN/AN/AV05274 OF 312
PVCCINFAON_CPU0
P12V_AUXP3V3_AUXP3V3_AUX
PVNN_TERM_CPU0PVCCFA_EHV_CPU0
P3V3_AUX
P3V3_AUX
P3V3_AUX
VCCINFAON/VCCFA_EHV CPU0 VR(1/3)
VSENSE_PVCCINFAON_CPU0_DNPVCCFA_EHV_CPU0_BPWM1PVCCFA_EHV_CPU0_BCSP1
PVCCINFAON_CPU0_VREF
PVCCFA_EHV_CPU0_BTSENPVCCINFAON_CPU0_ADDRPVCCINFAON_CPU0_VR_FAULTPVCCINFAON_CPU0_PIN_ALERTPVCCINFAON_CPU0_CSPIN
PWRGD_PVCCINFAON_CPU0_RSMB_DIO_PVCCINFAON_CPU0PVCCINFAON_CPU0_EN_RNC_PVCCINFAON_CPU0_SMB_ALERTSVID_CLK_PVCCINFAON_CPU0_R
PWRGD_PVCCFA_EHV_CPU0_R
SVID_ALERT_PVCCINFAON_CPU0_RSVID_DIO_PVCCINFAON_CPU0_RSMB_CLK_PVCCINFAON_CPU0
PVCCFA_EHV_CPU0_EN_RNC_PVCCINFAON_CPU0_ACSP6NC_PVCCINFAON_CPU0_APWM6NC_PVCCINFAON_CPU0_ACSP5NC_PVCCINFAON_CPU0_APWM5PVCCINFAON_CPU0_APWM1NC_PVCCINFAON_CPU0_ACSP7PVCCINFAON_CPU0_APWM2NC_PVCCINFAON_CPU0_APWM7NC_PVCCINFAON_CPU0_APWM3NC_PVCCINFAON_CPU0_APWM4NC_PVCCINFAON_CPU0_ACSP4NC_PVCCINFAON_CPU0_ACSP3IRQ_PVCCFA_CPU0_VRHOT_NPVCCINFAON_CPU0_ACSP2PVCCINFAON_CPU0_VCCPVCCINFAON_CPU0_ACSP1ICSMLFISL69260IRAZ-T
0402LF 1/16WCHIP0402LFIRQ_PVCCFA_CPU0_VRHOT_R_N1K1/16W1%214276
274 275 276
27427527621425322216161616241278241278142662221426621425314266
276276275
275275275275EMPTY10%25V0.1UF0402100NF50VEMPTYC040210%
1/16WCHIPEMPTY0402LF6811%PVCCINFAON_CPU0_VREFPWRGD_PVCCFA_EHV_CPU01/16WFM_PVCCFA_EHV_CPU0_ENPVCCINFAON_CPU0_VIN_CSNINVSENSE_PVCCFA_EHV_CPU0_DNVSENSE_PVCCFA_EHV_CPU0_DPVSENSE_PVCCINFAON_CPU0_DPSMB_VR_3V3AUX_SCL_R2SMB_VR_3V3AUX_SDA_R2SVID_CLK0_CPU0_RFM_PVCCINFAON_CPU0_ENSVID_DIO0_CPU0_RPWRGD_PVCCINFAON_CPU0SVID_ALERT0_CPU0_R_NSH_PVCCFA_EHV_CPU0SH_PVCCINFAON_CPU0SH_PVCCFA_EHV_CPU0_RSH_PVCCINFAON_CPU0_R
PVCCINFAON_CPU0_ATSENEMPTY1%28K0402LF5%1/16W0402LFCHIP00402LF5%00402LFCHIP05%1/16W1KCHIP 1/16W0402LF1%CHIP 1/16W0402LF05%0402LF1%1K1K0402LF1/16W1%CHIP5%0402LF01/16WCHIP0.1UF25V10%0402EMPTY0402LF1%EMPTY1/16W1K04021000PF50VEMPTY5%1000PF5%0402X7R50V
EMPTY1/16W0402LF1%49.9EMPTY1/16W0402LF1%100
CHIP0402LF1001%1/16WEMPTYSM1001%CHIP0402LF1/16WCHIP1001%0402LF1/16WSMEMPTYCHIP 1/16W1%1000402LF1/16W0402LFCHIP5%0040250V3300PF10%X7R5%1/16W0402LF0CHIP50V10%X7R04023300PF0402LF1/16W5%0CHIP01/16W0402LF5%CHIP1/16W05%CHIP0402LF1/16WCHIP0402LF05%0402LF1%1501/16WCHIP1/16WCHIP05%0402LF05%0402LFCHIP 1/16W1K1/16W1%CHIP0402LF04025%50V1000PFX7R040250V1000PF5%EMPTY
25V0402X7R10%0.1UF040250V470PFX7R10%0402LF10K1%EMPTY1/16W10%470PFX7R50V04021/16W5%CHIP00402LF05%CHIP0402LF5%CHIP01/16W1/16W0402LF5%0CHIP1/16W0402LF5%0CHIP1/16W0402LF5%0CHIPC040220%X6S6.3V10UF16V10%C0402X6S1UF16V1UFC0402X6S10%0402LF11%1/16WCHIP
10K1%EMPTY1/16W0402LF
PR436
21
2
1
2
1
2
1
PC1372
PR4225
21PC1271
PR435
2
1
21
21
21
21
21
21PR519
21
21PR520
21
2
1
2
1
21R2393
21
21
21
21
21
2
1
R2597
21
21
21
21
21R2392
21
2
1
2
1
21
21
2
1
2
1
21PR521
21PR522
PU5
21
21
21
21
PR130
PC225PC223
PC222
R2595
R2596
PR120
PR121
PJ45
PJ46
C3276
PR123PC214
R2396
R2397
PR107
PR108
PR105
PC224
R2388
R2389
R2391
C3275
R2394
R2398
PC221
R2594
PC215
PC216
C3273
C3274
R2383
PR106
PR4221
R2390
PR4222
PR4223
PR4224
37
38
14
19
11
15
32
21
40
39
TH
36
35
18
17
31
22
8
7
6
5
4
3
2
1
9
10
16
12
20
13
23
24
25
26
27
28
29
30
33
34
R2322
R2386
CS0
PWM0
TEMP0
ADDR_CFG
TH_GND
CFP
CS2
PWM2
CS3
PWM3
PWM7
CS1
RGND1
VSEN1
nPINALERT#||nPSYSCRIT#
TEMP1||ISYS
VINSEN||VSYS
VMON||IINSEN||VSYS||ISYS
VCCS
PWM6
PG0
PWM1
VSEN0
PWM5
PWM4
PMSDA
RGND0
EN0
nPMALERT#
SVCLK
PG1
CS4
CS5
nVRHOT#
nSVALERT#
CS6
SVDATA
PMSCL
EN1
VCC
CS7
SHORT
1 2
SHORT
1 2
2
1
2
1
21
21
21
2
1
21
21
21
21
SHEETDATE
DEPARTMENT
SIZE
PROJECT DOCUMENT NUMBER REV
REVIEWER
DESIGNER
123
7 3 2 1 6 5 4
E
A
B
C
E
D
C
B
A
7 6 5 4
D
OUT
IN
OUT
IN
IN
OUT
IN
OUT
IN
BI
IN
OUT
IN
IN
BI
IN
IN
IN
IN
OUT
OUT
IN
OUT
IN
PC2362
PR4220
C



HCBS4545-1014.5*4.5*4.5ISAT = 13A @ 100CDCR = 0.12M OHMESR=9.5M OHMESR=9.5M OHM
(499OHM) TO ABSORB LEAKAGE FROM SPS.RENESAS RECOMMEND BLEEDER RESISTORAPPLY TO ALL RAILS.
PGL6312.121AHLT6.5*6.5*10.0DCR=0.17M OHMISAT=60A@100CPGL6312.121AHLT6.5*6.5*10.0ISAT=60A@100CDCR=0.17M OHM
PVCCINFAON_CPU0_PHASE1PVCCINFAON_CPU0_PHASE2Fri Aug 25 14:04:46 2023N/AN/AN/AN/AV05275 OF 312PVCCFA_EHV_CPU0_PVCCPVCCFA_EHV_CPU0_PVCCSW_P12V_PVCCINFAON_CPU0_FLTSW_P12V_PVCCINFAON_CPU0_FLTPVCCINFAON_CPU0P12V_AUX
PVCCINFAON_CPU0PVCCINFAON_CPU0SW_P12V_PVCCINFAON_CPU0_FLTPVCCINFAON_CPU0
VCCINFAON CPU0 VR PHASE 1&2 (2/3)274275274274275276274274275274274274275276270UF16VOSCON20%THLF270UF16VOSCON20%THLF2.5VOSCON20%560UFTHLF2.5VOSCON20%560UFTHLF2.5VOSCON20%560UFTHLFPVCCINFAON_CPU0_LSET2PVCCINFAON_CPU0_APWM2PVCCINFAON_CPU0_ATSENPVCCINFAON_CPU0_VREFPVCCINFAON_CPU0_ACSP2PVCCINFAON_CPU0_VDD2PVCCFA_EHV_CPU0_PVCCPVCCINFAON_CPU0_APWM1PVCCINFAON_CPU0_LSET1PVCCFA_EHV_CPU0_PVCCPVCCINFAON_CPU0_VDD1PVCCINFAON_CPU0_ATSENPVCCINFAON_CPU0_ACSP1PVCCINFAON_CPU0_VREFPVCCINFAON_CPU0_VOS2SW_PVCCINFAON_CPU0_BOOT2SW_PVCCINFAON_CPU0_BOOTR2SW_PVCCINFAON_CPU0_BOOT2_RSW_PVCCINFAON_CPU0_SW2
SW_PVCCINFAON_CPU0_BOOT1PVCCINFAON_CPU0_VOS1SW_PVCCINFAON_CPU0_SW1SW_PVCCINFAON_CPU0_BOOTR1SW_PVCCINFAON_CPU0_BOOT1_R
EMPTY0402LF8.87K1%1/16W8.87K1%EMPTY1/16W0402LF04020.1UF10%25VX7RSMLFICISL99390FRZ-TR5935C040210%X6S10V2.2UF2.20402LF1%1/16WCHIPX6SC04022.2UF10%10V10V2.2UF10%X6SC0402X7R04020.1UF25V10%0402LFCHIP2.21/16W1%2.2UFC040210V10%X6S
5%01/16WCHIP0402LF04023300PF10%X7R50V0402LF1%1/16W3.3CHIP16V1UFX6S10%C040216VX6S22UFC080520%22UF16VX6SC080520%100NFC040250V10%X7R120NH/69ASMLFINDX6S4V22UFC080520%C0805X6S4V22UF20%
040210%3300PF50VX7R0402LFCHIP5%01/16W0402LFCHIP1/16W1%3.31UFX6SC040210%16VC080516VX6S22UF20%C080516V22UFX6S20%C040250V100NF10%X7RSMLF120NH/69AINDX7RC040210%50V100NFC080522UFX6S4V20%C0805X6S22UF4V20%10%50VX7R100NFC0402IND100NH/16ASMLF
4990402LF1/16WCHIP1%SMLF2V330UF35%SPCAPSMLF2V330UF35%SPCAPISL99390FRZ-TR5935SMLFIC275276279275276279
2
1 PC1579
PR4226
2
1
2
1
2
1
2
1
21PC1346
2
1
PR1708
2
1
PR1707
2
1
2
1 PC1575
21
2
1
2
1
2
1
2
1 PC1573
2
1 PC1576
2
1 PC1574
2
1
21
PL42
1PC193
2
1
2
1
2
1
21PR1774
21PR1776
2
1
2
1
21
PL52
1PC194
2
1
2
1
2
1
21PR1775
2
1
21PR1777
2
1
21PC1347
PC204_P0_1PC199_P0_1
PC187
PC188
PC208
PL6
PC205_P0_2
PR102
PC207
PC202_P0_1
PC197_P0_1PC195_P0_1PC191_P0_1PC189_P0_1
PC203_P0_2
PC198_P0_2PC196_P0_2PC192_P0_2PC190_P0_2
PR101
PC2946
PC2947
1
30
25_29
3
36
10_19
39
34
4
32
40
7_9-20_24
5
37
38
41
6
35
31
33
2
1
30
25_29
3
36
10_19
39
34
4
32
40
7_9-20_24
5
37
38
41
6
35
31
33
2
PU43_P0_1
PU44_P0_2
PGND2
GL2
GL1
DNC
EN
PGND3
VOS
VIN2
PGND1
SW
LSET
IOUT
TOUT_FLT
PVCC
PHASE
VIN1
BOOT
AGND
VCC
REFIN
PWM
1 2
1 2
1 2
PGND2
GL2
GL1
DNC
EN
PGND3
VOS
VIN2
PGND1
SW
LSET
IOUT
TOUT_FLT
PVCC
PHASE
VIN1
BOOT
AGND
VCC
REFIN
PWM
2
1
2
1
2
1PC1655
2
1
SHEETDATE
DEPARTMENT
SIZE
PROJECT DOCUMENT NUMBER REV
REVIEWER
DESIGNER
123
7 3 2 1 6 5 4
E
A
B
C
E
D
C
B
A
7 6 5 4
D
OUT
IN
OUT
IN
OUT
IN
OUT
IN
C



RENESAS RECOMMEND BLEEDER RESISTOR(499OHM) TO ABSORB LEAKAGE FROM SPS.APPLY TO ALL RAILS.PG1712.301AHLTDCR = 0.17M OHMISAT = 29A @ 125C9.6*6.4*9.0PVCCFA_EHV_CPU0
Fri Aug 25 14:04:47 2023N/AN/AN/AN/AV05276 OF 312
P5VPVCCFA_EHV_CPU0_VDD1P3V3PVCCFA_EHV_CPU0SW_P12V_PVCCINFAON_CPU0_FLT
VCCFA_EHV CPU0 VR PHASE (3/3)
2742752742742742.5VOSCON20%560UFTHLFPVCCFA_EHV_CPU0_LSET1PVCCFA_EHV_CPU0_PVCCPVCCINFAON_CPU0_VREFPVCCFA_EHV_CPU0_NC2PVCCFA_EHV_CPU0_BCSP1PVCCFA_EHV_CPU0_BPWM1PVCCFA_EHV_CPU0_BTSENSW_PVCCFA_EHV_CPU0_BOOTR1PVCCFA_EHV_CPU0_NC1PVCCFA_EHV_CPU0_FAULTSW_PVCCFA_EHV_CPU0_BOOT1 SW_PVCCFA_EHV_CPU0_BOOT1_RPVCCFA_EHV_CPU0_VDD1SW_PVCCFA_EHV_CPU0_SW11/16WEMPTY1%8.87K0402LF1/16W5%00402LFCHIP0.1UF25VX7R040210%10V10%X6SC04022.2UF05%EMPTY1/16W0402LFICRAA2213404GNP#HB0SMLF5%00402LFEMPTY1/16W0402LFCHIP05%1/16W3.31%1/16WCHIP0402LF10%50V100NFC0402X7R1%2.20402LFCHIP1/16W1/16WEMPTY5%00402LFX7R04023300PF50V10% 10%X6S1UFC040216VX6S16VC080522UF20%X6S16VC080522UF20%X7R10%C040250V100NFSMLF300NH/33AIND22UFX6SC08054V20%X6SC080522UF4V20%330UFSMLFSPCAP+10/-35%2.5V0402LFCHIP1%4991/16W275279
PR4227
PR443
2
1
PC178
21PR1779
16_18-284
1
8_12
24
21
19
22
3
25
26
23
6_7-13_15-29
27
5
2
20
PU42
21PC1348
2
1
PR1709
PR4229
2
1 PC1900
2
1
2
1
21PR1778
PR442
2
1 PC2180
21
PL3
2
1
2
1
2
1
2
1
2
1
2
1
2
1
PR4228
PC186
PC179
PC175
PC184PC181
PC180PC177PC176
PR97
1 2
LGCTRL
GL1
NC1
GND3
FAULT#
SW
GL2
GND1
IMON
TMON
VCC
PHASE
VIN
BOOT
GND2
REFIN
PWM
2
1
2
1
21
SHEETDATE
DEPARTMENT
SIZE
PROJECT DOCUMENT NUMBER REV
REVIEWER
DESIGNER
123
7 3 2 1 6 5 4
E
A
B
C
E
D
C
B
A
7 6 5 4
D
OUT
IN
OUT
IN
C



Thu Aug 24 16:16:38 2023N/AN/AN/AN/AV05277 OF 312BLANK
SHEETDATE
DEPARTMENT
SIZE
PROJECT DOCUMENT NUMBER REV
REVIEWER
DESIGNER
123
7 3 2 1 6 5 4
E
A
B
C
E
D
C
B
A
7 6 5 4
D
C



20220808 UPDATE PDG REV 1.6MAX VR OFFSET=5MVDC=+/-0.5% OF VIDRIPPLE=+/-10MVVBOOT=1.1VOCP=35APDG REV.1.6 FOR SPR+HBMPROTOCOL ID=07H (VR13 5MV VID)SVID ADDRESS=00H BUS#1
63H/C6HPVCCD_HV_CPU000HRAIL SVIDSVID / I2C ADDRESSI2C(7BIT/8BIT)
DIFFERENTIAL PAIRTRACE WIDTH = 10MILTRACE SPACING = 5MILSET FW CODE FUNCTION TO BVR_ENCONFIRM ADDRESS SETTING
MAX VOLTAGE VIA BIOS COMMAND=1.145VPVCCD_HV_CPU0 SPECIFICATIONTOTAL TOLERANCE=1.192MAX/1.086VMIN(FUTURE 1.189VMX/1.081VMIN)TDC=23A(EMR 26A)MAX CURRENT=25A(EMR 30A)CURRENT STEP=17A(8A-25A)(EMR 20A(10A-30A)SLEW RATE=8.6A/US(EMR 8A/US)WORK FREQUENCY=700KHZLOAD-LINE=0.80MINI OHM
Fri Aug 25 14:04:48 2023N/AN/AN/AN/AV05278 OF 312
PVCCD_HV_CPU0P3V3_AUXPVNN_TERM_CPU0
P3V3_AUX
P3V3_AUX
P3V3_AUXVCCD_HV CPU0 VR CONTROLLER (1/2)
SH_PVCCD_HV_CPU0_RPVCCD_HV_CPU0_VREF
PVCCD_HV_CPU0_ADDRPVCCD_HV_CPU0_FAULTPVCCD_HV_CPU0_PIN_ALT
PWRGD_PVCCD_HV_CPU0_RSMB_DIO_PVCCD_HV_CPU0PVCCD_HV_CPU0_EN_RNC_PVCCD_HV_CPU0_SMB_ALERTSVID_CLK_PVCCD_HV_CPU0_R
NC_PVCCD_HV_CPU0_BVR_RDY
SVID_ALERT_PVCCD_HV_CPU0_RSVID_DIO_PVCCD_HV_CPU0_RSMB_CLK_PVCCD_HV_CPU0
NC_PVCCD_HV_CPU0_ACSP8NC_PVCCD_HV_CPU0_APWM8NC_PVCCD_HV_CPU0_ACSP6NC_PVCCD_HV_CPU0_APWM6NC_PVCCD_HV_CPU0_ACSP5NC_PVCCD_HV_CPU0_APWM5PVCCD_HV_CPU0_APWM1NC_PVCCD_HV_CPU0_ACSP7PVCCD_HV_CPU0_ISYS_R
NC_PVCCD_HV_CPU0_APWM2NC_PVCCD_HV_CPU0_APWM7NC_PVCCD_HV_CPU0_APWM3NC_PVCCD_HV_CPU0_APWM4NC_PVCCD_HV_CPU0_ACSP4NC_PVCCD_HV_CPU0_ACSP3IRQ_PVCCD_CPU0_VRHOT_LVC3_R_NNC_PVCCD_HV_CPU0_ACSP2PVCCD_HV_CPU0_VCCPVCCD_HV_CPU0_ACSP1ICSMLFISL69260IRAZ-T0402LF278 27914241274279
25125127827916162412741421421914213253279
215279251
CHIPSVID_CLK1_CPU0_R0402C0402SMB_VR_3V3AUX_SDA_R20402EMPTY10%25V0.1UFEMPTYC0402 C0402
1/16WP12V_AUX_CPU0_DIMM_ISEN_PCHIPP12V_AUX_CPU0_DIMM_ISEN_N0402LF1%3.57KEMPTYPVCCD_HV_CPU0_VREF28K1%PVCCD_HV_CPU0_ISENSE_PVSENSE_PVCCD_HV_CPU0_DNVSENSE_PVCCD_HV_CPU0_DPSMB_VR_3V3AUX_SCL_R2SVID_DIO1_CPU0_RFM_PVCCD_HV_CPU0_ENSVID_ALERT1_CPU0_R_NPWRGD_PVCCD_HV_CPU0SH_PVCCD_HV_CPU0
PVCCD_HV_CPU0_ISENSE_NIRQ_PVCCD_CPU0_VRHOT_LVC3_NPVCCD_HV_CPU0_ATSENPVCCD_HV_CPU0_NVDIMM_ISENSE0402LF1/16W1/16WEMPTY1%1K0402LF10%X7R0.1UF25V04020402LF 1/16WCHIP49.91%49.9CHIP1%1/16WCHIP1%1K0402LFCHIP1K0402LF1/16W1%
10UF6.3VX6S20%X7R10%25V0.1UF1001%CHIP1%1/16W49.90402LFCHIP0402LFCHIP1001/16W1%100CHIP1%1/16WSMEMPTY5%00402LF1/16WCHIPX7R10%50V3300PF04025%01/16W0402LFCHIPCHIP1/16W05%0402LF5%0402LF0CHIP1/16WCHIP00402LF1/16W5%1%1500402LF1/16W01/16W5%CHIP0402LF1/16W0CHIP0402LF5%CHIP1%1K1/16W0402LF EMPTY50V1000PF04025%
1%1/16WEMPTY1K0402LF25VX7R10%0.1UF040216VX6S10%1UFC0402X7R10%470PF50V04021/16W0402LFEMPTY10K1%CHIP05%1/16W0402LFCHIP5%00402LF 1/16W0CHIP5%1/16W0402LFCHIP5%1/16W00402LF5%00402LFEMPTY1/16WCHIP00402LF5%1/16WCHIP05%0402LF1/16W1/16W05%CHIP0402LF1/16W05%0402LFCHIPX6SC040220%10UF6.3V1UF16V10%X6SC0402100NF10%50V10%1UF16VX6S0402LF1/16WCHIP05%0402LF 1/16WCHIP1%1
1K0402LF1%CHIP1/16W
1
R1717
21
2
1
2
1
PC1196
2
1
2
1
PC813
21
21
2
1
21
R17352
1
2
1
2
1
21PR1380
21PR1390
2
1
2
1
21
2
1
PR4232
PR409
21
21
21PR592
21PR1311
PR634
21
21
21PR591
21
2
1
PU35
2
1
21
2
1
R2405
2
1
21
21
21
PR375
PC632
PC630
PC631
R362
R2399
PC627
PR371
PR370
PC624PR369
PR357
R2404
R2400
R2401
R2402
PJ54
PR372
PC628
C626
PC629
PR373
R361
R363
R2403
PR358
PR4230
PR4231
PR4233
PR4234
PR4236
37
38
14
19
11
15
32
21
40
39
TH
36
35
18
17
31
22
8
7
6
5
4
3
2
1
9
10
16
12
20
13
23
24
25
26
27
28
29
30
33
34
C2444C2443
CS0
PWM0
TEMP0
ADDR_CFG
TH_GND
CFP
CS2
PWM2
CS3
PWM3
PWM7
CS1
RGND1
VSEN1
nPINALERT#||nPSYSCRIT#
TEMP1||ISYS
VINSEN||VSYS
VMON||IINSEN||VSYS||ISYS
VCCS
PWM6
PG0
PWM1
VSEN0
PWM5
PWM4
PMSDA
RGND0
EN0
nPMALERT#
SVCLK
PG1
CS4
CS5
nVRHOT#
nSVALERT#
CS6
SVDATA
PMSCL
EN1
VCC
CS7
SHORT
1 2
2
1
21
21
21
21
21
21
21
2PR4235
21
21
SHEETDATE
DEPARTMENT
SIZE
PROJECT DOCUMENT NUMBER REV
REVIEWER
DESIGNER
123
7 3 2 1 6 5 4
E
A
B
C
E
D
C
B
A
7 6 5 4
D
OUT
IN
IN
OUT
IN
OUT
IN
IN
OUT
IN
BI
OUT
IN
BI
IN
IN
IN
OUT
IN
PC2365
C



RENESAS RECOMMEND BLEEDER RESISTOR(499OHM) TO ABSORB LEAKAGE FROM SPS.RESERVE BY ARCHER CITYISAT=60A@100CDCR=0.17M OHM6.5*6.5*10.0PGL6312.121AHLTAPPLY TO ALL RAILS.PVCCD_HV_CPU0_PHASE1
Fri Aug 25 14:04:50 2023N/AN/AN/AN/AV05279 OF 312
PVCCFA_EHV_CPU0_PVCCSW_P12V_PVCCINFAON_CPU0_FLTPVCCD_HV_CPU0PVCCD_HV_CPU0
VCCD_HV_CPU0 VR PHASE (2/2)
2782782782782.5VOSCON20%560UFTHLF2.5VOSCON20%560UFTHLFPVCCD_HV_CPU0_LSET1PVCCD_HV_CPU0_VREFPVCCD_HV_CPU0_ATSENPVCCD_HV_CPU0_APWM1PVCCFA_EHV_CPU0_PVCCPVCCD_HV_CPU0_VDD1PVCCD_HV_CPU0_ACSP1PVCCD_HV_CPU0_VOSSW_PVCCD_HV_CPU0_BOOT1 SW_PVCCD_HV_CPU0_BOOT1_RSW_PVCCD_HV_CPU0_BOOTR1SW_PVCCD_HV_CPU0_SW18.87K0402LFEMPTY1/16W1%X7R 10%0.1UF25V0402ICISL99390FRZ-TR5935SMLF2.2UF10%10VX6SC0402CHIP0402LF2.21%1/16W10%X6S10V2.2UFC040205%0402LF1/16WCHIP3300PFX7R040250V10%3.31%0402LF1/16WCHIP10%1UF16VC0402X6S X6S22UF16VC080520%10%50VC0402X7R100NF16V22UFC0805X6S20%X7RC0402100NF50V10%4V22UFX6SC080520%SPCAP35%330UF2VSMLFX6SC080522UF4V20%X6S22UFC08054V20%SMLFIND120NH/69A1/16W0402LFCHIP1%499275276
21
PL35
21PC1354
PC1644
2
1
2
1
PR4237
PC1645
2
1
2
1
2
1 PC1910
2
1
2
1
2
1PC636
2
1
2
1
21PR1784
2
1
21PR1785
2
1
2
1
PR2718
PC639
PR380
PC1PC642PC641
PC638PC637PC635PC634
PC633
PC2948
1
30
25_29
3
36
10_19
39
34
4
32
40
7_9-20_24
5
37
38
41
6
35
31
33
2
PU36
PGND2
GL2
GL1
DNC
EN
PGND3
VOS
VIN2
PGND1
SW
LSET
IOUT
TOUT_FLT
PVCC
PHASE
VIN1
BOOT
AGND
VCC
REFIN
PWM
1 2
2
1
2
1
SHEETDATE
DEPARTMENT
SIZE
PROJECT DOCUMENT NUMBER REV
REVIEWER
DESIGNER
123
7 3 2 1 6 5 4
E
A
B
C
E
D
C
B
A
7 6 5 4
D
OUT
IN
OUT
IN
C



Thu Aug 24 16:16:42 2023N/AN/AN/AN/AV05280 OF 312BLANK
SHEETDATE
DEPARTMENT
SIZE
PROJECT DOCUMENT NUMBER REV
REVIEWER
DESIGNER
123
7 3 2 1 6 5 4
E
A
B
C
E
D
C
B
A
7 6 5 4
D
C



IC TABLE1ST AL0533180022ND AL0005480063RD AL00863300720220804 CHANGE IC TABLEPC2643 MAIN 1UF20220808 ADD CHANGE LIST3RD 1UF2ND 2.2UF
PVPP_HBM_CPU0RB6.5*6.9*3.0PCMC063T-R68MNISAT=23A@100CDCR=5.5M OHMVOUT=((RA/RB)+1)*0.6=2.634V20220808 ADD CHANGE LISTPC1253 MAIN 680PF3RD 100PF2ND 270PFRA
MAX CURRENT=5ATDC=4APDG REV 1.6RIPPLE=+/-7MVVOUT=2.5VDC=+/-0.7%20220808 UPDATE PDG REV 1.6PVPP_HBM_CPU0 SPECIFICATIONWORK FREQUENCY=800KHZOCP(IMAX*130%)=8ACURRENT STEP=4.6ATOTAL TOL=2.708VMAX/ 2.530VMINSLEW RATE=1.6A/US
REMOTE SENSEPLACE AT CHIPSET SIDE20220804 CHANGE PC1253 TO 680PF FOR TRANSIENT RESPONSEFri Aug 25 14:04:51 2023N/AN/AN/AN/AV05281 OF 312I31P3V3_AUXP3V3_AUXSW_P12V_PVCCIN_CPU0_FLTP3V3_AUXPVPP_HBM_CPU0
PVPP_HBM_CPU01%213 253215 299214PVPP_HBM_CPU0_VCCPVPP_HBM_CPU0_MODEPVPP_HBM_CPU0_CSPVPP_HBM_CPU0_REFSW_PVPP_HBM_CPU0_SWPVPP_HBM_CPU0_FBPWRGD_PVPP_HBM_CPU0_RSW_PVPP_HBM_CPU0_BSTPWRGD_PVPP_HBM_CPU0FM_HBM2_HBM3_VPP_SELSH_PVPP_HBM_CPU0_NFM_HBM_VPP_SEL_CPU0_DSH_PVPP_HBM_CPU0_PFM_PVPP_HBM_CPU0_EN25V1UF10%X6SC0402CHIP1/16W05%0402LFC0805X6S20%22UF16VEMPTY1/16W0402LF1%10KC080520%22UF16VX6SEMPTY1000PF5%50V0402 0402LFCHIP1%2K1/16W1%1/16W0402LFCHIP9.76KX6S20%22UF16VC080510%X6SC04021UF16V30.1KCHIP1/16W0402LFSMLFRS53318LRIC16V04020.022UF10%X7R10%0402X7R25V0.1UF0.1%1/16WCHIP0402LF11.3KC04020.22UF10%X7R25V0.68UHINDSMLF5%0402LF1/16WCHIP05%1000PFX7R50V0402BSS138KEMPTYSMEMPTYEMPTY26.1K 0.1%0402LF 1/16WC0402X7R 50V10%680PF0402LFCHIP1/16W38.3K 0.1%0402X7R25V10%0.1UFX7R040210%25V0.01UFEMPTYSMX6S22UF4V20%C0805X6S4VC080522UF20%4V22UF20%X6SC08050402LFCHIP1%1/16W10K6.3V20%560UFTHLFOSCON
PR1337
PR1310
PR2336
PC1257
PJ64
PC1421
21
2
1 PC1251
2
1
2
1 PC1247
2
1
PR1335
PC1256
21PC1253
G
2
1 PC831
2
1
R2407
PJ65
2
1
PR1336
21PL118
21
21
2
1 PC2643
PC1255
2
1 PC1254
21
2
1 PC1252
2
1 PC1249
2
1 PC1248
2
1
S D
PC1258
PR3335
21
10
19
20
6
5
9
11_18
4
7
8
3
1
2
R2408
PU79
R2332
PU173
C1301
R2406
C1300
SHORT
1 2
SHORT
1 2
1 2
VIN2
CS
MODE
REF
SW
RTN
VCC
AGND
FB
BST
EN
PGND
PGOODVIN1
2
1
21
2
1
21
21
21
SHEETDATE
DEPARTMENT
SIZE
PROJECT DOCUMENT NUMBER REV
REVIEWER
DESIGNER
123
7 3 2 1 6 5 4
E
A
B
C
E
D
C
B
A
7 6 5 4
D
OUT
IN
IN
PC2001
C



ISAT=9A@100C6.5*6.9*3.0PCMC063T-4R7MNPVNN_MAIN_CPU0PVNN_MAIN_CPU0 SPECIFICATION
UPDATE 20220531 ADD LOCAL SENSE20220808 UPDATE PDG REV 1.6REMOTE SENSE
TOTAL TOL=1.03VMAX/0.97VMINPDG REV 1.6WORK FREQUENCY=600KHZSLEW RATE=0.4A/USCURRENT STEP=0.52AOCP(IMAX*130%)=1ADC TOLERANCE=+/-0.7%RIPPLE=+/-7MVMAX CURRENT=0.52AVOUT=1VTDC=0.52ADCR=40M OHMPLACE AT CHIPSET SIDE2ND 470PF3RD 680PFPC237 MAIN 680PF20220808 ADD CHANGE LIST20220804 CHANGE IC TABLE2ND AL54L0610003RD AL008626000IC TABLE1ST AL053317005Fri Aug 25 14:04:52 2023N/AN/AN/AN/AV05282 OF 312
P3V3_AUXP3V3_AUXSW_P12V_PVCCINFAON_CPU0_FLTP3V3_AUXPVNN_MAIN_CPU0PVNN_MAIN_CPU0
PVNN_MAIN_CPU01/16W04020402LFCHIP05%040250V0.1%8.25K1/16W1/16WCHIP213132253214PVNN_MAIN_CPU0_VCCPVNN_MAIN_CPU0_MODEPVNN_MAIN_CPU0_CSPWRGD_PVNN_MAIN_CPU0_RPVNN_MAIN_CPU0_REFSW_PVNN_MAIN_CPU0_SWSW_PVNN_MAIN_CPU0_BST SW_PVNN_MAIN_CPU0_BST_RPVNN_MAIN_CPU0_FBPWRGD_PVNN_MAIN_CPU0PVNN_MAIN_CPU0_FB_RCFM_PVNN_MAIN_CPU0_ENEMPTY5%50V04021000PF10K0402LF1%EMPTY1/16WX6S1UF25V10%C0402CHIP1/16W1%0402LF60.4K1/16WCHIP05%0402LF2K1%1/16WCHIP0402LFC080516V22UFX6S20%C080520%22UF16VX6S22.6K1%1/16WCHIP0402LFICSMLFRS53317LRC040210%16V1UFX6S50V3300PFX7R10%X7R10%25VC04020.22UF5%0CHIP0402LF0.1%12.4K0402LFINDSMLF4.7UH1000PFX7R50V5%10K0402LFCHIP1%1/16W0CHIP5%10% X7R040250V680PFCHIP 0402LFC0402X7R100NF10%X6S22UF4V20%C080525V04020.01UFX7R10%EMPTY0402LF5%005%CHIP0402LF22UF4VC0805X6S20%C0805X6S20%4V22UF 22UF4V20%X6SC0805
2
1 PC1206
2
1 PC1277
2
1 PC1276
21PL120
2
1
PR1303
2
1 PC1272
PR1301
2
1 PC2221
21
2
1 PC1279
2
1
R2409
2
1
2
1
2
1 PC1273
PR3339
2
1
PC1420
21
2
1 PC1278
PC237
2
1
2
1
21 PR501
PC1275
PC1274
PR4683
PR4271
PR4698
PR1
3
13
11
2
8
9
14
1
12
6
5
4
10
7
PU81
R2338
C1307
R1652
R1445
C1296
1 2SW1
CS
MODE
REF
SW2
PGND1
VCC
AGND
FB
BST
EN
PGND2
PGOODVIN
PR50
2
1
21
2
1PC27
21
21
2
1
21
SHEETDATE
DEPARTMENT
SIZE
PROJECT DOCUMENT NUMBER REV
REVIEWER
DESIGNER
123
7 3 2 1 6 5 4
E
A
B
C
E
D
C
B
A
7 6 5 4
D
OUT
IN
C



THIS PAGE WAS INTENTIONALLY LEFT BLANK
Thu Aug 24 16:16:45 2023N/AN/AN/AN/AV05283 OF 312BLANK
SHEETDATE
DEPARTMENT
SIZE
PROJECT DOCUMENT NUMBER REV
REVIEWER
DESIGNER
123
7 3 2 1 6 5 4
E
A
B
C
E
D
C
B
A
7 6 5 4
D
C



20220725 CONNECT TO CPLDTRACE SPACING = 5MIL20211013 MODIFY FOR GTDIFFERENTIAL PAIRTRACE WIDTH = 10MILCONFIRM ADDRESS SETTINGI2C(7BIT/8BIT)SVID72H/E4H00HDIFFERENTIAL PAIRTRACE WIDTH = 10MILTRACE SPACING = 5MILSVID / I2C ADDRESSRAILPVCCIN_CPU1
DC=+/-0.5% OF VIDMAX CURRENT=136ALOAD-LINE=0.7 MOHMWORK FREQUENCY=700KHZSVID ADDRESS=03H BUS#0OCP=164ATDC=102ARIPPLE=+/-9MVVID=1.6V~1.88V(TYP=1.8V)PDG REV.1.6 FOR SPR+HBMOCP=500A20220808 UPDATE PDG REV 1.6SETVID RATE=10MV/US (FAST)PROTOCOL ID=04H (VR13 10MV VID)WORK FREQUENCY=700KHZSVID ADDRESS=00H BUS#0PROTOCOL ID=0AH (VR14 10MV VID)SETVID RATE=25MV/US (FAST)PDG REV 1.6 FOR 350W SPR+HBMICCIN_MAX.APP=430ATDC=220ATOTAL TOLERANCE BAND=+/-22MVDC=+/-0.5%RIPPLE=+/-10MVVID=1.6V~1.88V(TYP=1.8 OR1.83V)VBOOT=1.8VPVCCIN_CPU1 SPECIFICATIONPVCCFA_EHV_FIVRA_CPU0 SPECIFICATIONVBOOT=1.8VTRANSIENT OCP=600ACURRENT STEP=370A(OVERSHOOT)442A(UNDERSHOOT)SLEW RATE=960A/US(OVERSHOOT)1081A(UNDERSHOOT)LOAD-LINE=0.5 MOHM
Fri Aug 25 14:04:54 2023N/AN/AN/AN/AV05284 OF 312P12V_AUXP3V3_AUXP3V3_AUXP3V3_AUXPVCCFA_EHV_FIVRA_CPU1PVCCIN_CPU1P3V3_AUX
PVNN_TERM_CPU1
P3V3_AUX
VCCIN/VCCFA_EHV_FIVRA CPU1 VR(1/7)
4721447 284 285 286 287 288289 290285285286
2842852862872882892904722221425447452922842142542224528429245292284241266241266
285 286 287 288290289288288288289289289290290290289 290452842924528429245284292287287287288285285287286286286EMPTYVSENSE_PVCCIN_CPU1_DP1/16WIRQ_PVCCIN_CPU1_VRHOT_R_N0402LF1%1%0402LFPVCCIN_CPU1_VR_FAULTCHIP1/16W0402LF0402LF1/16WVSENSE_PVCCFA_EHV_FIVRA_CPU1_DN100CHIPIRQ_PVCCIN_CPU1_VRHOT_N5%PVCCIN_CPU1_PIN_ALERTPVCCFA_EHV_FIVRA_CPU1_EN_R0402LF
PVCCIN_CPU1_VCC0.1UF25V10%EMPTY0402PVCCIN_CPU1_VREFPVCCIN_CPU1_PWM2PVCCIN_CPU1_IMON2PVCCIN_CPU1_PWM3
PVCCIN_CPU1_VREFVSENSE_PVCCFA_EHV_FIVRA_CPU1_DPFM_PVCCFA_EHV_FIVRA_CPU1_ENPWRGD_PVCCFA_EHV_FIVRA_CPU1PVCCIN_CPU1_VIN_CSNINPVCCIN_CPU1_ADDRSH_PVCCFA_EHV_FIVRA_CPU1PVCCIN_CPU1_CSPINPWRGD_PVCCFA_EHV_FIVRA_CPU1_RSH_PVCCFA_EHV_FIVRA_CPU1_RVSENSE_PVCCIN_CPU1_DNSVID_ALERT0_CPU1_R_NPWRGD_PVCCIN_CPU1FM_PVCCIN_CPU1_ENSVID_CLK0_CPU1_RSVID_DIO0_CPU1_RSVID_CLK_PVCCIN_CPU1_RSVID_DIO_PVCCIN_CPU1_RSVID_ALERT_PVCCIN_CPU1_RSMB_VR_3V3AUX_SDA_R3SMB_VR_3V3AUX_SCL_R3SH_PVCCIN_CPU1SMB_CLK_PVCCIN_CPU1NC_PVCCIN_CPU1_SMB_ALERTSMB_DIO_PVCCIN_CPU1SH_PVCCIN_CPU1_RPVCCIN_CPU1_EN_RPWRGD_PVCCIN_CPU1_R
PVCCIN_CPU1_ATSENPVCCFA_EHV_FIVRA_CPU1_PWM4PVCCFA_EHV_FIVRA_CPU1_PWM1PVCCIN_CPU1_PWM8PVCCIN_CPU1_IMON8PVCCIN_CPU1_IMON7PVCCFA_EHV_FIVRA_CPU1_IMON1PVCCFA_EHV_FIVRA_CPU1_IMON2PVCCFA_EHV_FIVRA_CPU1_PWM2PVCCFA_EHV_FIVRA_CPU1_PWM3PVCCFA_EHV_FIVRA_CPU1_IMON4PVCCFA_EHV_FIVRA_CPU1_IMON3PVCCFA_EHV_FIVRA_CPU1_BTSENSVID_DIO0_CPU1_RSVID_CLK0_CPU1_RSVID_ALERT0_CPU1_R_NPVCCIN_CPU1_PWM6PVCCIN_CPU1_IMON5PVCCIN_CPU1_PWM5PVCCIN_CPU1_PWM7PVCCIN_CPU1_PWM1PVCCIN_CPU1_IMON1PVCCIN_CPU1_IMON6PVCCIN_CPU1_PWM4PVCCIN_CPU1_IMON3PVCCIN_CPU1_IMON4
0402LF1/16W28KEMPTY1%1/16W1%CHIP5.23K0402LF0402LFCHIP 1/16W5%005%EMPTY0402LF1%CHIP1K0402LF1%CHIP 1/16W01/16W5%0402LFCHIP1K1K1/16W05%0402LFCHIPSMEMPTY0402LF1/16W1001%CHIP1%1K00402LF5%CHIP1/16W25V0.1UF10%EMPTY04020402LF1K1%EMPTY1/16W040225V0.1UFX7R10%
SMLFICRAA229126GNP#HA0
5%X7R50V04021000PFEMPTY5%04021000PF50V00402LF05%CHIP1/16W3300PF10%0402X7R50V0402LF1/16W1%CHIP100SM0402LF1/16W1%100CHIP0CHIP5%1/16W0402LF5%0402LF0CHIP 1/16W1501%0402LFCHIP 1/16W1/16W5%0402LF0CHIP1/16W0402LF05%CHIPCHIP0402LF1%1K1/16W05%0402LFCHIP 1/16W50V3300PF040210%X7R0402LF5%01/16WCHIP05%CHIP 1/16W0402LF04021000PF50V X7R5%5%04021000PF50VEMPTY
X7R040250V470PF10%EMPTY10K1%0402LF1/16WEMPTY5%0EMPTY5%0X7R10%50V0402470PF0402LF1%10K1/16WEMPTY1/16W1001%CHIP0402LF1%49.9 CHIP49.9 EMPTY1%C06034V10UF20%EMPTY100NF50VC0402X7R10%10UFC0402X6S20%6.3VC0402EMPTY10%50V100NF16V10%1UFC0402X6SC040210%1UF16VX6SCHIP0402LF 1/16W11%
2
1
2
1
2
1
21
21
21
21PR574
21
40
25
45
46
48
47
TH
44
43
22
21
39
26
12
11
10
9
8
7
6
5
4
3
2
1
13
14
20
16
18
23
15
19
24
17
27
28
29
30
31
32
33
34
35
36
37
38
41
42
PU29
2
1
21PR561
21
21
2
1
21
2
1
2
1
21R2554
2
1
21
21PR578
2
1
21
21
21
2
1
21R2555
21
21
21
2
1
2
1
2
1
21PR560
2
1
PC1194
PR637
21
21
21
21
R2523
R2522
21
21
21
21
21R2525
21R2524
PC553
C2448
PC101
PC554
R312
R311
PJ52
PR242
PR305
R2551
PR304
PR318
PR323
PC555
C2449
PC549
R310
PC422
PJ49
R2552
PR303
PC552
R2520
R309
C2447
C2446
PC548PR313PC547
C2859
R2521
R307
R308
PR306
C2860
PR317
R2550
R2553
PR453
PR4239
PR4238
SHORT
1 2
CS10
PWM10
CS9
PWM9
CS8
PWM8
CS7
PWM7
CS0
PWM0
TEMP0
ADDR_CFG
TH_GND
CFP
CS2
PWM2
CS3
PWM3
PWM11
CS1
RGND1
VSEN1
nPINALERT||nPSYS_CRIT
TEMP1||ISYS
VINSEN||VSYS
VMON||IINSEN||VSYS||ISYS
VCCS
PWM6
PG0
PWM1
VSEN0
PWM5
PWM4
PMSDA
RGND0
EN0
nPMALERT
SVCLK
PG1
CS4
CS5
nVRHOT
nSVALERT
CS6
SVDATA
PMSCL
EN1
VCC
CS11
SHORT
1 2
2
1
21
2
1
2
1
21
21
21
21
SHEETDATE
DEPARTMENT
SIZE
PROJECT DOCUMENT NUMBER REV
REVIEWER
DESIGNER
123
7 3 2 1 6 5 4
E
A
B
C
E
D
C
B
A
7 6 5 4
D
IN
IN
IN
IN
IN
IN
OUT
IN
OUT
IN
OUT
IN
OUT
IN
OUT
IN
OUT
IN
IN
OUT
BI
IN
BI
IN
IN
IN
OUT
IN
OUT
OUT
IN
OUT
IN
OUT
IN
OUT
IN
OUT
IN
IN
OUT
IN
OUT
OUT
IN
PC2366
C



ISAT = 120A @ 100CPGL6189.500HLT10.0*8.3*8.0DCR = 0.04M OHMESR=9.5M OHMESR=9.5M OHMESR=9.5M OHMRESERVE BY ARCHER CITYESR=9.5M OHMISAT=70A@100CDCR=2-3,0.27M OHMDCR=1-4,0.105M OHM11.0*7.5*12.5PGL6303.151HLT
(499OHM) TO ABSORB LEAKAGE FROM SPS.RENESAS RECOMMEND BLEEDER RESISTORAPPLY TO ALL RAILS.DCR=1-4,0.105M OHMISAT=70A@100C11.0*7.5*12.5DCR=2-3,0.27M OHMPGL6303.151HLT
PVCCIN_CPU1_PHASE1PVCCIN_CPU1_PHASE2Fri Aug 25 14:04:55 2023N/AN/AN/AN/AV05285 OF 312PVCCIN_CPU1_PVCC
P5VP3V3
SW_P12V_PVCCIN_CPU1_FLTPVCCIN_CPU1PVCCIN_CPU1
SW_P12V_PVCCIN_CPU1_FLTP12V_AUXPVCCIN_CPU1PVCCIN_CPU1SW_P12V_PVCCIN_CPU1_FLT
VCCIN CPU1 VR PHASE 1&2 (2/7)2852862872882842842842852862872882892902842862842852862872882892902842852862872882842842852852872.5VOSCON20%560UFTHLF2.5VOSCON20%560UFTHLF2.5VOSCON20%560UFTHLFEMPTYSMLF2.5V+10/-35%330UF+10/-35%SMLF2.5VEMPTY330UFTHLFOSCON16V20%270UF270UFTHLFOSCON20%16V
SMLF330UF+10/-35%2.5VEMPTY2.5VOSCON20%560UFTHLF270UFOSCONTHLF20%16VTHLFOSCON16V20%270UF
+10/-35%330UFEMPTYSMLF2.5V2.5VOSCON20%560UFTHLFTHLF20%270UF16VOSCON
PVCCIN_CPU1_ATSENPVCCIN_CPU1_PWM2PVCCIN_CPU1_LSET2PVCCIN_CPU1_VREFPVCCIN_CPU1_VDD2PVCCIN_CPU1_IMON2IND_P1_CPL2SW_PVCCIN_CPU1_BOOT2SW_PVCCIN_CPU1_BOOTR2SW_PVCCIN_CPU1_SW2SW_PVCCIN_CPU1_BOOT2_RPVCCIN_CPU1_VREFPVCCIN_CPU1_LSET1PVCCIN_CPU1_VDD1PVCCIN_CPU1_IMON1PVCCIN_CPU1_ATSENPVCCIN_CPU1_PWM1PVCCIN_CPU1_PVCCSW_PVCCIN_CPU1_BOOT1SW_PVCCIN_CPU1_BOOTR1PVCCIN_CPU1_VOS1SW_PVCCIN_CPU1_BOOT1_RSW_PVCCIN_CPU1_SW1IND_P1_CPL1
PVCCIN_CPU1_VOS2IND_P1_CPL1IND_P1_CPL6
1/16WEMPTY1%8.87K0402LF040225V0.1UFX7R10%ISL99390FRZ-TR5935SMLFICX6S10%2.2UF10VC04022.21/16WCHIP1%0402LF10VX6S10%2.2UFC0402150NHSMLFINDX7R10%3300PF50V04021%1/16W3.30402LFCHIPC0402X6S10%1UF16VX6S22UF16VC080520%100NF10%50VX7RC040222UF16VC0805X6S20%
1/16WCHIP5%00402LF1/16WEMPTY1%8.87K0402LF040225V0.1UFX7R 10%10%X6S2.2UF10VC04021/16WCHIP1%2.20402LFX6S10%2.2UF10VC0402SMLFICISL99390FRZ-TR59351/16WEMPTY5%00402LFX7R10%3300PF50V04023.30402LF 1/16WCHIP1%10%X6S1UF16VC0402X6S22UF16VC080520%X7R10%100NF50VC0402X6S22UF16VC080520%
1/16WCHIP5%00402LFX6S22UF16VC080520%C0805X6S22UF4V20%X6S4VC080522UF20%1%4991/16WCHIP0402LF1/16W05%0402LFCHIP150NHINDSMLF22UF16VC0805X6S20%100NF50VX7RC040210%0.1%0.031WEMPTY2512LFIND50NH/148ASMLFC0402X7R10%100NF50VX6SC040216V1UF10%C0805X6S22UF20%4VC08054V22UFX6S20%
PR2556
2
1
2
1
2
1
2
1
2
1
2
1
2
1
21PR329
2
1
PR640
2
1
21PC1339
PR639
4
32
1
PL30
2
1
1
30
25_29
3
36
10_19
39
34
4
32
40
7_9-20_24
5
37
38
41
6
35
31
33
2
PU30_P1_2
2
1
2
1
2
1
21PR330
2
1
PC189
2
1 PC83
1
30
25_29
3
36
10_19
39
34
4
32
40
7_9-20_24
5
37
38
41
6
35
31
33
2
PU31_P1_12
1
2
1
2
1
21PR1766
2
1
2
1
2
1
2
1
2
1
PR4240
2
1
2
1
2
1
2
1PC565
2
1
2
1
2
1
2
12
1
21PC1338
2
1
2
1
21PL32
4
32
1
PL31
2
1
2
1
2
1
PC1990
21PR1767
2
1
2
1
PC588PC585PC579
PC571_P1_1
PC590
PC583
PC570_P1_2
PC561_P1_1
PC557
PR327
PC578_P1_1PC576_P1_1
PC582
PC559_P1_1PR328
PC562_P1_2PC560_P1_2
PC558_P1_2
PC574_P1_1
PC589PC580
PC577_P1_2PC575_P1_2
PC569_P1_1PC567_P1_1PC563_P1_1
PC568_P1_2
PC564
PC556
PR325
PC572_P1_1
PC586
PC587
PR326
PC566_P1_2
PC2346
1 2
1 4
32
PGND2
GL2
GL1
DNC
EN
PGND3
VOS
VIN2
PGND1
SW
LSET
IOUT
TOUT_FLT
PVCC
PHASE
VIN1
BOOT
AGND
VCC
REFIN
PWM
PGND2
GL2
GL1
DNC
EN
PGND3
VOS
VIN2
PGND1
SW
LSET
IOUT
TOUT_FLT
PVCC
PHASE
VIN1
BOOT
AGND
VCC
REFIN
PWM
1 4
32
2
121
2
1
2
1PC1656
SHEETDATE
DEPARTMENT
SIZE
PROJECT DOCUMENT NUMBER REV
REVIEWER
DESIGNER
123
7 3 2 1 6 5 4
E
A
B
C
E
D
C
B
A
7 6 5 4
D
IN
OUT
BI
BI
IN
BI
OUT
OUT
IN
OUT
IN
BI
C



PGL6303.151HLT11.0*7.5*12.5ISAT=70A@100CDCR=1-4,0.105M OHMDCR=2-3,0.27M OHMPGL6303.151HLT11.0*7.5*12.5ISAT=70A@100CDCR=1-4,0.105M OHMDCR=2-3,0.27M OHM
PVCCIN_CPU1_PHASE3PVCCIN_CPU1_PHASE4Fri Aug 25 14:04:56 2023N/AN/AN/AN/AV05286 OF 312
PVCCIN_CPU1_PVCCPVCCIN_CPU1_PVCCSW_P12V_PVCCIN_CPU1_FLTSW_P12V_PVCCIN_CPU1_FLT
PVCCIN_CPU1PVCCIN_CPU1
VCCIN CPU1 VR PHASE 3&4 (3/7)284285286287288289290284285286287288284284284285286287288284284
287 286286 285284285286287288289290PVCCIN_CPU1_LSET4PVCCIN_CPU1_VREFPVCCIN_CPU1_PWM4PVCCIN_CPU1_ATSENPVCCIN_CPU1_IMON4PVCCIN_CPU1_PWM3PVCCIN_CPU1_ATSENPVCCIN_CPU1_VDD4PVCCIN_CPU1_LSET3PVCCIN_CPU1_IMON3PVCCIN_CPU1_VDD3SW_PVCCIN_CPU1_BOOT4 SW_PVCCIN_CPU1_BOOT4_RPVCCIN_CPU1_VOS3PVCCIN_CPU1_VOS4SW_PVCCIN_CPU1_BOOTR4IND_P1_CPL4SW_PVCCIN_CPU1_SW4IND_P1_CPL3
SW_PVCCIN_CPU1_BOOT3 SW_PVCCIN_CPU1_BOOT3_RIND_P1_CPL3SW_PVCCIN_CPU1_BOOTR3SW_PVCCIN_CPU1_SW3IND_P1_CPL2PVCCIN_CPU1_VREF
1/16WEMPTY1%8.87K0402LFX7R 10%0.1UF25V0402SMLFICISL99390FRZ-TR5935X6S10%2.2UF10VC04021/16WCHIP1%2.20402LFEMPTY1%8.87K0402LF1/16WX6S10%2.2UF10VC0402X6S10%2.2UF10VC0402CHIP1%2.20402LF1/16WX7R 10%0.1UF25V0402X6S10%2.2UFC040210V
0402X7R10%3300PF50V1/16WCHIP1%3.30402LFX6S10%1UF16VC0402X6S20%22UF16VC0805150NHINDSMLF1/16WCHIP5%00402LFX7R10%100NF50VC0402X6S20%22UF16VC0805X6S20%22UF16VC08051/16W5%0CHIP0402LFCHIP1%3.30402LF1/16WX7R10%3300PF50V0402X6S1UFC040210%16V20%22UFC080516VX6SSMLF150NHINDX7R10%100NF50VC0402X6S20%22UF16VC0805X6S20%22UF16VC0805
4V22UF20%X6SC08054V22UF20%X6SC08054V22UFX6S20%C08054V22UF20%X6SC0805SMLFICISL99390FRZ-TR5935
1
30
25_29
3
36
10_19
39
34
4
32
40
7_9-20_24
5
37
38
41
6
35
31
33
2
PU28_P1_3
2
1
2
1
2
1
2
1
2
1
4
32
1
PL29
2
1
21PR302
2
1PC531
21PR301
4
32
1
PL28
2
1
2
1
2
1
2
1
2
1
2
1
1
30
25_29
3
36
10_19
39
34
4
32
40
7_9-20_24
5
37
38
41
6
35
31
33
2
PU27_P1_4
21PC1358
2
1
2
1
2
1PC532
2
1
2
1
21PR1789
2
1
2
1
2
1
2
1
21PR1788
21PC1359
2
1
2
1
PC544_P1_3PC542_P1_3
PC543_P1_4PC541_P1_4
PC538_P1_3PC534_P1_3
PC527_P1_4
PC526_P1_3PR300
PC524
PC525_P1_4
PR298
PR297
PC536_P1_3PC530_P1_3PC528_P1_3
PC537_P1_4PC535_P1_4PC533_P1_4PC529_P1_4
PR299
PC523
PGND2
GL2
GL1
DNC
EN
PGND3
VOS
VIN2
PGND1
SW
LSET
IOUT
TOUT_FLT
PVCC
PHASE
VIN1
BOOT
AGND
VCC
REFIN
PWM
1 4
32
1 4
32
PGND2
GL2
GL1
DNC
EN
PGND3
VOS
VIN2
PGND1
SW
LSET
IOUT
TOUT_FLT
PVCC
PHASE
VIN1
BOOT
AGND
VCC
REFIN
PWM
SHEETDATE
DEPARTMENT
SIZE
PROJECT DOCUMENT NUMBER REV
REVIEWER
DESIGNER
123
7 3 2 1 6 5 4
E
A
B
C
E
D
C
B
A
7 6 5 4
D
IN
OUT
BI
OUT
BI
BI
IN
BI
OUT
IN
IN
OUT
C



DCR=2-3,0.27M OHMDCR=1-4,0.105M OHM11.0*7.5*12.5PGL6303.151HLTISAT=70A@100CDCR=1-4,0.105M OHMDCR=2-3,0.27M OHMPGL6303.151HLTISAT=70A@100C11.0*7.5*12.5
PVCCIN_CPU1_PHASE5PVCCIN_CPU1_PHASE6Fri Aug 25 14:04:57 2023N/AN/AN/AN/AV05287 OF 312PVCCIN_CPU1_PVCCPVCCIN_CPU1_PVCCSW_P12V_PVCCIN_CPU1_FLTPVCCIN_CPU1
SW_P12V_PVCCIN_CPU1_FLTPVCCIN_CPU1
VCCIN CPU1 VR PHASE 5&6 (4/7)284285286287288289290284284285286287288284284285284285286287288289290284285286287288284288288286PVCCIN_CPU1_LSET5PVCCIN_CPU1_LSET6PVCCIN_CPU1_VREFPVCCIN_CPU1_PWM6PVCCIN_CPU1_IMON6PVCCIN_CPU1_ATSENPVCCIN_CPU1_VDD6PVCCIN_CPU1_PWM5SW_PVCCIN_CPU1_SW6SW_PVCCIN_CPU1_BOOTR6PVCCIN_CPU1_VOS6IND_P1_CPL6SW_PVCCIN_CPU1_BOOT6 SW_PVCCIN_CPU1_BOOT6_RPVCCIN_CPU1_VDD5PVCCIN_CPU1_VREFPVCCIN_CPU1_IMON5PVCCIN_CPU1_ATSENSW_PVCCIN_CPU1_BOOTR5SW_PVCCIN_CPU1_SW5SW_PVCCIN_CPU1_BOOT5 SW_PVCCIN_CPU1_BOOT5_RPVCCIN_CPU1_VOS5IND_P1_CPL5IND_P1_CPL7IND_P1_CPL4
0402LF8.87K1%EMPTY1/16W0402LFEMPTY8.87K1%1/16W040225V0.1UF10%X7RISL99390FRZ-TR5935ICSMLFC040210V2.2UF10%X6S0402LF2.21%CHIP1/16WC040210V2.2UF10%X6SISL99390FRZ-TR5935ICSMLF
C040250V100NF10%X7R0402LF05%CHIP1/16WSMLFIND150NH040250V3300PF10%X7R0402LF3.31%CHIP1/16WX6SC040216V1UF10%C080516V22UF20%X6SC080516V22UF20%X6SC080516V22UF20%X6S040225V0.1UF10%X7RC040210V2.2UF10%X6S0402LF2.21%CHIP1/16WC040210V2.2UF10%X6S0402LF3.31%CHIP1/16W040250V3300PF10%X7RC040216V1UF10%X6S50V100NFC040210%X7RSMLF150NHIND0402LF 1/16W05%CHIPC080516V22UF20%X6SC080516V22UF20%X6SC080516V22UF20%X6S
X6S20%22UF4VC0805X6S20%22UF4VC0805X6S20%22UF4VC0805X6S20%22UF4VC0805
2
1
2
1
2
1
2
1
2
1
2
1
2
1
2
1
21PR1790
21PR295
2
1PC509
2
1
2
1
1
30
25_29
3
36
10_19
39
34
4
32
40
7_9-20_24
5
37
38
41
6
35
31
33
2
PU25_P1_6
21PC1360
2
1
2
1
2
1
21PR296
4
32
1
PL272
1PC510
2
1
21PR1791
2
1
2
1
2
1
21PC1361
2
1
2
1
2
1
4
32
1
PL26
1
30
25_29
3
36
10_19
39
34
4
32
40
7_9-20_24
5
37
38
41
6
35
31
33
2
PU26_P1_5
2
1
2
1
PC522_P1_5PC520_P1_5
PC521_P1_6
PC516_P1_5PC514_P1_5PC508_P1_5
PC515_P1_6PC511_P1_6
PR293
PC501
PR292
PC519_P1_6
PC512_P1_5PC506_P1_5
PC504_P1_5PR294
PC502
PC513_P1_6PC507_P1_6PC505_P1_6
PC503_P1_6
PR291
1 4
32
1 4
32
PGND2
GL2
GL1
DNC
EN
PGND3
VOS
VIN2
PGND1
SW
LSET
IOUT
TOUT_FLT
PVCC
PHASE
VIN1
BOOT
AGND
VCC
REFIN
PWM
PGND2
GL2
GL1
DNC
EN
PGND3
VOS
VIN2
PGND1
SW
LSET
IOUT
TOUT_FLT
PVCC
PHASE
VIN1
BOOT
AGND
VCC
REFIN
PWM
SHEETDATE
DEPARTMENT
SIZE
PROJECT DOCUMENT NUMBER REV
REVIEWER
DESIGNER
123
7 3 2 1 6 5 4
E
A
B
C
E
D
C
B
A
7 6 5 4
D
IN
BI
BI
IN
BI
IN
BI
OUT
OUT
OUT
OUT
IN
C



11.0*7.5*12.5ISAT=70A@100CPGL6303.151HLTDCR=1-4,0.105M OHMDCR=2-3,0.27M OHMPGL6303.151HLT11.0*7.5*12.5ISAT=70A@100CDCR=1-4,0.105M OHMDCR=2-3,0.27M OHMISAT=60A@100CDCR=0.17M OHMPGL6312.121AHLT6.5*6.5*10.0
PVCCIN_CPU1_PHASE7PVCCIN_CPU1_PHASE8Fri Aug 25 14:04:59 2023N/AN/AN/AN/AV05288 OF 312PVCCIN_CPU1_PVCCPVCCIN_CPU1_PVCCSW_P12V_PVCCIN_CPU1_FLTPVCCIN_CPU1
SW_P12V_PVCCIN_CPU1_FLTPVCCIN_CPU1
VCCIN CPU1 VR PHASE 7&8 (5/7)284285286287288284284284285286287288289290284285286287288284284284285286287288289290287287PVCCIN_CPU1_LSET8PVCCIN_CPU1_VDD8PVCCIN_CPU1_PWM8PVCCIN_CPU1_ATSENPVCCIN_CPU1_IMON8PVCCIN_CPU1_VREFPVCCIN_CPU1_PWM7PVCCIN_CPU1_ATSENSW_PVCCIN_CPU1_BOOT8PVCCIN_CPU1_LSET7PVCCIN_CPU1_IMON7PVCCIN_CPU1_VREFPVCCIN_CPU1_VDD7SW_PVCCIN_CPU1_BOOT7 SW_PVCCIN_CPU1_BOOT7_RSW_PVCCIN_CPU1_BOOT8_RPVCCIN_CPU1_VOS8PVCCIN_CPU1_VOS7IND_P1_CPL8SW_PVCCIN_CPU1_BOOTR8IND_P1_CPL7SW_PVCCIN_CPU1_SW7SW_PVCCIN_CPU1_BOOTR7SW_PVCCIN_CPU1_SW8IND_P1_CPL50402LF8.87K1%EMPTY1/16W040225V0.1UF10%X7RC040210V2.2UF10%X6SISL99390FRZ-TR5935ICSMLF0402LF2.21%CHIP1/16WEMPTY0402LF8.87K1%1/16WC040210V2.2UF10%X6SISL99390FRZ-TR5935ICSMLF
INDSMLF120NH/69A3300PF50V040210%X7R1/16W0402LF3.31%CHIP1UFC040216V10%X6SC080516V22UF20%X6S040225V0.1UF10%X7RC040210V2.2UF10%X6S040250V3300PF10%X7R0402LF3.31%CHIP1/16WC040216V1UF10%X6SC080516V22UF20%X6S
C040250V100NF10%X7RSMLFIND150NH0402LF 1/16W05%CHIPX6S22UFC080516V20%C080516V22UF20%X6S1/16W5%CHIP00402LFC0402X6S16V1UF10%X6S20%22UF4VC0805X6S20%22UF4VC0805
SMLF150NHIND10%C040250V100NFX7RC080516V22UF20%X6S16V22UF20%X6SC0805C040216V1UF10%X6S X6S20%22UF4VC0805X6S20%22UF4VC08050402LF2.21%CHIP1/16WC040210V2.2UF10%X6S
2
1
2
1
2
1
2
1
2
1
2
1
2
1
2
1PC488
4
32
1
PL25
21PR290
2
1
2
1
2 1
PL106
1
30
25_29
3
36
10_19
39
34
4
32
40
7_9-20_24
5
37
38
41
6
35
31
33
2
PU24_P1_7
2
1
2
1
1
30
25_29
3
36
10_19
39
34
4
32
40
7_9-20_24
5
37
38
41
6
35
31
33
2
PU23_P1_8
21PC1362
2
1
2
1
2
1
2
1
2
1
2
1
21PR289
4
32
1
PL242
1PC487
2
1
2
1
21PR1793
2
1
2
1
21PC1363
2
1
21PR1792
2
1
2
1
PC482_P1_7PR288
PC500_P1_7PC498_P1_7PC496_P1_7
PC494_P1_7PC492_P1_7
PC485_P1_8PC483_P1_8
PR286
PR287
PR285
PC499_P1_8PC497_P1_8PC495_P1_8
PC493_P1_8PC491_P1_8
PC490_P1_7PC486_P1_7PC484_P1_7
PC480
PC489_P1_8
PC481_P1_8
PC479
1 4
32
1 4
3212
PGND2
GL2
GL1
DNC
EN
PGND3
VOS
VIN2
PGND1
SW
LSET
IOUT
TOUT_FLT
PVCC
PHASE
VIN1
BOOT
AGND
VCC
REFIN
PWM
PGND2
GL2
GL1
DNC
EN
PGND3
VOS
VIN2
PGND1
SW
LSET
IOUT
TOUT_FLT
PVCC
PHASE
VIN1
BOOT
AGND
VCC
REFIN
PWM
SHEETDATE
DEPARTMENT
SIZE
PROJECT DOCUMENT NUMBER REV
REVIEWER
DESIGNER
123
7 3 2 1 6 5 4
E
A
B
C
E
D
C
B
A
7 6 5 4
D
OUT
IN
OUT
BI
BI
OUT
IN
IN
OUT
IN
C



ESR=9.5M OHMHCBS4545-101ISAT = 13A @ 100CDCR = 0.12M OHM4.5*4.5*4.5
RENESAS RECOMMEND BLEEDER RESISTOR(499OHM) TO ABSORB LEAKAGE FROM SPS.APPLY TO ALL RAILS.
DCR = 0.103M OHMISAT = 90A @ 100CISAT = 90A @ 100CDCR = 0.103M OHM10.0*7.5*12.0PG2323.131HLTPG2323.131HLT10.0*7.5*12.0PVCCFA_EHV_FIVRA_CPU1_PHASE2PVCCFA_EHV_FIVRA_CPU1_PHASE120211013 MODIFY FOR GT
Fri Aug 25 14:05:00 2023N/AN/AN/AN/AV05289 OF 312
P5VP3V3P5VP3V3
SW_P12V_PVCCFA_EHV_FIVRA_CPU1_LSW_P12V_PVCCFA_EHV_FIVRA_CPU1_R
PVCCFA_EHV_FIVRA_CPU1PVCCFA_EHV_FIVRA_CPU1P12V_AUXPVCCFA_EHV_FIVRA_CPU1SW_P12V_PVCCFA_EHV_FIVRA_CPU1_L
VCCFA_EHV_FIVRA CPU1 VR PHASE 1&2(6/7)2892902842842842852862872882892902842842842842852862872882892902892902842.5VOSCON20%560UFTHLF2.5VOSCON20%560UFTHLF2.5VOSCON20%560UFTHLF16V270UFOSCON20%THLF
PVCCFA_EHV_FIVRA_CPU1_LSET2PVCCFA_EHV_FIVRA_CPU1_BTSENPVCCFA_EHV_FIVRA_CPU1_PWM2PVCCIN_CPU1_VREFPVCCFA_EHV_FIVRA_CPU1_IMON2PVCCFA_EHV_FIVRA_CPU1_VDD2PVCCFA_EHV_FIVRA_CPU1_PVCC2PVCCFA_EHV_FIVRA_CPU1_PVCC1PVCCFA_EHV_FIVRA_CPU1_IMON1PVCCFA_EHV_FIVRA_CPU1_PWM1PVCCFA_EHV_FIVRA_CPU1_LSET1PVCCIN_CPU1_VREFPVCCFA_EHV_FIVRA_CPU1_BTSENPVCCFA_EHV_FIVRA_CPU1_VDD1SW_PVCCFA_EHV_FIVRA_CPU1_BOOT2PVCCFA_EHV_FIVRA_CPU1_VOS2SW_PVCCFA_EHV_FIVRA_CPU1_BOOT2_RSW_PVCCFA_EHV_FIVRA_CPU1_BOOTR2SW_PVCCFA_EHV_FIVRA_CPU1_SW2
SW_PVCCFA_EHV_FIVRA_CPU1_BOOT1 SW_PVCCFA_EHV_FIVRA_CPU1_BOOT1_RPVCCFA_EHV_FIVRA_CPU1_VOS1SW_PVCCFA_EHV_FIVRA_CPU1_SW1SW_PVCCFA_EHV_FIVRA_CPU1_BOOTR1
0402LF8.87K1%EMPTY1/16W0.1UF25V10%0402X7RISL99390FRZ-TR5935SMLFICC040210V2.2UF10%X6S0402LFCHIP1/16W1%2.21/16W0402LF05%CHIPC040210V2.2UF10%X6S1/16W5%0EMPTY0402LF0402LF8.87K1%1/16WEMPTYC040210V2.2UF10%X6S0402LF2.21%CHIP1/16W0.1UF25VX7R040210%C040210%X6S2.2UF10V0402LF05%CHIP1/16W01/16W5%0402LFEMPTY
10%3300PFX7R040250V0402LF1%CHIP1/16W3.3X6SC040216V1UF10%16V22UFX6SC080520%00402LF5%CHIP 1/16WC080522UF16VX6S20%C040250V10%X7R100NF130NH/106ASMLFIND22UFX6S16VC080520%040250V3300PF10%X7RCHIP3.31/16W0402LF1%10%C040216V1UFX6S16V22UFC0805X6S20%CHIP 0402LF05%1/16WC040250V10%X7R100NF130NH/106ASMLFINDX6S22UFC080516V20%16V22UFX6SC080520%10%C0402100NF50VX7RC040216V1UF10%X6S X6S22UF4VC080520%22UFX6S4VC080520%4991%1/16WCHIP0402LF+10/-35%SMLFSPCAP330UF2.5V+10/-35%330UFSMLFSPCAP2.5VX6S22UF4VC080520%22UFX6S4VC080520%X7R10%100NF50VC0402SMLFIND100NH/16AC0805X6S16V22UF20%16V22UFC0805X6S20%22UF16VX6SC080520%C0805X6S22UF16V20%ICISL99390FRZ-TR5935SMLF
PC1680PC1677 PC1678 PC1679
1
30
25_29
3
36
10_19
39
34
4
32
40
7_9-20_24
5
37
38
41
6
35
31
33
2
PU75_P1_1
2
1
21PL43
2
1
2
1
2
1
2
1
PC724_P1_1
2
1PC402
2
1
2
1 PC1242_P1_1
2
1
2
1
PR704
2
1
PC1243_P1_2
PR702
21PC1368
2
1
PC2172
2
1
PR4241
2
1
2
1PC401
21PR1801
PR703PR701
2
1
2
1
2
1
2
1
2
1
21PR1332
2
1
21PC1367
2
1
2
1
21
PL18
21PR1331
21PR1800
2
1
PC725_P1_2
21
PL19
2
1
2
1
2
1
1
30
25_29
3
36
10_19
39
34
4
32
40
7_9-20_24
5
37
38
41
6
35
31
33
2
PU76_P1_2
2
1
PC417
PC412_P1_1PC410_P1_1
PC415PC414PC406_P1_2
PR226
PR225
PC418
PC408_P1_2
PC405_P1_1
PR227
PC396
PC411_P1_2
PC403_P1_1PC399_P1_1
PC404_P1_2 PC416
PC413_P1_2
PC621_P1_1
PC397_P1_1
PC400_P1_2PC398_P1_2
PC395
PR224
PGND2
GL2
GL1
DNC
EN
PGND3
VOS
VIN2
PGND1
SW
LSET
IOUT
TOUT_FLT
PVCC
PHASE
VIN1
BOOT
AGND
VCC
REFIN
PWM
PGND2
GL2
GL1
DNC
EN
PGND3
VOS
VIN2
PGND1
SW
LSET
IOUT
TOUT_FLT
PVCC
PHASE
VIN1
BOOT
AGND
VCC
REFIN
PWM
1 2
1 2
1 2
2
1
2
1PC16572
1
2
1
2
1
2
1
2
1
2
1
SHEETDATE
DEPARTMENT
SIZE
PROJECT DOCUMENT NUMBER REV
REVIEWER
DESIGNER
123
7 3 2 1 6 5 4
E
A
B
C
E
D
C
B
A
7 6 5 4
D
OUT
OUT
IN
IN
OUT
IN
OUT
IN
C



ESR=9.5M OHM4.5*4.5*4.5HCBS4545-101DCR = 0.12M OHMISAT = 13A @ 100CDCR = 0.103M OHM10.0*7.5*12.0PG2323.131HLTISAT = 90A @ 100CPG2323.131HLTDCR = 0.103M OHM10.0*7.5*12.0ISAT = 90A @ 100C
PVCCFA_EHV_FIVRA_CPU1_PHASE3PVCCFA_EHV_FIVRA_CPU1_PHASE4
20211013 MODIFY FOR GT
Fri Aug 25 14:05:01 2023N/AN/AN/AN/AV05290 OF 312
PVCCFA_EHV_FIVRA_CPU1_PVCC2PVCCFA_EHV_FIVRA_CPU1_PVCC1
PVCCFA_EHV_FIVRA_CPU1SW_P12V_PVCCFA_EHV_FIVRA_CPU1_LSW_P12V_PVCCFA_EHV_FIVRA_CPU1_RP12V_AUXPVCCFA_EHV_FIVRA_CPU1PVCCFA_EHV_FIVRA_CPU1SW_P12V_PVCCFA_EHV_FIVRA_CPU1_R
VCCFA_EHV_FIVRA CPU1 VR PHASE 3&4(7/7)2842852862872882892902842892902842842842892902842842852862872882892902842.5VOSCON20%560UFTHLF2.5VOSCON20%560UFTHLF2.5VOSCON20%560UFTHLF16V270UFOSCON20%THLFPVCCFA_EHV_FIVRA_CPU1_LSET3PVCCFA_EHV_FIVRA_CPU1_LSET4PVCCIN_CPU1_VREFPVCCFA_EHV_FIVRA_CPU1_IMON4PVCCFA_EHV_FIVRA_CPU1_VDD4PVCCFA_EHV_FIVRA_CPU1_BTSENPVCCFA_EHV_FIVRA_CPU1_PWM4SW_PVCCFA_EHV_FIVRA_CPU1_BOOT4PVCCFA_EHV_FIVRA_CPU1_PWM3PVCCFA_EHV_FIVRA_CPU1_BTSENPVCCIN_CPU1_VREFPVCCFA_EHV_FIVRA_CPU1_VDD3PVCCFA_EHV_FIVRA_CPU1_IMON3SW_PVCCFA_EHV_FIVRA_CPU1_BOOT3
SW_PVCCFA_EHV_FIVRA_CPU1_BOOTR4
SW_PVCCFA_EHV_FIVRA_CPU1_BOOT3_RSW_PVCCFA_EHV_FIVRA_CPU1_BOOT4_RPVCCFA_EHV_FIVRA_CPU1_VOS4SW_PVCCFA_EHV_FIVRA_CPU1_SW4SW_PVCCFA_EHV_FIVRA_CPU1_SW3SW_PVCCFA_EHV_FIVRA_CPU1_BOOTR3PVCCFA_EHV_FIVRA_CPU1_VOS3
0402LF8.87K1%EMPTY1/16WEMPTY1/16W1%8.87K0402LF10V2.2UF10%C0402X6S10%0.1UF 040225VX7RSMLFISL99390FRZ-TR5935IC3.30402LFCHIP1%1/16W0402LF1/16W1%2.2CHIP10%10VC0402X6S2.2UF0.1UF25VX7R10%0402ISL99390FRZ-TR5935SMLFICC040210%2.2UF10VX6S2.21%0402LF1/16WCHIP10V10%2.2UFC0402X6S3300PF10%X7R040250V1UFX6SC040210%16V16VC080522UFX6S20%X6S16VC080522UF20%3300PF50V10%0402X7R16VC040210%1UFX6SCHIP3.30402LF1%1/16W16V22UFX6SC080520%C0805X6S16V22UF20%
5%01/16W0402LFCHIPIND130NH/106ASMLFX7RC040250V100NF10%100NF50V10%C0402X7R22UFX6S4VC080520%22UFX6S4VC080520%22UF16VC0805X6S20%0402LF1/16W05%CHIP16V10%X6S1UFC0402SMLF130NH/106AINDC040210%50V100NFX7RX6S22UFC080516V20%C0402X7R10%100NF50V100NH/16AINDSMLF4VX6S22UFC080520%X6S4V22UFC080520%SMLF330UF+10/-35%SPCAP2.5V+10/-35%330UFSPCAPSMLF2.5VC080516V22UFX6S20%X6S22UF16VC080520%22UFX6S16VC080520%C0805X6S16V22UF20%
PC1683PC1681 PC1684PC1682
2
1
2
1
PC2171
PC726_P1_3
2
1PC1197
2
1
2
1
21PR1334
2
1
PR1306
2
1 PC1245_P1_4
21PR1803
21PC1370
2
1
2
1
2
1
PC1205
2
1
PC1204
21PR1333
PC727_P1_4
2
1
2
1
2
1 PC1244_P1_3
1
30
25_29
3
36
10_19
39
34
4
32
40
7_9-20_24
5
37
38
41
6
35
31
33
2
PU77_P1_3
21PC1369
2
1
21PL14
2
1
2
1
2
1
2
1
PC1191
2
1
PR1307
1
30
25_29
3
36
10_19
39
34
4
32
40
7_9-20_24
5
37
38
41
6
35
31
33
2
PU78_P1_4
21
PL12
2
1
2
1
2
1
2
1
PC1203
2
1
2
1
PC1201
2
1PC1198
21
PL113
21PR1802
2
1
2
1
2
1
PC1210
PC1207_P1_4PC1203_P1_4
PC1192
PR1305
PC1209_P1_4
PC1196_P1_4
PC1206_P1_3
PC1201_P1_3PC1195_P1_3
PC1202_P1_4
PC1199_P1_3PC1193_P1_3
PC1208_P1_3PC1204_P1_3
PC1200_P1_4PC1194_P1_4
PR1304
1 2
1 2
1 2
PGND2
GL2
GL1
DNC
EN
PGND3
VOS
VIN2
PGND1
SW
LSET
IOUT
TOUT_FLT
PVCC
PHASE
VIN1
BOOT
AGND
VCC
REFIN
PWM
PGND2
GL2
GL1
DNC
EN
PGND3
VOS
VIN2
PGND1
SW
LSET
IOUT
TOUT_FLT
PVCC
PHASE
VIN1
BOOT
AGND
VCC
REFIN
PWM
2
1
2
1
2
1PC16582
1
2
1
2
1
2
1
SHEETDATE
DEPARTMENT
SIZE
PROJECT DOCUMENT NUMBER REV
REVIEWER
DESIGNER
123
7 3 2 1 6 5 4
E
A
B
C
E
D
C
B
A
7 6 5 4
D
IN
IN
OUT
OUT
IN
IN
OUT
OUT
C



Thu Aug 24 16:16:56 2023N/AN/AN/AN/AV05291 OF 312BLANK
SHEETDATE
DEPARTMENT
SIZE
PROJECT DOCUMENT NUMBER REV
REVIEWER
DESIGNER
123
7 3 2 1 6 5 4
E
A
B
C
E
D
C
B
A
7 6 5 4
D
C



(EMR 1.05VAMX/0.93VMIN)TOTAL TOLERANCE=1.05VMAX/0.909VMINVID=0.7V~1.05V(TYP=1.0V)PVCCINFAON_CPU1 SPECIFICATIONTDC=48A(EMR 42A)DC=+/-0.5%@1VRIPPLE=+/-8MVVBOOT=1.0VPDG REV.1.6 FOR SPR+HBMWORK FREQUENCY=600KHZSVID ADDRESS=02H BUS#0SETVID RATE=10MV/US (FAST)PROTOCOL ID=04H (VR13 10MV VID)CURRENT STEP=4.75A(1.5A-6.25A)LOAD-LINE=N/ATDC=5ASLEW RATE=5.3A20220808 UPDATE PDG REV 1.6SVID / I2C ADDRESSI2C(7BIT/8BIT)CONFIRM ADDRESS SETTINGSET FW CODE FUNCTION TO BVR_ENTRACE SPACING = 5MILDIFFERENTIAL PAIRTRACE WIDTH = 10MILTRACE SPACING = 5MILTRACE WIDTH = 10MILDIFFERENTIAL PAIR74H/E8H74H/E8H01H02HSVIDRAILPVCCINFAON_CPU1PVCCFA_EHV_CPU120220725 CONNECT TO CPLDOCP=15AMAX CURRENT=6.25ATOTAL TOLERANCE=1.841VMAX/1.749VMINDC=+/-0.5% OF VIDRIPPLE=+/-9MVVID=1.6V~1.87V(TYP=1.8V)VBOOT=1.8VPVCCFA_EHV_CPU1 SPECIFICATIONMAX CURRENT=53A(EMR 46A)OCP=69A(130%)PDG REV.1.6 FOR SPR+HBMSETVID RATE=2.5MV/US (FAST)PROTOCOL ID=09H (VR14 5MV VID)SVID ADDRESS=01H BUS#0WORK FREQUENCY=700KHZLOAD-LINE=2.2 MOHMCURRENT STEP=15A(38A-53A)(EMR 31A-46A)SLEW RATE=18A/US(EMR 20.2A/US)
Fri Aug 25 14:05:03 2023N/AN/AN/AN/AV05292 OF 312
PVCCINFAON_CPU1PVNN_TERM_CPU1
P12V_AUXP3V3_AUXP3V3_AUXPVCCFA_EHV_CPU1P3V3_AUX
P3V3_AUXP3V3_AUX
VCCINFAON/VCCFA_EHV CPU1 VR CONTROLLER (1/3)
SH_PVCCFA_EHV_CPU1_R1UFCHIPNC_PVCCINFAON_CPU1_APWM5NC_PVCCINFAON_CPU1_ACSP5PVCCINFAON_CPU1_VREF
PVCCFA_EHV_CPU1_BTSENPVCCINFAON_CPU1_ADDRPVCCINFAON_CPU1_VR_FAULTPVCCINFAON_CPU1_PIN_ALERTPVCCINFAON_CPU1_CSPIN
PWRGD_PVCCINFAON_CPU1_RSMB_DIO_PVCCINFAON_CPU1PVCCINFAON_CPU1_EN_RNC_PVCCINFAON_CPU1_SMB_ALERTSVID_CLK_PVCCINFAON_CPU1_R
PWRGD_PVCCFA_EHV_CPU1_R
SVID_ALERT_PVCCINFAON_CPU1_RSVID_DIO_PVCCINFAON_CPU1_RSMB_CLK_PVCCINFAON_CPU1
PVCCFA_EHV_CPU1_EN_RPVCCFA_EHV_CPU1_BCSP1PVCCFA_EHV_CPU1_BPWM1NC_PVCCINFAON_CPU1_ACSP6NC_PVCCINFAON_CPU1_APWM6PVCCINFAON_CPU1_APWM1NC_PVCCINFAON_CPU1_ACSP7PVCCINFAON_CPU1_APWM2NC_PVCCINFAON_CPU1_APWM7NC_PVCCINFAON_CPU1_APWM3NC_PVCCINFAON_CPU1_APWM4NC_PVCCINFAON_CPU1_ACSP4NC_PVCCINFAON_CPU1_ACSP3IRQ_PVCCFA_CPU1_VRHOT_NPVCCINFAON_CPU1_ACSP2PVCCINFAON_CPU1_VCCPVCCINFAON_CPU1_ACSP1SMLFICISL69260IRAZ-T
CHIP0402LF1K1%1/16W293
294214293
293292 293 294
292293294
24129622245284
474724129645284214254452844747214254222
293
294294293
IRQ_PVCCFA_CPU1_VRHOT_R_N0402LFCHIPPVCCINFAON_CPU1_ATSEN1/16W0402
0.1UF25VEMPTY040210%0402LF
CHIP1/16WCHIP1/16W8.45K1%0402LFEMPTY 1/16W0PVCCINFAON_CPU1_VREF
SMB_VR_3V3AUX_SCL_RFM_PVCCINFAON_CPU1_ENSVID_CLK0_CPU1_R
VSENSE_PVCCFA_EHV_CPU1_DNVSENSE_PVCCINFAON_CPU1_DNSMB_VR_3V3AUX_SDA_RSVID_DIO0_CPU1_RPWRGD_PVCCINFAON_CPU1SVID_ALERT0_CPU1_R_NVSENSE_PVCCFA_EHV_CPU1_DPVSENSE_PVCCINFAON_CPU1_DPPWRGD_PVCCFA_EHV_CPU1FM_PVCCFA_EHV_CPU1_ENPVCCINFAON_CPU1_VIN_CSNINSH_PVCCFA_EHV_CPU1SH_PVCCINFAON_CPU1 SH_PVCCINFAON_CPU1_R1%1001/16W0402LFEMPTY1%49.90402LFEMPTY1/16W
5%0402LFEMPTY05%0402LF0402LF1%28K00402LF5%1/16WCHIP0.1UF040225V10%EMPTY5%0402LF1/16WCHIP01K1/16W0402LF1%CHIP05%0402LFCHIP 1/16W50VEMPTY1000PF5%040204025%1000PF50V X7R0402LF1K1%EMPTY1/16WX7R04020.1UF10%25V1/16W0402LF1001%CHIPEMPTYSMCHIP 1/16W0402LF1001%1/16W1%0402LFCHIP1001%0402LF1K1/16W0402LF1KCHIP1%040250V3300PF10%X7R0402LF05%CHIP 1/16W040250V10%X7R3300PFSMEMPTY1%0402LF100CHIP 1/16W1/16WCHIP05%0402LF1/16W0402LF05%CHIP0CHIP5%0402LF1/16W05%1/16W0402LFCHIP0402LF1/16W1%150CHIPCHIP 1/16W0402LF05%1000PF50V X7R04025%
0402X7R10%50V470PF1/16WEMPTY10K0402LF1%470PF10% X7R50V5%00402LF10K1%EMPTY1/16W01/16WCHIP5%0402LFCHIP5%05%CHIP00402LF1/16W05%1/16W0402LFCHIP05%1/16WC0402X6S20%10UF6.3VC040250V10%EMPTY100NFX6S10%16VC0402C04021UFX6S10%16V1/16W0402LF0CHIP5%0CHIP5%0402LF1/16W0402LF1K 1%1/16WCHIP040250V1000PF EMPTY5%1/16W1%CHIP10402LF
PR259
R2354
R2345
21
2121
2
1
PC1193
2
1
PR667
R2574
PR665
21
21R2568
21R2569
21PR566
21PR569
21PR567
PU22
2
1
2
1
21
21
21
2
1
2
1
21PC1292
21
2
1
21
21
21
21
21
2
1
2
1
21
21
21PR568
2
1
21
21
21
21
21
21
21
2
1
2
1
21
PR283
C2450R2556
PC477
C2451
PC474PR276
R2571
R2572
R4781
PC478PC476
PJ51
PC467
PR258
PR261
C2452
C2453
R2573
PC475
PR273
R2560
PC468
R2570
R2559
R2561
R2563
PJ50
PR274
PC469
PR275
PR260
R2558
R4594
PR4243
37
38
14
19
11
15
32
21
40
39
TH
36
35
18
17
31
22
8
7
6
5
4
3
2
1
9
10
16
12
20
13
23
24
25
26
27
28
29
30
33
34
PR4245
SHORT
1 2
SHORT
1 2
CS0
PWM0
TEMP0
ADDR_CFG
TH_GND
CFP
CS2
PWM2
CS3
PWM3
PWM7
CS1
RGND1
VSEN1
nPINALERT#||nPSYSCRIT#
TEMP1||ISYS
VINSEN||VSYS
VMON||IINSEN||VSYS||ISYS
VCCS
PWM6
PG0
PWM1
VSEN0
PWM5
PWM4
PMSDA
RGND0
EN0
nPMALERT#
SVCLK
PG1
CS4
CS5
nVRHOT#
nSVALERT#
CS6
SVDATA
PMSCL
EN1
VCC
CS7
2
1
2
1
21
21PR4242
21
21
21
21PR4244
21
21PR4246
SHEETDATE
DEPARTMENT
SIZE
PROJECT DOCUMENT NUMBER REV
REVIEWER
DESIGNER
123
7 3 2 1 6 5 4
E
A
B
C
E
D
C
B
A
7 6 5 4
D
IN
OUT
OUT
IN
BI
OUT
IN
IN
OUT
IN
IN
OUT
IN
IN
IN
IN
OUT
OUT
IN
IN
OUT
BI
OUT
IN
IN
PC2367
C



DCR = 0.12M OHMISAT = 13A @ 100CHCBS4545-1014.5*4.5*4.5ESR=9.5M OHMESR=9.5M OHM6.5*6.5*10.0ISAT=60A@100CDCR=0.17M OHMPGL6312.121AHLT
DCR=0.17M OHMISAT=60A@100C6.5*6.5*10.0PGL6312.121AHLT
PVCCINFAON_CPU1_PHASE1PVCCINFAON_CPU1_PHASE2RENESAS RECOMMEND BLEEDER RESISTOR(499OHM) TO ABSORB LEAKAGE FROM SPS.APPLY TO ALL RAILS.Fri Aug 25 14:05:04 2023N/AN/AN/AN/AV05293 OF 312PVCCFA_EHV_CPU1_PVCCPVCCFA_EHV_CPU1_PVCCSW_P12V_PVCCINFAON_CPU1_FLTSW_P12V_PVCCINFAON_CPU1_FLT
PVCCINFAON_CPU1PVCCINFAON_CPU1PVCCINFAON_CPU1PVCCINFAON_CPU1P12V_AUXSW_P12V_PVCCINFAON_CPU1_FLT
VCCINFAON CPU1 VR PHASE 1&2 (2/3)293292292293294292292293292292293294292
292
270UF16VOSCON20%THLF
2.5VOSCON20%560UFTHLF2.5VOSCON20%560UFTHLF2.5VOSCON20%560UFTHLF
270UF16VOSCON20%THLF
PVCCINFAON_CPU1_VDD2PVCCFA_EHV_CPU1_PVCCPVCCFA_EHV_CPU1_PVCCPVCCINFAON_CPU1_VDD1PVCCINFAON_CPU1_LSET1PVCCINFAON_CPU1_LSET2PVCCINFAON_CPU1_ATSENPVCCINFAON_CPU1_VREFPVCCINFAON_CPU1_ACSP2PVCCINFAON_CPU1_APWM1PVCCINFAON_CPU1_ATSENPVCCINFAON_CPU1_VREFPVCCINFAON_CPU1_ACSP1
PVCCINFAON_CPU1_APWM2PVCCINFAON_CPU1_VOS2SW_PVCCINFAON_CPU1_BOOT2SW_PVCCINFAON_CPU1_BOOT1SW_PVCCINFAON_CPU1_BOOTR1SW_PVCCINFAON_CPU1_BOOTR2SW_PVCCINFAON_CPU1_SW2PVCCINFAON_CPU1_VOS1SW_PVCCINFAON_CPU1_SW1SW_PVCCINFAON_CPU1_BOOT2_RSW_PVCCINFAON_CPU1_BOOT1_R
1/16WEMPTY1%8.87K0402LF25V0402X7R0.1UF10%10%2.2UF10VC0402X6S1/16W1%CHIP2.20402LF2.2UF10V10%X6SC04020402LF1/16WEMPTY1%8.87K0.1UF25VX7R 10%0402X6S10V2.2UF10%C04022.20402LF1%CHIP1/16WX6S10%C04022.2UF10VISL99390FRZ-TR5935SMLFIC05%0402LF 1/16WCHIP4V22UFX6SC080520%22UF4VX6SC080520%1/16W0402LFCHIP1%49950V3300PF0402X7R10%16V10%X6S1UFC0402ICSMLFISL99390FRZ-TR5935X7R10%3300PF50V0402X6S10%1UF16VC0402
3.31%1/16W CHIP0402LFX6S16V22UFC080520%X7R10%100NF50VC040216VX6SC080522UF20%SMLF120NH/69AIND0402LF1/16WCHIP05%CHIP0402LF1%1/16W3.3X6S22UF16VC080520%X7R10%100NFC040250VX6S16V22UFC080520%120NH/69ASMLFINDX7R10%50V100NFC0402330UF35%2VSPCAPSMLFSPCAP35%330UF2VSMLF4V22UFX6SC080520%4V22UFC0805X6S20%50V100NF10%X7RC0402IND100NH/16ASMLF
293294297293294297
21
2
1 PC1596
2
1
2
121PC1364
21PC1365
2
1
PR1727
21
PL21
21PR1794
21PR1796
2
1
21PR1797
2
1
2
1
2
1
2
1
2
1 PC1588
2
1 PC1595
2
1
21
PL22
2
1
2
1PC447
21PR1795
2
1
2
1
2
1
2
1
PR1726
2
1
2
1 PC1594
2
1 PC1593
2
1PC446
2
1
2
1
2
1
2
1
PR4247
2
1
2
1
PL23
PC457_P1_1PC452_P1_1
PC442_P1_1
PC440
PC441
PC461
PC455_P1_1
PC450_P1_1
PC451_P1_2PC445_P1_2
PC456_P1_2
PR254
PC460
PC448_P1_1
PC449_P1_2
PC444_P1_1
PC443_P1_2
PC458_P1_2
PR255
PC2950
PC2949
1
30
25_29
3
36
10_19
39
34
4
32
40
7_9-20_24
5
37
38
41
6
35
31
33
2
1
30
25_29
3
36
10_19
39
34
4
32
40
7_9-20_24
5
37
38
41
6
35
31
33
2
PU51_P1_2
PU50_P1_1
1 2
1 2
1 2
PGND2
GL2
GL1
DNC
EN
PGND3
VOS
VIN2
PGND1
SW
LSET
IOUT
TOUT_FLT
PVCC
PHASE
VIN1
BOOT
AGND
VCC
REFIN
PWM
PGND2
GL2
GL1
DNC
EN
PGND3
VOS
VIN2
PGND1
SW
LSET
IOUT
TOUT_FLT
PVCC
PHASE
VIN1
BOOT
AGND
VCC
REFIN
PWM
2
1
2
1
2
1PC1659
2
1
SHEETDATE
DEPARTMENT
SIZE
PROJECT DOCUMENT NUMBER REV
REVIEWER
DESIGNER
123
7 3 2 1 6 5 4
E
A
B
C
E
D
C
B
A
7 6 5 4
D
IN
OUT
OUT
IN
IN
OUT
OUT
IN
C



PVCCFA_EHV_CPU1ISAT = 29A @ 125CDCR = 0.17M OHMPG1712.301AHLT9.6*6.4*9.0APPLY TO ALL RAILS.(499OHM) TO ABSORB LEAKAGE FROM SPS.RENESAS RECOMMEND BLEEDER RESISTORFri Aug 25 14:05:05 2023N/AN/AN/AN/AV05294 OF 312
PVCCFA_EHV_CPU1SW_P12V_PVCCINFAON_CPU1_FLTPVCCFA_EHV_CPU1_VDD1P3V3P5V292292292
VCCFA_EHV_CPU1 VR PHASE (3/3)2922930402LFCHIP1/16W1%4992.5VSMLF330UFSPCAP+10/-35%20%C0805X6S4V22UF20%C0805X6S4V22UFC040250V100NFX7R10%20%X6S22UF16VC080520%16VX6SC080522UF1UFC040216V10%X6S3.3CHIP0402LF 1/16W1%0402X7R10%3300PF50V300NH/33ASMLFINDC0402100NFX7R10%50VCHIP1/16W5%0402LF0EMPTY0402LF05%1/16W1/16WEMPTY5%00402LFCHIP1%2.21/16W0402LFRAA2213404GNP#HB0ICSMLFEMPTY5%0C0402X6S2.2UF10V10%0.1UFX7R040225V10%1/16WCHIP5%00402LF1/16W0402LFEMPTY1%8.87KSW_PVCCFA_EHV_CPU1_BOOT1_RSW_PVCCFA_EHV_CPU1_BOOT1SW_PVCCFA_EHV_CPU1_BOOTR1PVCCFA_EHV_CPU1_NC1SW_PVCCFA_EHV_CPU1_SW1PVCCFA_EHV_CPU1_FAULTPVCCFA_EHV_CPU1_VDD1PVCCFA_EHV_CPU1_BTSENPVCCFA_EHV_CPU1_BPWM1PVCCFA_EHV_CPU1_BCSP1PVCCFA_EHV_CPU1_NC2PVCCINFAON_CPU1_VREFPVCCFA_EHV_CPU1_PVCCPVCCFA_EHV_CPU1_LSET1THLF560UF20%OSCON2.5V293297
PC1366
PR4250
2
1
PC1930
21PR1799
PR699
2
1
2
1
PR1728
2
1
PC2199
21
2
1
2
1
2
1
2
1
PR678
2
1
2
1
2
1
21PR1798
2
1
21
PL202
1PC431
16_18-284
1
8_12
24
21
19
22
3
25
26
23
6_7-13_15-29
27
5
2
20
PU49
PC428
PC434
PC433PC430
PR250
PC437PC435
PC432PC429
PR4249
PR4248
1 2
LGCTRL
GL1
NC1
GND3
FAULT#
SW
GL2
GND1
IMON
TMON
VCC
PHASE
VIN
BOOT
GND2
REFIN
PWM
2
1
21
21
SHEETDATE
DEPARTMENT
SIZE
PROJECT DOCUMENT NUMBER REV
REVIEWER
DESIGNER
123
7 3 2 1 6 5 4
E
A
B
C
E
D
C
B
A
7 6 5 4
D
IN
OUT
IN
OUT
C



Thu Aug 24 16:17:05 2023N/AN/AN/AN/AV05295 OF 312BLANK
SHEETDATE
DEPARTMENT
SIZE
PROJECT DOCUMENT NUMBER REV
REVIEWER
DESIGNER
123
7 3 2 1 6 5 4
E
A
B
C
E
D
C
B
A
7 6 5 4
D
C



DIFFERENTIAL PAIRMAX VOLTAGE VIA BIOS COMMAND=1.145VPDG REV.1.6 FOR SPR+HBM20220808 UPDATE PDG REV 1.6RIPPLE=+/-10MVDC=+/-0.5% OF VIDMAX VR OFFSET=5MVPROTOCOL ID=07H (VR13 5MV VID)SVID ADDRESS=00H BUS#1WORK FREQUENCY=700KHZVBOOT=1.1VPVCCD_HV_CPU1 SPECIFICATION
SVID / I2C ADDRESSPVCCD_HV_CPU1RAIL SVID00H
TRACE WIDTH = 10MILTRACE SPACING = 5MIL
I2C(7BIT/8BIT)76H/ECHSET FW CODE FUNCTION TO BVR_ENCONFIRM ADDRESS SETTING
OCP=35ATDC=23A(EMR 26A)TOTAL TOLERANCE=1.192MAX/1.086VMIN(FUTURE 1.189VMX/1.081VMIN)MAX CURRENT=25A(EMR 30A)CURRENT STEP=17A(8A-25A)(EMR 20A(10A-30A)SLEW RATE=8.6A/US(EMR 8A/US)LOAD-LINE=0.8MINI OHM
Fri Aug 25 14:05:07 2023N/AN/AN/AN/AV05296 OF 312P3V3_AUXP3V3_AUX
PVNN_TERM_CPU1PVCCD_HV_CPU1P3V3_AUXP3V3_AUX
VCCD_HV CPU1 VR CONTROLLER (1/2)
CHIPNC_PVCCD_HV_CPU1_ACSP20402LFPVCCD_HV_CPU1_VREF
PVCCD_HV_CPU1_ATSENPVCCD_HV_CPU1_ADDRPVCCD_HV_CPU1_FAULTPVCCD_HV_CPU1_PIN_ALT
PWRGD_PVCCD_HV_CPU1_RSMB_DIO_PVCCD_HV_CPU1PVCCD_HV_CPU1_EN_RNC_PVCCD_HV_CPU1_SMB_ALERTSVID_CLK_PVCCD_HV_CPU1_R
NC_PVCCD_HV_CPU1_BVR_RDY
SVID_ALERT_PVCCD_HV_CPU1_RSVID_DIO_PVCCD_HV_CPU1_RSMB_CLK_PVCCD_HV_CPU1
NC_PVCCD_HV_CPU1_ACSP8NC_PVCCD_HV_CPU1_APWM8NC_PVCCD_HV_CPU1_ACSP6NC_PVCCD_HV_CPU1_APWM6NC_PVCCD_HV_CPU1_ACSP5NC_PVCCD_HV_CPU1_APWM5PVCCD_HV_CPU1_APWM1NC_PVCCD_HV_CPU1_ACSP7PVCCD_HV_CPU1_ISYS_R
NC_PVCCD_HV_CPU1_APWM2NC_PVCCD_HV_CPU1_APWM7NC_PVCCD_HV_CPU1_APWM3NC_PVCCD_HV_CPU1_APWM4NC_PVCCD_HV_CPU1_ACSP4NC_PVCCD_HV_CPU1_ACSP3IRQ_PVCCD_CPU1_VRHOT_LVC3_R_N
PVCCD_HV_CPU1_VCCPVCCD_HV_CPU1_ACSP1ICSMLFISL69260IRAZ-T296 297
29629747
251
472412922412924545214219214254297297
297251215
45
251
EMPTY040225V0.1UF
CHIP1/16W24.3K1%EMPTY 1/16W28KPVCCD_HV_CPU1_VREFVSENSE_PVCCD_HV_CPU1_DN
P12V_AUX_CPU1_DIMM_ISEN_N
VSENSE_PVCCD_HV_CPU1_DP
PVCCD_HV_CPU1_ISENSE_P
SH_PVCCD_HV_CPU1SMB_VR_3V3AUX_SCL_RSMB_VR_3V3AUX_SDA_RSVID_DIO1_CPU1_RSVID_CLK1_CPU1_RFM_PVCCD_HV_CPU1_ENPWRGD_PVCCD_HV_CPU1SH_PVCCD_HV_CPU1_R
PVCCD_HV_CPU1_ISENSE_NPVCCD_HV_CPU1_NVDIMM_ISENSEIRQ_PVCCD_CPU1_VRHOT_LVC3_N
SVID_ALERT1_CPU1_R_N
0402LF1%1%49.9CHIP1/16W0402LF1%49.9CHIP0402LF1KEMPTY1/16W1%0402X7R10%0.1UF25V
1001%CHIP 1/16WEMPTYSM0402LFCHIP1%1/16W1K1/16W0402LFCHIP1K1%CHIP 1/16W00402LF5%3300PF50V10%X7R0402C0402X6S20%6.3V10UF04020.1UFX7R10%25V1/16W0402LF1001%CHIP0402LF 1/16WCHIP1%49.9100CHIP1%1/16W0402LF0402LF1/16W5%CHIP01/16W0402LF0CHIP0402LF5%1/16W0CHIPCHIP 1/16W05%0402LF0402LF1%1501/16WCHIP5%0402LF01/16WCHIP1/16W0402LF05%CHIP1000PF EMPTY50V5%04021/16W0402LF1K 1%CHIP
0402LF1%EMPTY1/16W1K040225V0.1UF10%X7RC040210%1UF 16VX6S040250V470PF10%X7RCHIP5%01/16W0402LF5%0CHIP05%CHIP1/16W0402LF5%0EMPTY1/16W0402LF05%0402LF1/16WCHIP05%0402LF1/16WCHIP05%0402LF1/16WCHIPCHIP05%0402LF1/16W0402LF05%CHIP1/16W6.3VX6S20%10UFC040210%EMPTYC04020402LF1/16W5%0CHIP10%C040216V1UFX6S16V1UFC040210%X6S0402LF 1/16W1%1
10KEMPTY1%1/16W0402LF0402LF1%CHIP1/16W1KP12V_AUX_CPU1_DIMM_ISEN_P
5%10%100NF50V
R2593
21
2
1
21
21
21
21
21
2
1 C1336
2
1
21
21PR558
2
1
21PR1410
21PR1400
21
2
1
2
1
PC1289
2
1
2
1
2
1
PC814
21
2
1 C1337
21
2
1
2
1
2
1
PR705
21
21PR559
PR410
21PR1315
PU18
2
1
2
1
21
21R1718
PR220
PC394
R2576
R2577
R2578
R2579
R2580
PC389
PJ48
PR214
PR202
R223
PC391
PC392
PC393
R4595
PR216
PR217PR215
PC386
C2454
PC390PR218
R2575
PR203
1
R2582
37
38
14
19
11
15
32
21
40
39
TH
36
35
18
17
31
22
8
7
6
5
4
3
2
1
9
10
16
12
20
13
23
24
25
26
27
28
29
30
33
34
CS0
PWM0
TEMP0
ADDR_CFG
TH_GND
CFP
CS2
PWM2
CS3
PWM3
PWM7
CS1
RGND1
VSEN1
nPINALERT#||nPSYSCRIT#
TEMP1||ISYS
VINSEN||VSYS
VMON||IINSEN||VSYS||ISYS
VCCS
PWM6
PG0
PWM1
VSEN0
PWM5
PWM4
PMSDA
RGND0
EN0
nPMALERT#
SVCLK
PG1
CS4
CS5
nVRHOT#
nSVALERT#
CS6
SVDATA
PMSCL
EN1
VCC
CS7
SHORT
1 2
2
1
21
21PR4254
21PR4253
21PR4252
2PR4255
21PR4257
21PR4251
21PR4256
21
21
21
R2557
SHEETDATE
DEPARTMENT
SIZE
PROJECT DOCUMENT NUMBER REV
REVIEWER
DESIGNER
123
7 3 2 1 6 5 4
E
A
B
C
E
D
C
B
A
7 6 5 4
D
OUT
IN
IN
OUT
OUT
IN
IN
IN
OUT
IN
IN
BI
OUT
IN
BI
IN
IN
OUT
IN
PC2368
C



APPLY TO ALL RAILS.RESERVE BY ARCHER CITY(499OHM) TO ABSORB LEAKAGE FROM SPS.RENESAS RECOMMEND BLEEDER RESISTORDCR=0.17M OHMISAT=60A@100CPGL6312.121AHLT6.5*6.5*10.0PVCCD_HV_CPU1_PHASE1
Fri Aug 25 14:05:08 2023N/AN/AN/AN/AV05297 OF 312
PVCCFA_EHV_CPU1_PVCCPVCCD_HV_CPU1PVCCD_HV_CPU1SW_P12V_PVCCINFAON_CPU1_FLT
VCCD_HV_CPU1 VR PHASE (2/2)
2962962962962.5VOSCON20%560UFTHLF2.5VOSCON20%560UFTHLFPVCCD_HV_CPU1_LSET1PVCCD_HV_CPU1_VREFPVCCD_HV_CPU1_APWM1PVCCD_HV_CPU1_ATSENPVCCD_HV_CPU1_ACSP1SW_PVCCD_HV_CPU1_BOOTR1SW_PVCCD_HV_CPU1_SW1PVCCD_HV_CPU1_VOSPVCCFA_EHV_CPU1_PVCCPVCCD_HV_CPU1_VDD1SW_PVCCD_HV_CPU1_BOOT1 SW_PVCCD_HV_CPU1_BOOT1_R0402LF8.87K1%EMPTY1/16W10%25V0.1UF0402X7RICSMLFISL99390FRZ-TR59350402LF1/16W5%0CHIP10%C040250V100NFX7R120NH/69AINDSMLF10%10VX6SC04022.2UF1%2.2CHIP1/16W0402LFC040210%10VX6S2.2UF040250V3300PF10%X7RCHIP0402LF1%3.31/16WC040216V1UF10%X6SC080516V22UFX6S20%16V22UFX6SC080520%SMLF2V330UF35%SPCAPX7R100NF50V10%C0402 C080522UF4VX6S20%C08054V22UFX6S20%X6S4VC080522UF20%4991%1/16WCHIP0402LF293294
PR4258
2
1
2
1
PC1940
2
1
2
1PC376
2
1
2
1
2
1
2
1
PR1746
2
1
2
1
21
PL17
2
1
21PR1805
2
1
2
1
2
1
21PR1804
2
1
21PC1371
PC384
PC378
PC385
PC2
PR200
PC382
PC373
PC375
PC381PC379
PC377PC374PC2951
1
30
25_29
3
36
10_19
39
34
4
32
40
7_9-20_24
5
37
38
41
6
35
31
33
2
PU17
1 2
PGND2
GL2
GL1
DNC
EN
PGND3
VOS
VIN2
PGND1
SW
LSET
IOUT
TOUT_FLT
PVCC
PHASE
VIN1
BOOT
AGND
VCC
REFIN
PWM
2
1
2
1
SHEETDATE
DEPARTMENT
SIZE
PROJECT DOCUMENT NUMBER REV
REVIEWER
DESIGNER
123
7 3 2 1 6 5 4
E
A
B
C
E
D
C
B
A
7 6 5 4
D
OUT
OUT
IN
IN
C



Thu Aug 24 16:17:09 2023N/AN/AN/AN/AV05298 OF 312BLANK
SHEETDATE
DEPARTMENT
SIZE
PROJECT DOCUMENT NUMBER REV
REVIEWER
DESIGNER
123
7 3 2 1 6 5 4
E
A
B
C
E
D
C
B
A
7 6 5 4
D
C



IC TABLEPC644 MAIN 1UF20220808 ADD CHANGE LIST3RD AL0086330071ST AL0533180022ND AL00054800620220804 CHANGE IC TABLE3RD 1UF2ND 2.2UF
PVPP_HBM_CPU1
20220808 ADD CHANGE LISTVOUT=((RA/RB)+1)*0.6=2.634V3RD 100PF2ND 270PFPC1266 MAIN 680PFRBDCR=5.5M OHMISAT=23A@100C6.5*6.9*3.0PCMC063T-R68MNRAPDG REV 1.620220808 UPDATE PDG REV 1.6TOTAL TOL=2.708VMAX/ 2.530VMINPVPP_HBM_CPU1 SPECIFICATIONOCP(IMAX*130%)=8ARIPPLE=+/-7MVDC=+/-0.7%VOUT=2.5VMAX CURRENT=5ATDC=4ASLEW RATE=1.6A/USWORK FREQUENCY=800KHZCURRENT STEP=4.6A
20220804 CHANGE PC1266 TO 680PF FOR TRANSIENT RESPONSEREMOTE SENSEPLACE AT CHIPSET SIDEFri Aug 25 14:05:09 2023N/AN/AN/AN/AV05299 OF 312I29P3V3_AUXP3V3_AUXSW_P12V_PVCCIN_CPU1_FLTP3V3_AUXPVPP_HBM_CPU1
PVPP_HBM_CPU1215281213 254214PVPP_HBM_CPU1_VCCPVPP_HBM_CPU1_MODEPVPP_HBM_CPU1_CSSW_PVPP_HBM_CPU1_BSTPVPP_HBM_CPU1_REFPWRGD_PVPP_HBM_CPU1_RSW_PVPP_HBM_CPU1_SWPVPP_HBM_CPU1_FBSH_PVPP_HBM_CPU1_NFM_HBM_VPP_SEL_CPU1_DFM_HBM2_HBM3_VPP_SELPWRGD_PVPP_HBM_CPU1SH_PVPP_HBM_CPU1_P1UFX6S25VC040210%CHIP1/16W5%00402LFFM_PVPP_HBM_CPU1_EN20%C080516V22UFX6S9.76K1/16W1%CHIP0402LFEMPTY5%50V1000PF04020402LF2KCHIP1%1/16W1/16W0402LF10K1%EMPTYC080522UF20%X6S16VC080516V22UFX6S20% 10%16VX6S1UFC04021%1/16WCHIP0402LF30.1K10%040216VX7R0.022UF10%040225V0.1UFX7RSMLFRS53318LRICX7R10%C040225V0.22UF10K1/16W0402LFCHIP1%CHIP1/16W0.1%11.3K0402LFBSS138KEMPTY0.1%1/16W0402LF26.1KEMPTY0.01UF25V10%X7R0402SMLFIND0.68UH1/16W38.3KCHIP0402LF0.1%50V0402X7R10%680PF1000PF50V5%0402 X7RCHIP5%00402LF1/16W25VX7R0.1UF10%04024VX6S22UFC080520%X6SC080520%4V22UFEMPTYSMSMEMPTYC080522UF4V20%X6S6.3V20%560UFOSCONTHLF
PR1340
PR1314
C2445
2
1 PC1270
2
1 PC1268
2
1 PC1267
21PC1266
G
2
1 PC1265
21
2
1 PC1259
2
1 PC644
PJ66
2
1 PC1269
2
1 PC1264
2
1 PC1261
2
1
PR1339
2
1
PR1338
21
2
1
PJ67
21PL119
2
1
R2583
2
1 PC1262
PC228221
2
1 PC1260
S D
PC1771
PR3336
21
10
19
20
6
5
9
11_18
4
7
8
3
1
2
PU174
R2367
R2380
PU80
R2374
PR2381
SHORT
1 2
SHORT
1 2
1 2
VIN2
CS
MODE
REF
SW
RTN
VCC
AGND
FB
BST
EN
PGND
PGOODVIN1
2
1
2
1
21
2
1
21
2
1
21
21
21
SHEETDATE
DEPARTMENT
SIZE
PROJECT DOCUMENT NUMBER REV
REVIEWER
DESIGNER
123
7 3 2 1 6 5 4
E
A
B
C
E
D
C
B
A
7 6 5 4
D
OUT
IN
IN
PC2002
C2460
C



3RD AL0086260002ND AL54L06100020220804 CHANGE IC TABLE1ST AL053317005IC TABLE6.5*6.9*3.0ISAT=9A@100CPCMC063T-4R7MNDCR=40M OHM20220808 ADD CHANGE LISTPC238 MAIN 680PF2ND 470PF3RD 680PFREMOTE SENSEPLACE AT CHIPSET SIDEUPDATE 20220531 ADD LOCAL SENSE
WORK FREQUENCY=600KHZPDG REV 1.6SLEW RATE=0.4A/USOCP(IMAX*130%)=1AMAX CURRENT=0.52AVOUT=1VTDC=0.52ADC TOLERANCE=+/-0.7%TOTAL TOL=1.03VMAX/0.97VMINPVNN_MAIN_CPU1 SPECIFICATIONCURRENT STEP=0.52A20220808 UPDATE PDG REV 1.6PVNN_MAIN_CPU1RIPPLE=+/-7MV
Fri Aug 25 14:05:10 2023N/AN/AN/AN/AV05300 OF 312PVNN_MAIN_CPU1PVNN_MAIN_CPU1P3V3_AUXSW_P12V_PVCCINFAON_CPU1_FLTP3V3_AUXP3V3_AUX
PVNN_MAIN_CPU10402LF05%CHIP1/16W214 213 2541%PVNN_MAIN_CPU1_MODEPWRGD_PVNN_MAIN_CPU1_RSW_PVNN_MAIN_CPU1_BST_RSMLFX7R0402C080522UF4V20%X6SC080520%4V22UFX6S0402LFCHIP05%05%EMPTY0402LFX7R25V040210%0.01UFC080520%X6S4V22UF5%50V1000PF040220%4V22UFX6SC0805CHIP0.1%0402LF1/16W8.25K040210%680PF50VX7R1/16W10K0402LFCHIP1%CHIP0402LF5%0C0402100NFX7R10%50VIND4.7UHCHIP0402LF12.4K0.1%1/16W05%0402LFCHIPC0402X7R0.22UF10%25V3300PF50V0402X7R10%ICSMLFRS53317LRCHIP0402LF1/16W34.8K1%1UFX6S16V10%C040222UFC080516V20%X6S0402LF1/16W0CHIP5%1%0402LFCHIP1/16W60.4KC04021UF25VX6S10%20%16V22UFX6SC08051/16W0402LFCHIP2KEMPTY5%1000PF50V10K1/16W0402LFEMPTY1%FM_PVNN_MAIN_CPU1_ENPVNN_MAIN_CPU1_FB_RCPWRGD_PVNN_MAIN_CPU1PVNN_MAIN_CPU1_FBSW_PVNN_MAIN_CPU1_SWSW_PVNN_MAIN_CPU1_BSTPVNN_MAIN_CPU1_REFPVNN_MAIN_CPU1_CSPVNN_MAIN_CPU1_VCC
PC1283
PR4272
2
1 PC1207
PC2277
2
1
2
1 PC1284
2
1
2
1
PR2222
2
1 PC1281
PR2220
2
1 PC2222
2
1
21
2
1 PC1286
PC238
2
1 PC1285
21 PR502
PR3338
2
1 PC1280
2
1 PC1287
PC28
2
1
2
1
R2584
21
21PL121
2
1
2
1
PC1282
3
13
11
2
8
9
14
1
12
6
5
4
10
7
C1297
R2385
R2384
PU82
R2387
C1308
1 2SW1
CS
MODE
REF
SW2
PGND1
VCC
AGND
FB
BST
EN
PGND2
PGOODVIN
2
1
21
21
21
2
1
21PR51
SHEETDATE
DEPARTMENT
SIZE
PROJECT DOCUMENT NUMBER REV
REVIEWER
DESIGNER
123
7 3 2 1 6 5 4
E
A
B
C
E
D
C
B
A
7 6 5 4
D
OUT
IN
PR4699
PR2
PR4700
C



7BITS ADDRESS 0X20HSOFT START TIME=6MS.VOUT SLEW RATE: 2V/MSEN<0.95V OFFEN>1.2V ONHOT SWAT CIRCUITFPH=220AOCW=220AOV =14.333VUV =10.091VADDRESS 0X20LATCH OFF MODEOCP=240A20211112 MODIFY FOR GT
JUMPER 1-220211203 CHANGE JP4003 CONNECTFri Aug 25 14:05:12 2023N/A301 OF 312V05N/AN/AN/A
AGND_HSCP3V3_AUXAGND_HSCAGND_HSCP12V_PSU
AGND_HSC
HSC_VDD
AGND_HSCAGND_HSCHSC_VDDP12V_AUXAGND_HSCAGND_HSCAGND_HSCAGND_HSCP12V_AUXAGND_HSCAGND_HSCAGND_HSCAGND_HSCHSC_VDD
HSC MP5990 (1/4)
241305241305301305302303228305183215 305 213302 303302 303302 303245304301305302 303302303302 303302 303302 303306 215305 214 247 259SMB_SML1_PMBUS_HSC_SDACHIPSMB_SML1_PMBUS_HSC_SCLHSC1_BOM125VX6SC04020402LF1/16WCHIPHSC_ENHSC_ONCONN3_210-HP1-030BR10402LF5%IRQ_SML1_PMBUS_ALERT_NHSC_VDD18IRQ_HSC_FAULT_N4.7K16.9KHSC_FLT_TYPEHSC_SSHSC_OCREFCHIP120K1/16W1%1/16W0.001UF1/16W0402LF
PDB_PRSNT_NP12V_PSU_FUSEHSC_ENHSC_ADDRHSC_ON_RHSC_EN_RHSC_CSHSC_MODEHSC_FAULTHSC_IMON
0.1UF25V0402X7R10%1%33K0402LF1/16WICSMLF2N7002K1%0402LFCHIP1/16W1%63.4KTHLFIO01/16W05%
1/16W CHIP82K1%0402LF50VC0402X7R10%100NF1/16WCHIP0C0402CHIP1%33.24.99K1/16WCHIPEMPTY1/16W0.01UF25V1UFCHIP0402LF75K
0CHIP1/16W5%0402LF
ICMP5990GMA-1111-ZSMLFCHIP2K0402LFCHIP6.19KCHIP0402LF1%16VX7RC040210K1%1/16W220.1%CHIP1/16W75KC04020.047UF0402LF2K0.1%0402LF1%
0402LF1/16W31.6K
1/16W0402LF1UFCHIP1UF25V1/16W0.1%1/16WCHIPHSC_VDD_R1/16W0CHIPHSC_VTEMPCHIP0402LF1UFX6S25V0402LF5%1/16W4.7K1%CHIP1/16W 1/16W0402LF0402LFCHIP0402LF1%CHIP0.1%25VX7R1/16WCHIPCHIP0.068UF0402LFCHIP1/16WSMB_SML1_PMBUS_HSC_L_SCLHSC_SCREFHSC1_BOM1HSC1_BOM1HSC1_BOM1HSC1_BOM1HSC1_BOM1HSC1_BOM1HSC1_BOM1HSC1_BOM1HSC1_BOM1HSC1_BOM1HSC1_BOM1HSC1_BOM1HSC1_BOM1HSC1_BOM1HSC1_BOM1HSC1_BOM1HSC1_BOM1HSC1_BOM1HSC1_BOM1HSC1_BOM104021%1/16W1/16WHSC1_BOM10.01UFHSC1_BOM10402LFHSC1_BOM1X7RC0402HSC_VSENSEC0402X7R0402LFX6SC04020.1%50V0.1%4.99K50VHSC_D_OC_R1%HSC_D_OCCHIPHSC_VOSEN22HSC1_BOM1HSC1_BOM10402LFX7R50VHSC1_BOM10402LF1/16WHSC1_BOM1MB0_P12V_STBY_PWRGDHSC1_BOM11/16WSMB_SML1_PMBUS_HSC_R_SDAIRQ_SML1_PMBUS_ALERT00402LF1%5%05%0402LF1K1%0402LFHSC1_BOM1HSC1_BOM10402LF10K1/16WCHIPHSC_VIN_UVW_N1%1K0402LF5%C0402X6S
G
S D
U290
R3909
3
2
1
15
36
35
34
33
32
31
30
29
28
27
249
14
43
42
8
7
6
5
4
3
2
1
45
17
19 16
12
25
11
13
38
22
41
21
39
44
18
40
26
37
2010
23
G
S D
R2587
PR1133PC2193
PR3937
R3934
PR3935
R3933
PR1131
PR3002
R2586
PR3929
R1714
PC2103
PR3930
C2179
R4901
PC2187PC2186
JP4003
PC2192
PC2191
R1117
PC2189
PR3928
R3925
R3924
R2585
R2588
PC2190
PC2188
PR2106
PR2149
R3936
PU289
R3923
R3907
ADDR
VDD18
VDD33_2
VDD33_1
VINSEN
VIN10
FLT_TYPE
GND2
VIN1
VOUT4
VOSEN
VOUT10
VIN9
CS
IMON
VOUT6
SS
SCREF_OCWREF
OCREF
VTEMP
VIN6
VIN5
ON
VOUT8
PG||OCW#
VIN8
MODE
VOUT7VIN7
GOK
ALT#
VOUT9
VOUT5
D_OC
SCL
VIN_UVW#
SDA
GND1
VIN4
VIN3
EN
VIN2
VOUT1
VOUT2
VOUT3
S
G
D
1
2
3
2
1
2
1
2
1
21
21
2
1
2
1
21
21
21
2
1
21
2
1
2
1
2
1
2
1
2
1
2
1
21
2
1
21
21
21
2
1
2
1
21
2
1
2
1
2
1
2
1
2
1
21212121
SHEETDATE
DEPARTMENT
SIZE
PROJECT DOCUMENT NUMBER REV
REVIEWER
DESIGNER
123
7 3 2 1 6 5 4
E
A
B
C
E
D
C
B
A
7 6 5 4
D
OUT
OUT
IN
IN
IN
IN
OUT
OUT
OUT
OUT
OUT
OUT
IN
IN
IN
IN
OUT
BI
OUT
C1797
PR3927
PR3931
PR3932
PR3926
C



HOT SWAT CIRCUITOCP=240AOCW=220AOV =14.333VUV =10.091VADDRESS 0X20SOFT START TIME=6MS.VOUT SLEW RATE: 2V/MSFOR MP5981:DNI PR3919, PR3920, PR3916VOUT SLEW RATE: 2V/MSSOFT START TIME=6MS.DNI PR3917, PR3921, PR3922CHANGE PU288 TO AL005981A00
20211112 MODIFY FOR GTFPH=220ALATCH OFF MODE
FOR MP5981:CHANGE PU287 TO AL005981A00
N/AN/A302 OF 312V05Fri Aug 25 14:05:13 2023N/AN/A
AGND_HSCAGND_HSC
AGND_HSCAGND_HSCHSC_VDDP12V_PSUAGND_HSCHSC_VDDAGND_HSC
P12V_PSU
AGND_HSCP12V_AUXAGND_HSCP12V_AUX
HSC MP5990 (2/4)
HSC_ON5%0402LFHSC1_BOM150VHSC1_BOM1HSC_SCREF120KC04023023011%1/16WCHIP5%HSC1_BOM1HSC1_BOM11UF25V CHIP1/16W0402LFCHIP
302303301301302303302303301301302303303301302303301302303301302303302 303301302 303301301302 303302 303301301302 303302 303301301302 303301302 303302 303301302 3033011/16W1/16WHSC_MODE_2HSC1_BOM10.1%1/16WCHIP0402LFHSC1_BOM104021/16WEMPTY50VCHIPHSC_IMONHSC_CS_2HSC_OCREFHSC_SCREF_2HSC_VDD_R_20402LF0402HSC_IMONHSC_CS_1HSC_OCREFHSC1_BOM10402LFCHIP1/16W0.1%2KHSC1_BOM1HSC1_BOM1X6S1/16WCHIPHSC_SCREF_11NF0.1%0HSC_MODE_10402LF5%CHIP0402LF0402LF1%0402LF5%CHIPHSC_ON1/16W50V0402EMPTY50VHSC1_BOM1HSC1_BOM1HSC1_BOM1HSC1_BOM1HSC1_BOM1HSC1_BOM1HSC1_BOM1HSC1_BOM1HSC1_BOM1HSC1_BOM1
HSC1_BOM1HSC1_BOM1IC1NFEMPTY220PF120K1/16WHSC_SCREFHSC_D_OC_1HSC_FLT_TYPE_1HSC_NC1_1HSC_FAULTHSC_FLT_TYPE_2HSC_NC1_2HSC_VTEMP0402LFCHIPHSC_D_OC_2HSC_VDD_R_1
HSC_SSHSC_D_OC_RHSC_FLT_TYPEHSC_FAULTHSC_SSHSC_FLT_TYPEHSC_D_OC_RHSC_VTEMP25VX6SC04021UF00402LF1/16WCHIP5%0.1%2K2KSMLFMP5991GLU-Z0
00402LF1/16W220PF0402X7R2KSMLFMP5991GLU-ZIC
0402X7R16V0.068UFCHIP1/16W00402LF5%0402LF1/16W CHIP5%016V0402X7R0.068UFCHIP5%00
PC2348
18
32
31
30
29
28
27
26
25
2
1
33
16
15
14
13
12
11
10
9
21
19
17
4
24
7
8
22
5
20
6
3
23
18
32
31
30
29
28
27
26
25
2
1
33
16
15
14
13
12
11
10
9
21
19
17
4
24
7
8
22
5
20
6
3
23
PC2184
PC2185
PC2182
PR1134
PU288
PR3920
PR3922
PU287
PR3914
PR3917
PR3910
PR3912
PR3919
PR3921
PR3918
PR3911
PR3916
PC1525
PC2181
PC2347
PR1101PR3915
PC2183
NC1
FLT_TYPE
SCREF_OCWREF
MODE
VOUT10
VOUT9
VOUT8
VOUT7
VOUT6
VOUT5
VIN9
VIN8
VIN7
VIN6
D_OC
VOUT4
VOUT3
VOUT2
VOUT1
VTEMP
GOK
SS
GND
VDD33
IMON
CS
OCREF
ON
VIN5
VIN4
VIN3
VIN2
VIN1
NC1
FLT_TYPE
SCREF_OCWREF
MODE
VOUT10
VOUT9
VOUT8
VOUT7
VOUT6
VOUT5
VIN9
VIN8
VIN7
VIN6
D_OC
VOUT4
VOUT3
VOUT2
VOUT1
VTEMP
GOK
SS
GND
VDD33
IMON
CS
OCREF
ON
VIN5
VIN4
VIN3
VIN2
VIN1
2
1
2
1
2
1
21
21
21
2
1
21
21
21
21
2
1
2
1
21
2
1
2
1
2
1
2
1
2
1
2
1
2121
SHEETDATE
DEPARTMENT
SIZE
PROJECT DOCUMENT NUMBER REV
REVIEWER
DESIGNER
123
7 3 2 1 6 5 4
E
A
B
C
E
D
C
B
A
7 6 5 4
D
IN
IN
OUT
IN
OUT
OUT
IN
OUT
IN
OUT
IN
OUT
OUT
IN
IN
IN
OUT
IN
C



CHANGE PU296 TO AL005981A00DNI PR3992, PR3993, PR3988ADDRESS 0X20UV =10.091VOCW=220A FPH=220AHOT SWAT CIRCUITOCP=240ASOFT START TIME=6MS.VOUT SLEW RATE: 2V/MSVOUT SLEW RATE: 2V/MSSOFT START TIME=6MS.FOR MP5981:20211116 MODIFY FOR GT
CHANGE PU297 TO AL005981A00DNI PR3994, PR3995, PR3989FOR MP5981:
LATCH OFF MODEOV =14.333V
V05303 OF 312N/AN/AFri Aug 25 14:05:14 2023N/AN/AAGND_HSCAGND_HSCAGND_HSC
AGND_HSCAGND_HSCHSC_VDDP12V_PSUAGND_HSCHSC_VDDP12V_PSU
AGND_HSCP12V_AUXAGND_HSCP12V_AUX
HSC MP5990 (3/4)302 303301301302 303302 303301301302 303301302303302303301301302303301302303301302303302303301301302303301302303302 303301301302 303302 303301302 303301301302 303302 303301
HSC1_BOM10.1%1/16WCHIP0402LFHSC1_BOM1X7R0402HSC1_BOM1HSC1_BOM15%0HSC1_BOM1HSC_D_OC_RHSC_FLT_TYPECHIP5%0402LF1/16WHSC_VTEMPHSC_SS0402LFCHIP1/16W0.1%1/16WHSC_SCREF1/16WHSC_IMONHSC_CS_4HSC_OCREFHSC_ONHSC_SCREF_4HSC_MODE_4HSC_VDD_R_4HSC1_BOM1HSC1_BOM10402
HSC1_BOM1HSC1_BOM1HSC1_BOM1HSC1_BOM1HSC1_BOM1 HSC1_BOM1HSC1_BOM1HSC1_BOM1HSC1_BOM1HSC1_BOM1HSC1_BOM1HSC1_BOM1HSC1_BOM10402LF0402LF1%HSC_NC1_40.068UF16V0402LF0.068UF1/16W0402LF0402LFHSC_OCREFHSC_CS_3HSC_IMON1/16W0.1%2K0402LF00402LF120K25V0402LF0402LF1/16WC0402HSC_VDD_R_31%CHIPHSC_SCREF1/16W
EMPTYEMPTYCHIP5%CHIP120K5%CHIPC04021UF25VX6SHSC_ONHSC_MODE_3HSC_SCREF_3HSC_D_OC_4HSC_FLT_TYPE_4HSC_FAULTHSC_SSHSC_NC1_3HSC_D_OC_3HSC_FLT_TYPE_3HSC_FAULTHSC_VTEMPHSC_FLT_TYPEHSC_D_OC_R
220PF040250V1/16W0402LF050V1NF2K2K0MP5991GLU-ZICSMLFX6S1UFCHIP5%0220PFEMPTY50V04021NFEMPTY040250V0402LFCHIP1/16WCHIP5%CHIP2K1/16W0.1%MP5991GLU-ZICSMLF
01/16W CHIPX7R040216V0CHIP5%1/16W5%CHIP0
18
32
31
30
29
28
27
26
25
2
1
33
16
15
14
13
12
11
10
9
21
19
17
4
24
7
8
22
5
20
6
3
23
18
32
31
30
29
28
27
26
25
2
1
33
16
15
14
13
12
11
10
9
21
19
17
4
24
7
8
22
5
20
6
3
23
PC2226
PR3988
PR3984
PR3981
PC2225
PR3982
PC2224
PC3272
PC2227
PR3992
PR3994
PR3986
PC2223
PR3993
PR3995
PR3990
PR3980
PR3989
PR3991PR3987
NC1
FLT_TYPE
SCREF_OCWREF
MODE
VOUT10
VOUT9
VOUT8
VOUT7
VOUT6
VOUT5
VIN9
VIN8
VIN7
VIN6
D_OC
VOUT4
VOUT3
VOUT2
VOUT1
VTEMP
GOK
SS
GND
VDD33
IMON
CS
OCREF
ON
VIN5
VIN4
VIN3
VIN2
VIN1
NC1
FLT_TYPE
SCREF_OCWREF
MODE
VOUT10
VOUT9
VOUT8
VOUT7
VOUT6
VOUT5
VIN9
VIN8
VIN7
VIN6
D_OC
VOUT4
VOUT3
VOUT2
VOUT1
VTEMP
GOK
SS
GND
VDD33
IMON
CS
OCREF
ON
VIN5
VIN4
VIN3
VIN2
VIN1
2
1
21
21
2
1
21
2
1
2
1
2
1
2
1
21
21
2
1
2
1
21
21
2
1
21
2
1
2
1
2
1
21 21
PC2350
PC2349
SHEETDATE
DEPARTMENT
SIZE
PROJECT DOCUMENT NUMBER REV
REVIEWER
DESIGNER
123
7 3 2 1 6 5 4
E
A
B
C
E
D
C
B
A
7 6 5 4
D
IN
IN
OUT
IN
OUT
OUT
IN
OUT
IN
OUT
OUT
IN
OUT
IN
IN
IN
OUT
IN
C
PU296
PU297



OV =14.333VOCW=220AOCP=240AUV =10.091VLATCH OFF MODEHOT SWAT CIRCUIT20220308 MODIFY FOR GTFPH=220AAT 4.5V, ID=300ARDS(ON)=0.76M OHM20211208 ADD FS1
Fri Aug 25 14:05:16 2023V05304 OF 312N/AN/AN/AN/A
P12V_PSU
P12V_AUX
P12V_MAIN_R_0P12V_MAIN_R
HSC MODULE(1/4)
304304304304304304304304305305304304 305305304 305304304304304304305304304305304305304 305304304304304304304304305
301304P12V_HSC_SENSE2_R4_NP12V_HSC_GATE_G1P12V_HSC_GATE_G2P12V_HSC_GATE_G3HSC1_BOM2P12V_HSC_GATE_G4HSC1_BOM2P12V_HSC_GATE_G5P12V_HSC_GATE_G6P12V_HSC_SENSE2_R3_NHSC1_BOM24WICHSC1_BOM2HSC1_BOM2HSC1_BOM2P12V_HSC_SENSE2_R4_PHSC1_BOM2P12V_HSC_SENSE2_R2_NEMPTY1/16WHSC1_BOM2HSC1_BOM2HSC1_BOM2HSC1_BOM2HSC1_BOM2HSC1_BOM2HSC1_BOM2HSC1_BOM2HSC1_BOM2HSC1_BOM2HSC1_BOM2HSC1_BOM2HSC1_BOM2HSC1_BOM2HSC1_BOM2HSC1_BOM2HSC1_BOM2HSC1_BOM2HSC1_BOM2HSC1_BOM2HSC1_BOM2HSC1_BOM2HSC1_BOM2HSC1_BOM2HSC1_BOM2HSC1_BOM2HSC1_BOM2HSC1_BOM2HSC1_BOM2HSC1_BOM2PSMNR58-30YLHSMLFEMPTY0402LFEMPTY1/16W1%10SMLFEMPTYPSMNR58-30YLH0402LF10EMPTY1%1/16W0402LF1%1/16W10EMPTYSMLFEMPTYPSMNR58-30YLH11%EMPTY11%EMPTY11%EMPTY11%EMPTY1%10EMPTY10 1%EMPTY1%10EMPTY1%10EMPTY10 1%EMPTY100EMPTY1%11%EMPTY11%EMPTY11%EMPTY1%EMPTY110 1%EMPTY10 1%EMPTY1%10EMPTY10 1%EMPTY0402LFEMPTY1%1/16W100402LF1%101/16W0402LF1%10EMPTYEMPTYSMLFPSMNR58-30YLH1/16WEMPTY0402LF1%104W1%EMPTYSMLF0.00031%EMPTYSMLF0.00031%4W0.0003SMLFEMPTYEMPTYSMLF0.0031%3W1%4W0.0003EMPTYSMLFEMPTYPSMNR58-30YLHSMLFPSMNR58-30YLHEMPTYSMLFSMLFEMPTYPSMNR58-30YLHP12V_HSC_SENSE2_R3_PP12V_HSC_SENSE2_R4_NSMLF5.0SMDJ14AP12V_HSC_SENSE2_R1_PSMLF5.0SMDJ14ASMLFP12V_HSC_SENSE1_PP12V_HSC_GATE1P12V_HSC_SENSE2_R4_PP12V_HSC_SENSE1_NP12V_HSC_ADC_NP12V_HSC_SENSE1_PP12V_HSC_SENSE2_R4_PP12V_HSC_SENSE2_R3_PP12V_HSC_SENSE2_R2_PP12V_HSC_SENSE2_R1_PP12V_HSC_SENSE2_R1_NP12V_HSC_SENSE2_NP12V_HSC_SENSE2_R1_NP12V_HSC_SENSE2_R1_PP12V_HSC_SENSE2_PP12V_HSC_SENSE2_R4_NP12V_HSC_ADC_PP12V_HSC_SENSE1_NP12V_HSC_SENSE2_R2_NP12V_HSC_SENSE2_R2_PP12V_HSC_SENSE2_R3_PP12V_HSC_SENSE2_R1_NP12V_HSC_SENSE2_R2_NP12V_HSC_SENSE2_R3_NP12V_HSC_SENSE2_R3_N
MB0_CM_GATE_G0P12V_HSC_GATE2
P12V_PSU_FUSE
P12V_HSC_GATE_RC
ICIC
C040225V10%EMPTY33NF040210%1NF50VEMPTY0402LF10EMPTY1%1/16WSS15P3S-M3/86AICSMLF
20A/125VP12V_HSC_SENSE2_R2_P
21
43
Anode_2CathodeAnode_1
PR2514
PR2519
21
2B
2A
1B
1A
4
44
2B
2A
1B
1A
43
53215321K215321
2 1CACA
21PR2525
21PR2524
PR2526
PR2527
21PR2511
21PR2510
PR2512
PR2513
21PR2516
21PR2515
PR2518
PR2517
21PR2520
21PR2521
PR2523
PR2522
PR4
2B
2A
1B
1A
PR2532
PPQ9
PPQ2
PD17
PPQ1
PR2533
PR2534
PPQ8
PR2536PR2535PR2531
FS1
PD16PD15
PPQ7PPQ6
PR2530PR2529
PPQ5
PR2528
1A 2A
1B 2B
1A 2A
1B 2B
D1
G1
S3 S2 S1
4
D1
G1
S3 S2 S1
4
D1
G1
S3 S2 S1
4
1A 2A
1B 2B
1A 2A
1B 2B
D1
G1
S3 S2 S1
4
D1
G1
S3 S2 S1
4
D1
G1
S3 S2 S1
4
D1
G1
S3 S2 S1
4
1253125312531253 2 1CACA125312531253
21
21
21
21
21
21
21
21
21
21
2
1
2
1PR2537
2
1PC1751
2
1
2
1
2
1
2B2A1B1A
4444
5321532153215321
PR3
SHEETDATE
DEPARTMENT
SIZE
PROJECT DOCUMENT NUMBER REV
REVIEWER
DESIGNER
123
7 3 2 1 6 5 4
E
A
B
C
E
D
C
B
A
7 6 5 4
D
OUT
OUT
OUT
IN
OUT
OUT
OUT
OUT
OUTOUT
OUT
OUT
IN
IN
OUT
IN
IN
IN
IN
IN
IN
OUT
IN
IN
IN
IN
IN
OUT
IN
IN
IN
IN
IN
OUT
IN PR2538
PC1750
C



LTC4282=1.0VLTC4287=1.5V2ND SOURCE:AL000788001 (G788P81U(MSOP8))MAIN SOURCE:AL007718001 (NCT7718W(MSOP))U345U365 CLOSE TO MOSFETFri Aug 25 14:05:17 2023N/AN/AN/AN/AV05305 OF 312
P12V_AUXP3V3_AUXP3V3_AUXP3V3_AUXP12V_PSUP3V3_AUX
HSC MODULE(2/4)
304213304304304304241301301170233251213233251 170301213241301301214247259306251304304304228301183215EMPTYSMLFP12V_HSC_SENSE1_PP12V_PSUP12V_HSC_T_CRIT_R_NP12V_HSC_T_CRIT_N
SMLFEMPTYNCT7718WSMLF49.91%0402LF EMPTY060310.5K1/16W1%0402LFEMPTY5%00402LF00402LF1/16W5%00402LF5%01/16WEMPTY0402P12V_HSC_GATE1P12V_HSC_SENSE2_NP12V_HSC_SENSE2_PP12V_HSC_SENSE1_NSMB_SML1_PMBUS_HSC_SCLEMPTY10%HSC_EN25V0.1UF1%SMB_LM75_0_3V3AUX_SCL10.5KEMPTY5%1/16W0402LFEMPTY10%50VEMPTY1/16WP12V_HSC_TEMP_RHSC1_BOM2HSC1_BOM2HSC1_BOM2HSC1_BOM2HSC1_BOM2HSC1_BOM20402LF49.91000PFHSC1_BOM2P12V_HSC_TEMP_SDAP12V_HSC_TEMP_ALERT_R_NSMB_LM75_0_3V3AUX_SDAEMPTY1/16WP12V_HSC_TEMP_ALERT_NP12V_HSC_TEMP_D+HSC1_BOM2P12V_HSC_TEMP_SCLHSC1_BOM2HSC1_BOM2EMPTY0402LFEMPTY1/16WEMPTYHSC1_BOM2EMPTYHSC1_BOM210%0.1UF25V04021/16W1%P12V_HSC_TEMP_D-IRQ_HSC_FAULT_NSMB_SML1_PMBUS_HSC_SDAHSC1_BOM2MB0_P12V_STBY_PWRGDHSC_CSOUTHSC_TYPE_ADCSCONN21_91930-31121LFP12V_HSC_ADC_PP12V_HSC_ADC_NHSC1_BOM2MMBT3904P12V_HSC_TEMP_EP12V_HSC_GATE2P12V_AUX0CHIP0CHIPIOTHLFCONN3_210-HP1-030BR1SMB_SML1_PMBUS_HSC_MODULE_SCLSMB_SML1_PMBUS_HSC_MODULE_SDAIRQ_SML1_PMBUS_ALERT_N
C2459
R4895
R4894
R4896
R4685
R4684
R4892
R4893
3
2
1
B
G2
G1
21
20
19
18
17
16
15
14
13
12
11
10
9
8
7
6
5
4
3
2
1
1
4
7
8
5
3
2
6
C2458
CE
JP10
U365
PJ42
R4695
R4696
U345
1
2
3
1
21
20
19
18
17
16
15
14
13
12
11
10
9
8
7
6
G2
G1
2
5
4
3
1
SCL
SDA
ALERT#
GNDT_CRIT#
D-
D+
VDD
32
2
1
21 21
2
1
2
1
R4686
21
2
1
21
21
21
21
21
2
1
SHEETDATE
DEPARTMENT
SIZE
PROJECT DOCUMENT NUMBER REV
REVIEWER
DESIGNER
123
7 3 2 1 6 5 4
E
A
B
C
E
D
C
B
A
7 6 5 4
D
ININ
ININ
IN
OUTIN
OUT
OUTINOUT
BI
OUTOUT
OUT
IN
BI
OUT
IN
OUT
PC1789
C



20210705 MODIFY FOR GTPROCHOT20220811 ADD CO-LAY DESIGNOC DETECT ON MODULE
Fri Aug 25 14:05:25 2023N/AN/AN/AN/AV05306 OF 312
SMLFLM4040AIM3X-2.5/NOPBU206_VDD10%25VX7RP12V_AUX1K1%1/16WC0402C0402EMPTYI38P3V3_AUXP12V_AUXP12V_AUXP3V3_AUXP3V3_AUXP3V3_AUXP3V3_AUXP3V3_AUXP3V3_AUX
P12V_AUXP12V_AUXHSC MODULE(3/4)
305306307215306301215305306306
307 215244 307182214
HSC_CSOUTEMPTYAP331AWG-7HSC_D_OC_R2SMLFLT6700CS6-1#TRPBFIC0402LF25VC0402EMPTY10%50V100NFX6SA_P12V_STBY_ADR_TRIGGER1/16WCHIPSMLFNC_U205_INB-A_P12V_STBY_FP_TRIGGER04020402LFFM_UV_ADR_TRIGGER_NBSS138KBSS138K0402LFCHIP1/16W5%4.7KIC0402LF0402LF10KCHIP1/16W1%CHIP1/16W1%10K0402LF10%C0402CHIP0.1UF1UFCHIP1/16W1%26.7K0402LFCHIP26.7K1%1/16W1%1K0402LFCHIP1%1K1/16WSMLF0A_HSC_HIGH
EMPTY0402LFTPS3700DDCREMPTYA_HSC_INAP10%0402PWRGD_DSW_PWROK_R4100NFEMPTY0402LF1/16W10KU369_VDDEMPTY1/16W1%1K0402LF5%
1KU205_VDD1/16W1%NC_U205_OUTB
25VEMPTY
EMPTY0402LFEMPTY1/16W1%
EMPTYA_HSC_LOW_DRAIN
1%1/16W50V10%50V1/16W10KEMPTY1/16W1%160K0402LFOC_P2V5_COMP33.21%10K1/16W1%EMPTY1/16W1M1%0402LFEMPTY10K1%10KHSC_OC_VOLA_HSC_LOW_GATEEMPTY2N7002KSMLF5%00402LF1/16W1%1/16WEMPTY0402LF01/16WEMPTY0402LF5%EMPTY10K1%0402LFEMPTY1%EMPTY1/16W1%1%160K1/16W0402LFEMPTY1%10KHSC_D_OCHSC_CSOUTEMPTY0402LF
5%01%4.99KA_P12V_STBY_FPH_GATE
1/16WA_HSC_LOW0402LFEMPTY
1/16WEMPTY0402LF
1UF100NF10%EMPTYEMPTY
0402LF1/16W0402LF160K0402LF0402LFEMPTY1/16WHSC1_BOM2A_HSC_LOW_GATE
IRQ_UV_DETECT_NPWRGD_DSW_PWROK0402LFEMPTY10%C040225V0.1UFEMPTYSMLFTPS3700DDCREMPTY25V1UF25V0.1UFC0402EMPTY10%1/16W100K
040210%
G
S D
OUTPUT
IN-
IN+
GND VCC
R4793
C2388
R4620
R2238
G
S D
5
6
1
4
3
2
4
1
3
3
2
1
G
5
6
1
4
3
2
5
6
1
4
3
2
52S D
R4806
U206
R2227
R2219
R4805
R4804
U344
U343
R4672R4671
U329
2
1
R2233
2
1
R2230
U325
R2330
U369
2
1
R2221
2
1
R2222
2
1
R2236
U205
+
-
3
2-
1+
OUTB
INA+ OUTA
GND
INB-
VDD
S
G
D
OUTB
INA+ OUTA
GND
INB-
VDD
OUTB
INA+ OUTA
GND
INB-
VS
1
2
1
2
1
2
1
2
2
1
2
1
2
1
2
1
2
1
2
1
2
1
2
1
2
1
2
1
2
1 C2389
21
2
1 C2390
21
2
1
2
1
2
1
2
1
2
1
2
1
2
1
21
2
1
2
1
R4670
2
1
2
1
R4668
2
1
R4667
SHEETDATE
DEPARTMENT
SIZE
PROJECT DOCUMENT NUMBER REV
REVIEWER
DESIGNER
123
7 3 2 1 6 5 4
E
A
B
C
E
D
C
B
A
7 6 5 4
D
IN
IN
OUT
OUT
OUT
OUT
OUT
IN
C1561
C2392
C2394
C2393C4562
C1562
R4797R4795
R4796
R4794
R4792
R4652
R4673
R4693
R4669
C



20220811 ADD CO-LAY DESIGN
Fri Aug 25 14:05:27 2023N/AN/AN/AN/AV05307 OF 312P12V_AUXP12V_AUXP12V_AUXP3V3_AUXP12V_AUX
P3V3_AUXP3V3_AUXP12V_AUXP3V3_AUX
P3V3_AUXP3V3_AUXP12V_AUXHSC MODULE(4/4)
306 215306 215244 306182214P12V_AUX_UV_TRIGGERUV_P2V5_COMP10%0402LF100NF50V10%50V100NFEMPTY10%EMPTY5.11KEMPTYAP331AWG-7LM4040AIM3X-2.5/NOPB0402LFEMPTYEMPTYEMPTY10K0402LF1/16W1%33.21%EMPTYSMLFAP331AWG-750V100NFC0402EMPTY1/16W1%5.11K0402LFEMPTY0402LF1/16W1%17.8KEMPTYLM4040AIM3X-2.5/NOPBSMLFEMPTY0402LF1/16W10K1%EMPTY10K0402LF1/16W1%33.21%EMPTY10%100NFC040250VSMLF0402LF1%1/16WEMPTY17.8K1%1/16W0402LF1/16W1%10KSMLFP12V_AUX_UV_ADR_TRIGGERUV_ADR_P2V5_COMPCHIPIRQ_UV_DETECT_R2_NC0402FM_UV_ADR_TRIGGER_N_R2C0402EMPTYPWRGD_DSW_PWROK_TRIGGERLM4040AIM3X-2.5/NOPBC04021%1/16W0402LF10%EMPTY EMPTY1M0402LFEMPTYC0402C04021/16WEMPTY100NF10%EMPTYPWRGD_DSW_PWROK_R5AP331AWG-7
10%
DSW_PWROK_P2V5_COMP1%1/16W100NF50V10%0402LF1/16WEMPTY
1%CHIP1M1/16WFM_UV_ADR_TRIGGER_N10%EMPTY
50V100NF0402LF1%IRQ_UV_DETECT_N100NF50V50V100NF
PWRGD_DSW_PWROK1%1/16W0402LF10KEMPTY1%33.250VEMPTYSMLF2KEMPTY10K1%1/16WEMPTY4.75KC0402EMPTY0402LFSMLF1% 1MC0402EMPTY
OUTPUT
IN-
IN+
OUTPUT
IN-
IN+
OUTPUT
IN-
IN+
GND VCC GND VCCGND VCC
R4791
R4787
R4777
R4776 R4779
R4774 R4778
R4775 C2379
3
2
1
4
1
3
3
2
1
4
1
3
4
1
3
3
2
1
52 52 52
U341
U342
U338
U340
U339
U337
3
2-
1+
+
-
3
2-
1+
3
2-
1+
+
-
+
-
2
1
2
1
2
1
2
1
C2385
2
1 C2386
2
1 C2387
21R4788
2
121
2
1
2
1
2
1
2
1 C2380
2
1 C2382
21
2
1 C2384
21R4783
2
1
2
1
2
1
2
1 C2381
2
1 C2383
21
21
2
1
2
1
2
1
SHEETDATE
DEPARTMENT
SIZE
PROJECT DOCUMENT NUMBER REV
REVIEWER
DESIGNER
123
7 3 2 1 6 5 4
E
A
B
C
E
D
C
B
A
7 6 5 4
D
OUT
OUT
OUT
R4790R4786 R4789
R4773 R4785
R4772
R4782
R4784
C



10 INCH5 INCH
Fri Aug 25 14:05:28 2023V05308 OF 312N/AN/AN/AN/ADELTA_L_GND_1DELTA_L_GND_1DELTA_L_GND_1DELTA_L_GND_1DELTA_L_GND_1DELTA_L_GND_1DELTA_L_GND_1DELTA_L_GND_1
DELTA_L_GND_1DELTA_L_GND_1DELTA_L_GND_1DELTA_L_GND_1DELTA_L_GND_1DELTA_L_GND_1DELTA_L_GND_1DELTA_L_GND_1DELTA_L_GND_1DELTA_L_GND_1DELTA_L_GND_1DELTA_L_GND_1DELTA_L_GND_1DELTA_L_GND_1DELTA_L_GND_1DELTA_L_GND_1DELTA_L_GND_1DELTA_L_GND_1
DELTA_L_GND_1DELTA_L_GND_1DELTA_L_GND_1DELTA_L_GND_1DELTA_L_GND_1DELTA_L_GND_1
DELTA LDELTA_L_85_5INCH_IN6_DPDELTA_L_85_5INCH_IN6_DNDELTA_L_85_5INCH_IN5_DPDELTA_L_85_5INCH_IN5_DNDELTA_L_85_5INCH_IN4_DPDELTA_L_85_5INCH_IN4_DNDELTA_L_85_5INCH_IN3_DPDELTA_L_85_5INCH_IN3_DNDELTA_L_85_5INCH_IN2_DPDELTA_L_85_5INCH_IN2_DNDELTA_L_85_5INCH_IN1_DPDELTA_L_85_5INCH_IN1_DNDELTA_L_85_5INCH_BOT_DPDELTA_L_85_5INCH_BOT_DNDELTA_L_85_5INCH_TOP_DNDELTA_L_85_5INCH_TOP_DP
DELTA_L_85_10INCH_IN5_DPDELTA_L_85_10INCH_IN5_DNDELTA_L_85_10INCH_IN6_DPDELTA_L_85_10INCH_IN6_DNDELTA_L_85_10INCH_IN3_DPDELTA_L_85_10INCH_IN3_DNDELTA_L_85_10INCH_IN4_DPDELTA_L_85_10INCH_IN4_DNDELTA_L_85_10INCH_BOT_DPDELTA_L_85_10INCH_BOT_DNDELTA_L_85_10INCH_IN1_DPDELTA_L_85_10INCH_IN1_DNDELTA_L_85_10INCH_IN2_DPDELTA_L_85_10INCH_IN2_DNDELTA_L_85_10INCH_TOP_DNDELTA_L_85_10INCH_TOP_DP
DELTA-L 4.0SMLFEMPTYDELTA-L 4.0EMPTYSMLFEMPTYSMLFDELTA-L 4.0EMPTYSMLFDELTA-L 4.0DELTA-L 4.0EMPTYSMLFDELTA-L 4.0SMLFEMPTYDELTA-L 4.0EMPTYSMLFSMLFDELTA-L 4.0EMPTYDELTA-L 4.0SMLFEMPTYDELTA-L 4.0SMLFEMPTY
EMPTYSMLFDELTA-L 4.0SMLFDELTA-L 4.0EMPTYEMPTYSMLFDELTA-L 4.0SMLFDELTA-L 4.0EMPTYSMLFEMPTYDELTA-L 4.0DELTA-L 4.0SMLFEMPTY
DELTA-L 4.0SMLFEMPTYDELTA-L 4.0EMPTYSMLFEMPTYSMLFDELTA-L 4.0EMPTYSMLFDELTA-L 4.0SMLFDELTA-L 4.0EMPTYSMLFDELTA-L 4.0EMPTYDELTA-L 4.0SMLFEMPTYSMLFDELTA-L 4.0EMPTYDELTA-L 4.0SMLFEMPTYSMLFDELTA-L 4.0EMPTY
DELTA-L 4.0SMLFEMPTYEMPTYSMLFDELTA-L 4.0EMPTYSMLFDELTA-L 4.0DELTA-L 4.0SMLFEMPTYDELTA-L 4.0SMLFEMPTYDELTA-L 4.0EMPTYSMLF
32
1
32
1
32
1
3 2
1
3 2
1
3 2
1
3 2
1
32
1
32
1
32
1
3 2
1
3 2
1
3 2
1
32
1
32
1
3 2
1
3 2
1
32
1
32
1
32
1
3 2
1
3 2
1
3 2
1
32
1
32
1
3 2
1
32
1
32
1
32
1
3 2
1
3 2
1
3 2
1
J76
J77
J79
J119
J63
J64
J65
J114
J115
J75
J78
J80
J118
J66
J67
J68
1_P
3_G 2_N
1_P
3_G2_N
1_P
3_G2_N
1_P
3_G2_N
1_P
3_G2_N
1_P
3_G2_N
1_P
3_G2_N
1_P
3_G2_N
1_P
3_G 2_N
1_P
3_G 2_N
1_P
3_G2_N
1_P
3_G 2_N
1_P
3_G 2_N
1_P
3_G 2_N
1_P
3_G 2_N
1_P
3_G 2_N
1_P
3_G2_N
1_P
3_G2_N
1_P
3_G 2_N
1_P
3_G 2_N 1_P
3_G 2_N
1_P
3_G2_N
1_P
3_G2_N
1_P
3_G2_N
1_P
3_G2_N
1_P
3_G2_N
1_P
3_G2_N
1_P
3_G 2_N
1_P
3_G 2_N
1_P
3_G 2_N
1_P
3_G 2_N
1_P
3_G 2_N
J81J83J85J69J71J73J116J117
J82J84J86J120J121
J70J72J74
SHEETDATE
DEPARTMENT
SIZE
PROJECT DOCUMENT NUMBER REV
REVIEWER
DESIGNER
123
7 3 2 1 6 5 4
E
A
B
C
E
D
C
B
A
7 6 5 4
D
C



40 OHM 50 OHM100 OHM85 OHM
309 OF 312V05N/AN/AN/AFri Aug 25 14:05:30 2023N/AT1_GND
T1_GNDT1_GNDT1_GNDT1_GNDT1_GNDT1_GNDT1_GNDT1_GNDT1_GNDT1_GNDT1_GNDT1_GNDT1_GNDT1_GNDT1_GNDT1_GNDT1_GNDT1_GNDT1_GNDT1_GNDT1_GNDT1_GNDT1_GNDT1_GNDT1_GNDT1_GNDT1_GNDT1_GNDT1_GNDT1_GND T1_GNDT1_GND T1_GNDT1_GNDT1_GNDT1_GNDT1_GNDT1_GNDT1_GNDT1_GNDT1_GNDT1_GNDT1_GND
T1_GNDT1_GNDT1_GNDT1_GND
TDREMPTY
TDR_SE_40_OHM_IN3TDR_SE_50_OHM_IN4EMPTYTDR_SE_50_OHM_IN1TDR_SE_50_OHM_IN3TP_TDR_4P_DIPTH2TH2TP_TDR_4P_DIPTHTP_TDR_4P_DIPTP_TDR_4P_DIPTP_TDR_4P_DIPTDR_DIFF_100_IN5_DPTDR_DIFF_85_IN5_DN
TH2TDR_SE_50_OHM_IN2TP_TDR_4P_DIPTDR_DIFF_85_IN4_DPTDR_SE_50_OHM_IN6EMPTYTHTP_TDR_4P_DIPTDR_SE_40_OHM_IN6TP_TDR_4P_DIPEMPTYTDR_DIFF_85_IN4_DNEMPTYTHTP_TDR_4P_DIPTDR_DIFF_85_IN2_DNTDR_DIFF_85_IN2_DPTDR_DIFF_85_IN1_DNTDR_DIFF_85_IN1_DPTDR_DIFF_85_TOP_DNTP_TDR_4P_DIPTP_TDR_4P_DIP
THTDR_SE_50_OHM_IN5TH2TDR_DIFF_85_IN5_DPTDR_DIFF_100_IN6_DPTDR_DIFF_100_IN6_DNTDR_DIFF_100_IN5_DNTDR_DIFF_100_BOT_DPTDR_DIFF_100_BOT_DNEMPTYTP_TDR_4P_DIPTHEMPTYTHTP_TDR_4P_DIPTDR_DIFF_100_IN3_DNTDR_DIFF_100_IN3_DPTDR_DIFF_100_IN4_DNTDR_DIFF_100_IN4_DPEMPTYTHEMPTYEMPTYTHTP_TDR_4P_DIPTHTP_TDR_4P_DIPTP_TDR_4P_DIPTHEMPTYTP_TDR_4P_DIPTHEMPTYTP_TDR_4P_DIPTHEMPTYTHTP_TDR_4P_DIPEMPTYTHEMPTY
TDR_DIFF_85_BOT_DNTDR_DIFF_85_BOT_DPEMPTYTP_TDR_4P_DIPTHTP_TDR_4P_DIPTHTDR_DIFF_85_IN6_DNTDR_DIFF_85_IN6_DPTP_TDR_4P_DIPTDR_SE_40_OHM_IN5EMPTYTHTP_TDR_4P_DIPTHEMPTYTP_TDR_4P_DIPTHEMPTYTDR_DIFF_85_IN3_DNTDR_DIFF_85_IN3_DPEMPTYTP_TDR_4P_DIPTHTHEMPTY
TDR_DIFF_100_TOP_DNTDR_DIFF_100_TOP_DPTDR_DIFF_100_IN1_DNTDR_DIFF_100_IN1_DPTDR_DIFF_100_IN2_DNTDR_DIFF_100_IN2_DPTDR_DIFF_85_TOP_DPTDR_SE_50_OHM_TOP
TDR_SE_50_OHM_BOT
TDR_SE_40_OHM_TOPTDR_SE_40_OHM_IN1TDR_SE_40_OHM_IN2TDR_SE_40_OHM_IN4TDR_SE_40_OHM_BOT
EMPTYTHTP_TDR_4P_DIPEMPTYTHEMPTYTP_TDR_4P_DIPTHTP_TDR_4P_DIPEMPTYTHEMPTYTHTHTP_TDR_4P_DIPEMPTYTP_TDR_4P_DIPTHEMPTYEMPTYTP_TDR_4P_DIPEMPTYTHTHTP_TDR_4P_DIPEMPTYTHEMPTYTHTH2TH2TH2TH2TH2TH2TH2
TH2TH2TH2TH2TH2
4
1
3
2
4
1
3
2
4
1
3
2
4
1
3
2
4
1
3
2
4
1
3
2
4
1
3
2
4
1
3
2
3
2
1
3
2
1
3
2
1
3
2
1
3
2
1
3
2
1
3
2
1
3
2
1
3
2
1
3
2
1
3
2
1
3
2
1
3
2
1
3
2
1
3
2
1
3
2
1
4
1
3
2 4
1
3
2 4
1
3
2 4
1
3
2
4
1
3
2
4
1
3
2
4
1
3
2
4
1
3
2
4
1
3
2
4
1
3
2
4
1
3
2
4
1
3
2
4
1
3
2
4
1
3
2
4
1
3
2
4
1
3
2
4
1
3
2
4
1
3
2
4
1
3
2
4
1
3
2
4
1
3
2
4
1
3
2
4
1
3
2
4
1
3
2
TDR
TDR
TDR
TDR
TDR
TDR
TDR
TDR
TDR
TDR
TDR
TDR
TDR
TDR
TDR
TDR
X30
X29
X32
X31
X26
X25
X28
X27
X6 X12 X18 X24
X5
X4
X3
X11
X10
X9
X2
X1
X8
X7
X17
X16
X15
X14
X13
X23
X21
X22
X20
X19
S1
P2S2
P1
S1
P2S2
P1
S1
P2 S2
P1
S1
P2S2
P1
S1
P2 S2
P1
S1
P2S2
P1
S1
P2S2
P1
S1
P2 S2
P1
S1
P2 S2
P1
S1
P2 S2
P1
S1
P2S2
P1
S1
P2S2
P1
S1
P2S2
P1
S1
P2 S2
P1
S1
P2S2
P1
S1
P2 S2
P1
S1
P2S2
P1
S1
P2S2
P1
S1
P2 S2
P1
S1
P2 S2
P1
S1
P2 S2
P1
S1
P2 S2
P1
S1
P2 S2
P1
S1
P2 S2
P1
S1
P2S2
P1
S1
P2S2
P1
S1
P2 S2
P1
S1
P2 S2
P1
S1
P2 S2
P1
S1
P2S2
P1
S1
P2S2
P1
S1
P2S2
P1
SHEETDATE
DEPARTMENT
SIZE
PROJECT DOCUMENT NUMBER REV
REVIEWER
DESIGNER
DB13
DB16
DB15
DB14
DB6
DB5
DB4
DB3
DB2
DB1
DB12
DB11
DB10
DB9
DB8
DB7
123
7 3 2 1 6 5 4
E
A
B
C
E
D
C
B
A
7 6 5 4
D
C



20230204 DEL X40,X48,X41,X3320230116 ADD TDR FOR NECKNECK 85 OHM
Fri Aug 25 14:05:31 2023N/AN/AN/AN/AV05310 OF 312T1_GNDT1_GNDT1_GNDT1_GNDT1_GNDT1_GNDT1_GNDT1_GNDT1_GNDT1_GNDT1_GNDT1_GND
TDREMPTYTHTP_TDR_4P_DIPTP_TDR_4P_DIPEMPTYTHTP_TDR_4P_DIPTHEMPTYEMPTYTHTP_TDR_4P_DIPTHEMPTYTP_TDR_4P_DIPEMPTYTHTP_TDR_4P_DIPTP_TDR_4P_DIPTHEMPTYTP_TDR_4P_DIPTHEMPTYTP_TDR_4P_DIPTHEMPTYTP_TDR_4P_DIPTHEMPTYTHEMPTYTP_TDR_4P_DIPEMPTYTHTP_TDR_4P_DIP
4
1
3
2
4
1
3
2
4
1
3
2
4
1
3
2
4
1
3
2 4
1
3
2
4
1
3
2
4
1
3
2
4
1
3
2
4
1
3
2
4
1
3
24
1
3
2
X33
X34
X35
X36
X37
X38
S1
P2S2
P1
S1
P2 S2
P1
S1
P2 S2
P1
S1
P2S2
P1
S1
P2 S2
P1
S1
P2S2
P1
S1
P2S2
P1
S1
P2 S2
P1
S1
P2 S2
P1
S1
P2 S2
P1
S1
P2S2
P1
S1
P2S2
P1
X39X40X41X42X43X44
SHEETDATE
DEPARTMENT
SIZE
PROJECT DOCUMENT NUMBER REV
REVIEWER
DESIGNER
123
7 3 2 1 6 5 4
E
A
B
C
E
D
C
B
A
7 6 5 4
D
C



HOLE_D3-1NHOLE78 (PCH HEATSINK HOLE)GND_HOLE514(STD)HOLE1248 (M.2 LATCH HOLE)HOLE_C4-5D3-8B8I5-6_RO6-6_NPT_RBHOLE_OB6-4X8OBD3-2X4-8B6-4X8N_RO6X7-6_NPM
HOLE_D10NHOLE300 (CPU HS HOLE)HOLE1079 (CPU SOCKET HOLE)GND_HOLE140 (HANDLE)HOLE_DUMMY50HOLE_C8D4-2B8_NPMMODULE HOLEG_HOLE_C8D3-2B8I5_RO6_NPBHOLE1199(MOS HS)GND_C8D4B8HOLE_D3-429N
GND_C10_D4GND_HOLE149TOOLING HOLEHOLE1247(M.2)HOLE39(GUIDE PIN)HOLE_R4-2X5D2B4_IX0-1T_NPM_RBHOLE1187 (E1S SCREW HOLE)Fri Aug 25 14:05:32 2023N/AN/A V05311 OF 312N/AN/AMOUNTING HOLETHTHTHTH THEMPTYTHEMPTYTHTH
THTHIOTHLFEMPTYEMPTYEMPTY
TH TH THEMPTYEMPTYEMPTYEMPTYEMPTYTHEMPTYTHTHTHTHEMPTYTHTHEMPTYEMPTYTHEMPTYTHEMPTYTHEMPTYTHEMPTYTHEMPTYEMPTYTHEMPTYEMPTYTHEMPTYTHEMPTYTHEMPTYEMPTYTHTH EMPTYIOEMPTYTHEMPTYTHEMPTYTHEMPTYEMPTYTH THEMPTYEMPTYEMPTYTHTHEMPTY EMPTYEMPTYTHEMPTYTHTHEMPTYTHTH THEMPTYTHTHEMPTY EMPTYTHEMPTYEMPTYEMPTYTHEMPTY EMPTY EMPTY
EMPTYTHTHEMPTYTH THTHEMPTYTHEMPTYTHTHEMPTYTHEMPTYEMPTYTHTHTHEMPTYEMPTYEMPTYTHEMPTYEMPTY
THEMPTYTHLFCONN1_10165288-101LF CONN1_10165288-101LF
GND5
GND6 GND2
GND3GND5
GND6 GND2
GND3GND5
GND6 GND2
GND3GND5
GND6 GND2
GND3 GND5
GND6 GND2
GND3
GND7GND8GND9GND4GND7GND8GND9GND4GND7GND8GND9GND4GND7GND8GND9GND4
GND7GND8GND9GND4
1
1
6
5 3
26
5 3
2
SCR_H1SCR_H1
1
1 1
1111
1111
6
5 3
26
5 3
2 6
5 3
2
1
1
1
1 1 1 1
11111
11 1 1 1
111
1
1 1
1 1
1
9874987498749874
9874
H90
H129
H114H113
J123J122
H128
H125 H127
H126H124H122H120
H49H47H45H44
H112H111 H115
H105
H106
H103
H89 H94 H96 H100
H101H95H93H88H86
H104H87 H92 H98 H102
H99H97H91
H77
H15 H17 H19 H21 H23 H25
H16 H18 H20
H74 H75
H31 H32
H22 H24 H26
H76
H27 H28
H36 H38
H29 H30
1
1
1
1
1 1 1 1
1
1
1 1 1
1 1
1 1
1
1
NC1NC1
1
1 1
1111
1111
1 1
1
1
1
1
1
1
1 1 1 1 1 1 1 1
1 11 11111
1 1
1
1 1 1 1 1 1
1 1 1 1 1 1
1 1
1 1
1 1
SHEETDATE
DEPARTMENT
SIZE
PROJECT DOCUMENT NUMBER REV
REVIEWER
DESIGNER
123
7 3 2 1 6 5 4
E
A
B
C
E
D
C
B
A
7 6 5 4
D
C



CPU BOLSTEREFI BIOS LABELE1.SCPU DUST COVERJUMPER
NUTFBPN+VPN
CPU BACKPLANEFri Aug 25 14:05:34 2023N/AN/AN/AN/AV05312 OF 312DGRA^000178NADGRA^000128DUMMY SYMBOL
PICKUP_SMDC20MECH
DEJP0020021NADEJP0020021NACBS_3X558-8MECHSNLABEL_15X5EMPTYEMPTYPCB_VENDOR_LOGO_15X8MECHSNLABEL_27X6PICKUP_SMDC20MECHPICKUP_SMDC20EMPTYEMPTYMECHEMPTYMECHANIC_SYMBOL
NADFHS56FR016DGRA^000180NADGRA^000180NAPICKUP_SMDC20MECHEMPTYEMPTYPICKUP_SMDC20MECHPICKUP_SMDC20EMPTYMECHPICKUP_SMDC20EMPTYPICKUP_SMDC20MECHEMPTYMECHEMPTYPICKUP_SMDC20EMPTYMECHPB-E1_SMALLMECHEMPTYEMPTYMECHMECHNA
QUANTA_LOGO_7X26WEEEMECHEMPTYEMPTYDGRA^000178MECHEMPTYMECHMECH
NANA
PICKUP_SMDC20MECHMECHAHL03003003EFI BIOS LABELDEJP0020021NADGRA^000128EMPTYMECHMECHBATTERY_SYMBOL
U2_BP
JP16_23
JP15_23
JP4003_12J90_CON
U1_DC U2_DCU1_BP
U2_BLU1_BL
1
1
1 1 111111 11
ME29
ME28ME27
ME22
ME21
ME20ME18ME17
DM9
ME10
ME9
DM13
ME14
ME12
ME11
ME13 ME15
ME3
ME2 ME4
ME_PART Symbol
ME_PART Symbol
ME_PART SymbolME_PART Symbol
ME_PART Symbol
ME_PART Symbol
ME_PART SymbolME_PART SymbolME_PART Symbol
DUMMY_SYMBOL
ME_PART Symbol
ME_PART Symbol
DUMMY_SYMBOL
ME_PART Symbol
ME_PART Symbol
ME_PART Symbol
ME_PART Symbol ME_PART Symbol
ME_PART Symbol
ME_PART Symbol
11
SHEETDATE
REVIEWER
DESIGNERDEPARTMENT
SIZE
PROJECT DOCUMENT NUMBER REV
123
7 3 2 1 6 5 4
E
A
B
C
E
D
C
B
A
7 6 5 4
D
C
QUANTA_LOGO PB-E1 BIOS-BMCLABEL BARCODE PCB_VENDOR_LOGO
BMC_FLASH BIOS_FLASH MECHANIC_SYMBOL
PCBA_LABEL
HEATSINK BATTERY_SYMBOL
QCT_LOGO
PICKUP_SYMBOLPICKUP_SYMBOL
CBS_SYMBOL TOOLING-HOLESYMBOL
WEEE